G04 ================== begin FILE IDENTIFICATION RECORD ==================*
G04 Layout Name:  9127_F0T_Expander_BD_F_v02_0110_1240.brd*
G04 Film Name:    in5*
G04 File Format:  Gerber RS274X*
G04 File Origin:  Cadence Allegro 17.2-S081*
G04 Origin Date:  Wed Jan 11 16:06:31 2023*
G04 *
G04 Layer:  PIN/SPECIAL_DRILL*
G04 Layer:  DRAWING FORMAT/TITLE_BLOCK_A*
G04 Layer:  VIA CLASS/IN5*
G04 Layer:  PIN/IN5*
G04 Layer:  MANUFACTURING/PHOTOPLOT_OUTLINE*
G04 Layer:  ETCH/IN5*
G04 Layer:  DRAWING FORMAT/TITLE_BLOCK*
G04 Layer:  DRAWING FORMAT/TITLE_DATA_IN5*
G04 *
G04 Offset:    (0.00 0.00)*
G04 Mirror:    No*
G04 Mode:      Positive*
G04 Rotation:  0*
G04 FullContactRelief:  No*
G04 UndefLineWidth:     6.00*
G04 ================== end FILE IDENTIFICATION RECORD ====================*
%FSLAX25Y25*MOIN*%
%IR0*IPPOS*OFA0.00000B0.00000*MIA0B0*SFA1.00000B1.00000*%
%ADD20O,.137X.062*%
%ADD10C,.02*%
%ADD22C,.03*%
%ADD13O,.137X.064*%
%ADD16C,.016*%
%ADD15C,.018*%
%ADD14C,.0315*%
%ADD18C,.064*%
%ADD25C,.048*%
%ADD19C,.0282*%
%ADD26C,.085*%
%ADD24C,.07051*%
%ADD21C,.0193*%
%ADD17C,.03568*%
%ADD27O,.044X.071*%
%ADD23C,.315*%
%ADD28O,.044X.087*%
%ADD11C,.256*%
%ADD12C,.394*%
%ADD29C,.01*%
%ADD30C,.006*%
%ADD31C,.0061*%
%ADD32C,.008*%
%ADD33C,.0035*%
%ADD34C,.0045*%
%ADD35C,.0055*%
%ADD36C,.0065*%
%ADD47C,.03004*%
%ADD59C,.03006*%
%ADD50C,.02404*%
%ADD61C,.07005*%
%ADD53C,.02804*%
%ADD56C,.07404*%
%ADD54C,.03282*%
%ADD55C,.03158*%
%ADD49C,.03824*%
%ADD46C,.09208*%
%ADD41C,.07606*%
%ADD52C,.02576*%
%ADD43C,.08408*%
%ADD45C,.07608*%
%ADD44C,.08409*%
%ADD37O,.1621X.2251*%
%ADD38O,.03604X.07004*%
%ADD40O,.03006X.06406*%
%ADD62C,.16206*%
%ADD57C,.41406*%
%ADD39O,.03606X.07006*%
%ADD60C,.17406*%
%ADD42C,.16506*%
%ADD48C,.16804*%
%ADD51C,.37406*%
%ADD58C,.21786*%
G75*
%LPD*%
G75*
G36*
G01X2000Y1212277D02*
X3998D01*
Y970425D01*
G03X5133Y967685I3877J1D01*
G01X15480Y957338D01*
G02X18958Y948943I-8394J-8396D01*
G01Y344836D01*
G02X15480Y336442I-11871J1D01*
G01X5132Y326094D01*
G03X3998Y323355I2742J-2739D01*
G01Y7874D01*
G03X7874Y3998I3876J0D01*
G01X23484D01*
G03X27360Y7874I0J3876D01*
G01Y46654D01*
G02X35295Y54588I7935J-1D01*
G01X64100D01*
X64454Y54234D01*
Y52945D01*
X64100Y52591D01*
X35295D01*
G03X29358Y46654I0J-5937D01*
G01Y7874D01*
G02X23484Y2000I-5874J0D01*
G01X7874D01*
G02X2000Y7874I0J5874D01*
G01Y323354D01*
G02X3720Y327506I5873J-1D01*
G01X14068Y337855D01*
G03X16961Y344836I-6980J6983D01*
G01Y948943D01*
G03X14068Y955925I-9875J-1D01*
G01X3720Y966273D01*
G02X2000Y970426I4154J4153D01*
G01Y1212277D01*
G37*
G36*
G01X1081725Y1645992D02*
X1833071D01*
G02X1838945Y1640118I0J-5874D01*
G01Y970426D01*
G02X1837225Y966273I-5874J0D01*
G01X1826876Y955925D01*
G03X1823984Y948944I6982J-6982D01*
G01Y344836D01*
G03X1826876Y337855I9873J0D01*
G01X1837225Y327506D01*
G02X1838945Y323354I-4153J-4153D01*
G01Y7874D01*
G02X1833071Y2000I-5874J0D01*
G01X1756949D01*
G02X1751075Y7874I0J5874D01*
G01Y46654D01*
G03X1749600Y50571I-5938J0D01*
G01Y50666D01*
X1749606Y50672D01*
X1751979D01*
G02X1753072Y46654I-6841J-4019D01*
G01Y7874D01*
G03X1756947Y3998I3876J0D01*
G01X1833071D01*
G03X1836948Y7874I0J3877D01*
G01Y323354D01*
G03X1835813Y326094I-3876J0D01*
G01X1825464Y336443D01*
G02X1821987Y344836I8393J8394D01*
G01X1821986D01*
Y948944D01*
X1821987D01*
G02X1825464Y957337I11871J-1D01*
G01X1835813Y967685D01*
G03X1836948Y970426I-2742J2741D01*
G01Y1640118D01*
G03X1833073Y1643994I-3876J0D01*
G01X1633526D01*
Y1644873D01*
X1578560D01*
Y1643994D01*
X1285912D01*
Y1644677D01*
X1232543D01*
Y1643994D01*
X1081724D01*
G03X1078854Y1642722I1J-3877D01*
G02X1070058Y1638822I-8797J7971D01*
G01X800966D01*
G02X792169Y1642722I0J11872D01*
G03X789299Y1643994I-2871J-2603D01*
G01X608951D01*
Y1644464D01*
X555228D01*
Y1643994D01*
X262776D01*
Y1644377D01*
X208818D01*
Y1643994D01*
X7874D01*
G03X3998Y1640118I0J-3876D01*
G01Y970425D01*
G03X5133Y967685I3877J1D01*
G01X15480Y957338D01*
G02X18958Y948943I-8394J-8396D01*
G01Y344836D01*
G02X15480Y336442I-11871J1D01*
G01X5132Y326094D01*
G03X3998Y323355I2742J-2739D01*
G01Y7874D01*
G03X7874Y3998I3876J0D01*
G01X23484D01*
G03X27360Y7874I0J3876D01*
G01Y46654D01*
G02X35295Y54588I7935J-1D01*
G01X64100D01*
X64454Y54234D01*
Y52945D01*
X64100Y52591D01*
X35295D01*
G03X29358Y46654I0J-5937D01*
G01Y7874D01*
G02X23484Y2000I-5874J0D01*
G01X7874D01*
G02X2000Y7874I0J5874D01*
G01Y323354D01*
G02X3720Y327506I5873J-1D01*
G01X14068Y337855D01*
G03X16961Y344836I-6980J6983D01*
G01Y948943D01*
G03X14068Y955925I-9875J-1D01*
G01X3720Y966273D01*
G02X2000Y970426I4154J4153D01*
G01Y1640118D01*
G02X7874Y1645992I5874J0D01*
G01X789298D01*
G02X793649Y1644063I-1J-5873D01*
G03X800966Y1640819I7317J6631D01*
G01X1070058D01*
G03X1077374Y1644063I-1J9873D01*
G02X1081725Y1645992I4352J-3945D01*
G37*
G36*
G01X1827017Y6400D02*
X1753959D01*
X1753820Y6456D01*
G03X1752778Y6876I-1042J-1083D01*
G01X1752775D01*
G03X1752273Y6789I2J-1502D01*
G01X1752206Y6777D01*
G02X1752064Y6836I0J200D01*
G01X1751135Y7765D01*
G02X1751076Y7907I141J142D01*
G01Y46654D01*
G03X1745138Y52592I-5938J0D01*
G01X1713642D01*
G03X1707704Y46654I0J-5938D01*
G01Y13217D01*
G02X1707504Y13017I-200J0D01*
G01X1648914D01*
G02X1648714Y13217I0J200D01*
G01Y46654D01*
G03X1642776Y52592I-5938J0D01*
G01X1611280D01*
G03X1605342Y46654I0J-5938D01*
G01Y7425D01*
G02X1605283Y7283I-200J0D01*
G01X1603959Y5959D01*
G02X1603817Y5900I-142J141D01*
G01X1548583D01*
G02X1548441Y5959I0J200D01*
G01X1546410Y7990D01*
G02X1546351Y8132I141J142D01*
G01Y46654D01*
G03X1540413Y52592I-5938J0D01*
G01X1508917D01*
G03X1502979Y46654I0J-5938D01*
G01Y13217D01*
G02X1502779Y13017I-200J0D01*
G01X1444189D01*
G02X1443989Y13217I0J200D01*
G01Y46654D01*
G03X1438051Y52592I-5938J0D01*
G01X1406555D01*
G03X1400617Y46654I0J-5938D01*
G01Y13217D01*
G02X1400417Y13017I-200J0D01*
G01X1294189D01*
G02X1293989Y13217I0J200D01*
G01Y46654D01*
G03X1288051Y52592I-5938J0D01*
G01X1256555D01*
G03X1250617Y46654I0J-5938D01*
G01Y13217D01*
G02X1250417Y13017I-200J0D01*
G01X1191827D01*
G02X1191627Y13217I0J200D01*
G01Y46654D01*
G03X1185689Y52592I-5938J0D01*
G01X1154193D01*
G03X1148255Y46654I0J-5938D01*
G01Y7638D01*
G02X1148196Y7496I-200J0D01*
G01X1146559Y5859D01*
G02X1146417Y5800I-142J141D01*
G01X1091383D01*
G02X1091241Y5859I0J200D01*
G01X1089324Y7776D01*
G02X1089265Y7918I141J142D01*
G01Y46654D01*
G03X1083327Y52592I-5938J0D01*
G01X1051831D01*
G03X1045893Y46654I0J-5938D01*
G01Y13217D01*
G02X1045693Y13017I-200J0D01*
G01X987103D01*
G02X986903Y13217I0J200D01*
G01Y46654D01*
G03X980965Y52592I-5938J0D01*
G01X949468D01*
G03X943530Y46654I0J-5938D01*
G01Y7913D01*
G02X943471Y7771I-200J0D01*
G01X941679Y5979D01*
G02X941538Y5921I-141J142D01*
G01X941490Y5927D01*
G03X941129Y5971I-361J-1458D01*
G03X939773Y5114I0J-1501D01*
G02X939593Y5000I-181J86D01*
G01X840295D01*
G02X840100Y5185I4J200D01*
G01Y5221D01*
G03X840108Y5372I-1494J155D01*
G01Y5374D01*
G03X838606Y6876I-1502J0D01*
G01X838604D01*
G03X838287Y6842I1J-1502D01*
G02X838104Y6896I-42J196D01*
G01X837162Y7838D01*
G02X837103Y7980I141J142D01*
G01Y13017D01*
G02X836903Y13217I0J200D01*
G01Y46654D01*
G03X830965Y52592I-5938J0D01*
G01X799468D01*
G03X793530Y46654I0J-5938D01*
G01Y13217D01*
G02X793330Y13017I-200J0D01*
G01X734740D01*
G02X734540Y13217I0J200D01*
G01Y46654D01*
G03X728602Y52592I-5938J0D01*
G01X697106D01*
G03X691168Y46654I0J-5938D01*
G01Y7751D01*
G02X691109Y7609I-200J0D01*
G01X688659Y5159D01*
G02X688517Y5100I-142J141D01*
G01X634983D01*
G02X634841Y5159I0J200D01*
G01X632237Y7763D01*
G02X632178Y7905I141J142D01*
G01Y46654D01*
G03X626240Y52592I-5938J0D01*
G01X594744D01*
G03X588806Y46654I0J-5938D01*
G01Y13217D01*
G02X588606Y13017I-200J0D01*
G01X530016D01*
G02X529816Y13217I0J200D01*
G01Y46654D01*
G03X523878Y52592I-5938J0D01*
G01X492382D01*
G03X486444Y46654I0J-5938D01*
G01Y13217D01*
G02X486244Y13017I-200J0D01*
G01X380016D01*
G02X379816Y13217I0J200D01*
G01Y46654D01*
G03X373878Y52592I-5938J0D01*
G01X342382D01*
G03X336444Y46654I0J-5938D01*
G01Y13217D01*
G02X336244Y13017I-200J0D01*
G01X331860D01*
G02X331749Y13051I0J200D01*
G01X331747D01*
X331699Y13081D01*
G03X330914Y13308I-794J-1275D01*
G01X330900D01*
G03X330069Y13055I3J-1502D01*
G01X330062Y13050D01*
X330046Y13041D01*
G02X329951Y13017I-95J176D01*
G01X323463D01*
G02X323441Y13018I-2J200D01*
G02X323304Y13096I23J199D01*
G01X323289Y13119D01*
X323231Y13222D01*
X323118Y13422D01*
X323114Y13430D01*
G02X323093Y13525I179J89D01*
G01X323094Y13552D01*
X323109Y13604D01*
X323123Y13626D01*
X323125Y13630D01*
X323131Y13639D01*
G03X323139Y13652I-1276J794D01*
G03X323140Y13655I-185J63D01*
G03X323342Y14407I-1300J752D01*
G01Y14441D01*
G03X321840Y15910I-1502J-33D01*
G03X320338Y14408I0J-1502D01*
G01Y14405D01*
G03X320556Y13624I1505J-1D01*
G01X320573Y13596D01*
X320580Y13567D01*
G02X320560Y13423I-194J-46D01*
G01X320529Y13367D01*
X320424Y13178D01*
G02X320422Y13176I-137J135D01*
G01X320397Y13132D01*
G02X320370Y13098I-169J107D01*
G01X320347Y13075D01*
G02X320297Y13039I-140J142D01*
G02X320206Y13017I-91J178D01*
G01X291598D01*
G02X291458Y13075I1J200D01*
G01X291430Y13103D01*
X291399Y13176D01*
Y13216D01*
G03X288395I-1502J-8D01*
G01Y13176D01*
X288364Y13103D01*
X288336Y13075D01*
G02X288196Y13017I-141J142D01*
G01X277654D01*
G02X277454Y13217I0J200D01*
G01Y46654D01*
G03X271516Y52592I-5938J0D01*
G01X240020D01*
G03X234082Y46654I0J-5938D01*
G01Y13217D01*
G02X233882Y13017I-200J0D01*
G01X175292D01*
G02X175092Y13217I0J200D01*
G01Y46654D01*
G03X169154Y52592I-5938J0D01*
G01X137657D01*
G03X131719Y46654I0J-5938D01*
G01Y13217D01*
G02X131519Y13017I-200J0D01*
G01X72929D01*
G02X72729Y13217I0J200D01*
G01Y46654D01*
G03X66791Y52592I-5938J0D01*
G01X35295D01*
G03X29357Y46654I0J-5938D01*
G01Y8587D01*
G02X29335Y8496I-200J0D01*
G02X29299Y8446I-178J90D01*
G01X28497Y7644D01*
G03X28438Y7502I141J-142D01*
G01Y5284D01*
G02X28416Y5193I-200J0D01*
G02X28380Y5143I-178J90D01*
G01X28379Y5142D01*
X27448Y4210D01*
X26532Y3294D01*
G02X26482Y3258I-140J142D01*
G02X26391Y3236I-91J178D01*
G01X23937D01*
G03X23795Y3177I0J-200D01*
G01X23011Y2393D01*
G02X22961Y2357I-140J142D01*
G02X22870Y2335I-91J178D01*
G01X6403D01*
G02X6312Y2357I0J200D01*
G02X6262Y2393I90J178D01*
G01X2876Y5779D01*
G02X2840Y5829I142J140D01*
G02X2818Y5920I178J91D01*
G01Y326192D01*
G02X2822Y326230I200J-2D01*
G02X2875Y326332I196J-37D01*
G01X11276Y334733D01*
G02X11339Y334775I140J-142D01*
G01X11376Y334791D01*
X11991D01*
G03X12133Y334850I0J200D01*
G01X17201Y339918D01*
G03X17260Y340060I-141J142D01*
G01Y952819D01*
G03X17201Y952961I-200J0D01*
G01X3489Y966673D01*
G02X3453Y966723I142J140D01*
G02X3431Y966814I178J91D01*
G01Y970254D01*
G03X3372Y970396I-200J0D01*
G01X2144Y971624D01*
G02X2108Y971674I142J140D01*
G02X2086Y971765I178J91D01*
G01Y1640295D01*
G02X2090Y1640333I200J-2D01*
G02X2143Y1640435I196J-37D01*
G01X7457Y1645749D01*
G02X7520Y1645791I140J-142D01*
G01X7557Y1645807D01*
X208754D01*
G02X208954Y1645607I0J-200D01*
G01Y1644577D01*
G02X208932Y1644486I-200J0D01*
G02X208896Y1644436I-178J90D01*
G01X208837Y1644377D01*
X208818D01*
Y1643068D01*
G03X208877Y1642926I200J0D01*
G01X208935Y1642868D01*
X208952D01*
Y1552480D01*
Y1552280D01*
X256951D01*
G02X257059Y1552221I-38J-197D01*
G01X259241Y1550039D01*
G02X259283Y1549976I-142J-140D01*
G01X259299Y1549939D01*
Y1544284D01*
G02X259277Y1544193I-200J0D01*
G02X259241Y1544143I-178J90D01*
G01X257789Y1542691D01*
G02X257767Y1542672I-141J141D01*
G02X257668Y1542633I-120J160D01*
G02X257561Y1542651I-22J199D01*
G01X257503Y1542679D01*
X257499Y1542681D01*
X257496Y1542682D01*
G03X257452Y1542698I-90J-179D01*
G01X257450D01*
G03X257429Y1542702I-48J-194D01*
G01X257427D01*
X257425Y1542703D01*
X257408Y1542705D01*
X257390Y1542708D01*
X257344Y1542714D01*
X257265Y1542768D01*
X257260Y1542771D01*
X257214Y1542798D01*
X257189Y1542832D01*
X257180Y1542844D01*
X257175Y1542852D01*
G03X255909Y1543545I-1266J-810D01*
G03X254417Y1542219I0J-1502D01*
G01X254410Y1542159D01*
G03X254406Y1542043I1499J-110D01*
G03X255121Y1540763I1503J0D01*
G01X255142Y1540751D01*
X255181Y1540712D01*
G02X255231Y1540629I-141J-142D01*
G02X255238Y1540596I-191J-58D01*
G01X255278Y1540292D01*
G02X255268Y1540200I-198J-25D01*
G01X255253Y1540157D01*
X255220Y1540124D01*
G03X255215Y1540119I139J-144D01*
G01X255210Y1540112D01*
X249252Y1534154D01*
G02X249202Y1534118I-140J142D01*
G02X249111Y1534096I-91J178D01*
G01X249014D01*
G02X248957Y1534104I-1J200D01*
G01X248928Y1534113D01*
X248901Y1534132D01*
G03X248044Y1534402I-859J-1232D01*
G01X248028D01*
G03X246971Y1533954I13J-1502D01*
G01X246941Y1533924D01*
X246841Y1533880D01*
G02X246820Y1533872I-82J183D01*
G02X246767Y1533863I-60J191D01*
G01X246531Y1533854D01*
X246515D01*
G02X246370Y1533912I-4J200D01*
G01X246315Y1533967D01*
G03X245369Y1534302I-946J-1168D01*
G01X245368D01*
G03X243902Y1533128I0J-1502D01*
G01X243897Y1533105D01*
X243871Y1533052D01*
G02X243822Y1532988I-180J87D01*
G01X243818Y1532984D01*
X243809Y1532977D01*
X243797Y1532969D01*
G03X243098Y1531700I802J-1269D01*
G03X243111Y1531500I1502J-3D01*
G03X244399Y1530211I1489J200D01*
G01X244402D01*
G02X244500Y1530168I-28J-198D01*
G01X244523Y1530149D01*
X244554Y1530104D01*
X244607Y1529946D01*
Y1529944D01*
X244667Y1529769D01*
G02X244678Y1529704I-189J-65D01*
G01Y1529663D01*
G02X244620Y1529522I-200J0D01*
G01X237830Y1522732D01*
G02X237689Y1522674I-141J142D01*
G01X237655D01*
G02X237602Y1522681I-1J200D01*
G01X237377Y1522746D01*
X237375D01*
X237288Y1522772D01*
G02X237157Y1522898I58J191D01*
G01X237151Y1522916D01*
X237149Y1522926D01*
G03X235687Y1524080I-1462J-349D01*
G03X234185Y1522578I0J-1502D01*
G03X235367Y1521110I1503J0D01*
G01X235400Y1521102D01*
X235438Y1521066D01*
G02X235493Y1520977I-137J-146D01*
G01X235519Y1520890D01*
Y1520888D01*
X235603Y1520595D01*
G02X235513Y1520368I-192J-55D01*
G01X235420Y1520313D01*
G03X235381Y1520283I101J-172D01*
G01X227100Y1512002D01*
G02X226959Y1511944I-141J142D01*
G01X226957D01*
G03X225455Y1510440I0J-1502D01*
G01Y1510400D01*
X225439Y1510362D01*
G02X225396Y1510298I-184J77D01*
G01X223427Y1508329D01*
G02X223281Y1508271I-141J142D01*
G01X223280D01*
G03X223242Y1508272I-59J-1501D01*
G01X223234D01*
G03X221733Y1506771I1J-1502D01*
G01Y1506769D01*
G03Y1506758I1502J-5D01*
G01Y1506737D01*
X221734Y1506695D01*
X221678Y1506558D01*
G03X221663Y1506483I185J-76D01*
G01Y1502955D01*
G02X221657Y1502905I-200J-1D01*
G01X221633Y1502823D01*
X221619Y1502800D01*
G03Y1501256I1288J-772D01*
G01X221633Y1501233D01*
X221657Y1501151D01*
G02X221663Y1501101I-194J-49D01*
G01Y1499449D01*
X221652Y1499405D01*
X221625Y1499322D01*
X221608Y1499297D01*
X221607Y1499296D01*
G03X221341Y1498442I1236J-853D01*
G03X221607Y1497588I1502J-1D01*
G01X221608Y1497587D01*
X221625Y1497562D01*
X221652Y1497479D01*
X221663Y1497435D01*
Y1493511D01*
G02X221654Y1493454I-200J2D01*
G01X221619Y1493349D01*
X221599Y1493323D01*
G03X221600Y1491492I1194J-915D01*
G01X221608Y1491482D01*
X221622Y1491462D01*
X221625Y1491453D01*
X221653Y1491368D01*
G02X221663Y1491306I-190J-62D01*
G01Y1490531D01*
G02X221655Y1490477I-200J2D01*
G01X221645Y1490446D01*
X221627Y1490417D01*
G02X221603Y1490388I-165J112D01*
G01X221518Y1490312D01*
X221514Y1490258D01*
X221391Y1490214D01*
G03X220407Y1488976I508J-1414D01*
G01X220402Y1488935D01*
G03X220396Y1488802I1497J-134D01*
G01Y1488800D01*
G03X221330Y1487409I1503J0D01*
G01X221332D01*
G03X221515Y1487346I580J1387D01*
G01X221516D01*
G02X221623Y1487273I-53J-193D01*
G01X221642Y1487248D01*
X221663Y1487187D01*
Y1484300D01*
X221654Y1484259D01*
X221643Y1484237D01*
G03X221509Y1483381I1355J-651D01*
G03X221524Y1483291I1488J202D01*
G01X221525Y1483288D01*
X221528Y1483271D01*
G03X221566Y1483124I1472J302D01*
G03X221643Y1482927I1435J447D01*
G01X221654Y1482904D01*
X221663Y1482863D01*
Y1445380D01*
G02X221641Y1445289I-200J0D01*
G02X221605Y1445239I-178J90D01*
G01X220155Y1443789D01*
G03X220096Y1443647I141J-142D01*
G01Y1442303D01*
G02X220074Y1442212I-200J0D01*
G02X220038Y1442162I-178J90D01*
G01X219825Y1441949D01*
G02X219775Y1441913I-140J142D01*
G02X219684Y1441891I-91J178D01*
G01X210729D01*
G02X210638Y1441913I0J200D01*
G02X210588Y1441949I90J178D01*
G01X202783Y1449754D01*
G02X202736Y1449828I141J142D01*
G01X196728Y1466617D01*
G02X196716Y1466685I188J68D01*
G01Y1479851D01*
G03X195566Y1482627I-3926J0D01*
G01X193995Y1484198D01*
G03X191368Y1485345I-2776J-2776D01*
G02X191204Y1485442I8J200D01*
G03X187835Y1487352I-3369J-2016D01*
G01X187832D01*
G03X186196Y1486994I2J-3926D01*
G01X186166Y1486999D01*
G03X186111Y1487020I-563J-1393D01*
G01X186100Y1487023D01*
X186094Y1487025D01*
G03X186089Y1487027I-560J-1393D01*
G03X186083Y1487029I-66J-189D01*
G03X186074Y1487032I-479J-1422D01*
G01X186073D01*
X186045Y1487040D01*
G03X185991Y1487055I-429J-1439D01*
G03X185869Y1487081I-374J-1455D01*
G03X185651Y1487101I-246J-1482D01*
G01X185610D01*
G03X184120Y1485599I12J-1502D01*
G01Y1485581D01*
G03X184122Y1485515I1502J12D01*
G03X184154Y1485280I1500J85D01*
G03X184222Y1485054I1468J318D01*
G01X184229Y1485038D01*
Y1485037D01*
X184237Y1484998D01*
G03X183908Y1483426I3598J-1573D01*
G01Y1481922D01*
G03X183979Y1481181I3927J2D01*
G01X183984Y1481149D01*
G03X183993Y1481089I3853J547D01*
G03X183998Y1481059I3841J625D01*
G03X184011Y1480987I3836J655D01*
G01X183832Y1480837D01*
G02X183638Y1480801I-129J153D01*
G03X182704Y1481002I-1287J-3710D01*
G01X182550Y1481099D01*
G03X179173Y1483022I-3377J-2004D01*
G03X177605Y1482695I1J-3927D01*
G01X177566Y1482678D01*
X177480D01*
X177449Y1482689D01*
G03X176962Y1482770I-487J-1421D01*
G01X176958D01*
G03X175458Y1481268I2J-1502D01*
G01Y1481250D01*
G03X175460Y1481184I1502J12D01*
G03X175492Y1480949I1500J85D01*
G03X175560Y1480723I1468J318D01*
G01X175567Y1480707D01*
Y1480706D01*
X175575Y1480667D01*
G03X175246Y1479095I3598J-1573D01*
G01Y1477591D01*
G03X175390Y1476539I3927J2D01*
G01X175391Y1476535D01*
G03X175246Y1475481I3782J-1057D01*
G01Y1473977D01*
G03X175573Y1472409I3927J1D01*
G01X175565Y1472367D01*
X175543Y1472305D01*
Y1472304D01*
G03X175537Y1472285I1429J-462D01*
G01X175533Y1472275D01*
G03X175458Y1471807I1427J-469D01*
G01Y1471806D01*
G03Y1471794I1502J-6D01*
G01Y1471763D01*
G03X175465Y1471655I1502J43D01*
G01X175468Y1471630D01*
G03X176760Y1470316I1493J176D01*
G01X176761D01*
X176768Y1470315D01*
G02X176906Y1470220I-34J-197D01*
G01X176990Y1470069D01*
X177066Y1469933D01*
G02X177078Y1469903I-180J-89D01*
G01X177081Y1469890D01*
G02X177082Y1469807I-195J-44D01*
G01X177073Y1469762D01*
X177068Y1469750D01*
X177065Y1469743D01*
G03X176978Y1469498I2107J-886D01*
G03X176961Y1469436I2196J-635D01*
G03X176935Y1469327I2210J-585D01*
G01Y1469325D01*
X176921Y1469265D01*
X176920Y1469257D01*
G03X176919Y1469251I197J-36D01*
G01Y1469246D01*
X176912Y1469200D01*
G03X176906Y1469158I2260J-344D01*
G01Y1469156D01*
X176904Y1469142D01*
G03X176897Y1469075I2270J-271D01*
G03X176892Y1469011I2277J-210D01*
G01X176888Y1468944D01*
X176887Y1468939D01*
Y1468859D01*
G03X178339Y1466730I2287J0D01*
G01X178448Y1466687D01*
X178466Y1466661D01*
Y1466222D01*
G02X178316Y1466154I-150J131D01*
G01X177763D01*
G03X177560Y1465951I0J-203D01*
G01Y1464838D01*
G02X177549Y1464773I-200J0D01*
G01X177532Y1464723D01*
X177522Y1464706D01*
G03Y1462776I1650J-965D01*
G01X177532Y1462759D01*
X177549Y1462709D01*
G02X177560Y1462644I-189J-65D01*
G01Y1459719D01*
G02X177549Y1459654I-200J0D01*
G01X177532Y1459604D01*
X177522Y1459587D01*
G03Y1457657I1650J-965D01*
G01X177532Y1457640D01*
X177549Y1457590D01*
G02X177560Y1457525I-189J-65D01*
G01Y1456413D01*
G03X177763Y1456210I203J0D01*
G01X178316D01*
G02X178466Y1456142I0J-199D01*
G01Y1455702D01*
X178448Y1455676D01*
X178339Y1455633D01*
G03X176894Y1453688I834J-2129D01*
G01X176891Y1453648D01*
G03X176887Y1453504I2282J-135D01*
G03X178798Y1451248I2287J0D01*
G01X178825Y1451243D01*
X178870Y1451224D01*
X178875Y1451220D01*
X178904Y1451196D01*
G02X178908Y1451192I-139J-143D01*
G01X178923Y1451179D01*
G02X178982Y1451085I-133J-149D01*
G01X179889Y1448002D01*
G03X180354Y1446984I3768J1106D01*
G01X181756Y1444805D01*
X181764Y1444776D01*
G03X181994Y1444159I3748J1046D01*
G01X182738Y1442585D01*
G03X183476Y1441524I3519J1661D01*
G01X183499Y1441501D01*
X183554Y1441395D01*
X183558Y1441358D01*
G03X183909Y1440110I3869J415D01*
G01X184653Y1438536D01*
G03X185864Y1437065I3518J1663D01*
G02X185887Y1437045I-119J-161D01*
G01X185919Y1437013D01*
G02X185936Y1436986I-160J-120D01*
G01X198431Y1410569D01*
G02X198070Y1409998I-361J-171D01*
G01X198062D01*
G03Y1406992I0J-1503D01*
G01X199996D01*
G02X200056Y1406983I1J-200D01*
G02X200175Y1406882I-60J-191D01*
G01X209623Y1386909D01*
Y1386850D01*
G03X209622Y1386795I1401J-53D01*
G01Y1386792D01*
G03X209700Y1386333I1401J2D01*
G01Y1386331D01*
X209701Y1386330D01*
G02X209710Y1386238I-189J-65D01*
G01X209703Y1386190D01*
X209554Y1385981D01*
G03X209529Y1385933I163J-116D01*
G01Y1385932D01*
X209528Y1385931D01*
G02X209456Y1385837I-188J69D01*
G02X209340Y1385800I-116J163D01*
G01X206846D01*
G03Y1382794I0J-1503D01*
G01X209304D01*
G02X209343Y1382790I-1J-200D01*
G01X209368Y1382785D01*
G02X209485Y1382712I-41J-196D01*
G02X209491Y1382704I-157J-124D01*
G01X209556Y1382611D01*
X209669Y1382449D01*
G02X209674Y1382442I-159J-119D01*
G02X209700Y1382344I-174J-99D01*
G01Y1382296D01*
X209690Y1382234D01*
X209686Y1382220D01*
X209685Y1382218D01*
G03X209622Y1381803I1339J-416D01*
G01Y1381801D01*
G03X210274Y1380616I1403J0D01*
G01X210296Y1380602D01*
X210329Y1380567D01*
X210344Y1380540D01*
Y1376191D01*
G02X210320Y1376097I-200J1D01*
G01X209951Y1375405D01*
G02X209705Y1375312I-176J94D01*
G01X209691Y1375317D01*
G03X209622Y1374882I1334J-435D01*
G01Y1374842D01*
G03X209700Y1374420I1402J41D01*
G01X209708Y1374397D01*
X209713Y1374350D01*
X209709Y1374325D01*
G02X209674Y1374237I-198J28D01*
G01X209634Y1374182D01*
X209580Y1374106D01*
Y1374104D01*
X209496Y1373988D01*
Y1373987D01*
G02X209461Y1373945I-170J106D01*
G01X209455Y1373940D01*
X209454Y1373939D01*
X209444Y1373931D01*
G02X209321Y1373888I-124J157D01*
G01X206846D01*
G03Y1370882I0J-1503D01*
G01X208978D01*
G02X209347Y1370329I0J-400D01*
G01X201784Y1352076D01*
G02X201742Y1352012I-185J76D01*
G01X201716Y1351986D01*
X201679Y1351970D01*
G03X200837Y1350683I563J-1287D01*
G03X200842Y1350562I1403J-3D01*
G01X200845Y1350544D01*
Y1350540D01*
G03X200850Y1350499I1394J149D01*
G03X200854Y1350471I1390J184D01*
G01Y1350470D01*
G02X200834Y1350350I-198J-29D01*
G01X200791Y1350266D01*
X200766Y1350234D01*
X200761Y1350230D01*
X200748Y1350220D01*
G03X200743Y1350216I811J-1019D01*
G01X200723Y1350200D01*
X200657Y1350170D01*
X200632Y1350158D01*
X200571Y1350149D01*
G02X200395Y1350218I-24J198D01*
G01X200391Y1350223D01*
G03X200378Y1350237I-153J-129D01*
G02X200376Y1350239I140J142D01*
G03X199388Y1350688I-1075J-1053D01*
G01X199266Y1350738D01*
X199178Y1350816D01*
X199114Y1350931D01*
G03X197734Y1352085I-1380J-248D01*
G01X197732D01*
G03X197537Y1352071I3J-1402D01*
G02X197481I-28J198D01*
G03X197286Y1352085I-198J-1388D01*
G01X197284D01*
G03X195901Y1350915I0J-1402D01*
G01X195896Y1350883D01*
X195882Y1350856D01*
G02X195846Y1350807I-177J93D01*
G01X195765Y1350726D01*
G02X195713Y1350688I-143J140D01*
G01X195688Y1350676D01*
X195656Y1350670D01*
X195654D01*
G03X194399Y1349187I249J-1483D01*
G01Y1349186D01*
G03X194525Y1348584I1504J1D01*
G01X194533Y1348565D01*
X194538Y1348541D01*
X194543Y1348518D01*
G02X194545Y1348447I-196J-41D01*
G01X194542Y1348428D01*
Y1348426D01*
X194539Y1348409D01*
G03X194520Y1348200I1283J-222D01*
G01Y1348175D01*
G03X195706Y1346890I1302J12D01*
G01X195721Y1346889D01*
X195756Y1346886D01*
X195798Y1346859D01*
G02X195863Y1346789I-110J-167D01*
G01X195940Y1346652D01*
X196029Y1346493D01*
G02X196047Y1346377I-180J-87D01*
G01X196041Y1346349D01*
G02X196032Y1346324I-192J55D01*
G01X196025Y1346309D01*
X196010Y1346278D01*
X195998Y1346251D01*
G03X195926Y1346042I1286J-560D01*
G01X195920Y1346018D01*
G03X195887Y1345816I1364J-327D01*
G01X195886Y1345807D01*
G02X195791Y1345662I-198J26D01*
G01X124132Y1302708D01*
G02X124128Y1302706I-91J177D01*
G01X122496Y1301767D01*
G03X122273Y1301629I1953J-3406D01*
G01X120793Y1300641D01*
G02X120682Y1300607I-112J166D01*
G01X97428D01*
G03X97286Y1300548I0J-200D01*
G01X67194Y1270456D01*
G03X67135Y1270314I141J-142D01*
G01Y1213178D01*
G02X67129Y1213130I-200J1D01*
G01X67122Y1213102D01*
X67092Y1213018D01*
X67071Y1212991D01*
G03Y1211117I1174J-937D01*
G01X67092Y1211090D01*
X67116Y1211023D01*
G02X67121Y1211006I-189J-65D01*
G01X67128Y1210979D01*
G02X67135Y1210928I-193J-52D01*
G01Y1192005D01*
G02X67120Y1191930I-200J1D01*
G03X66029Y1186654I12211J-5276D01*
G01Y1186600D01*
G03X67118Y1181382I13302J54D01*
G01X67129Y1181357D01*
X67135Y1181314D01*
Y1097544D01*
G02X66935Y1097344I-200J0D01*
G01X42573D01*
X42500Y1097314D01*
X42480Y1097294D01*
G03X42476Y1097290I139J-143D01*
G01X40906Y1095720D01*
G03X40848Y1095578I142J-141D01*
G01Y1089598D01*
G03Y1089595I200J-1D01*
G01Y1089517D01*
X40876Y1089489D01*
X40877Y1089487D01*
X40893Y1089471D01*
G03X40899Y1089465I145J139D01*
G01X43010Y1087354D01*
G02X43067Y1087241I-141J-142D01*
G01X43071Y1087211D01*
X43060Y1087147D01*
X43044Y1087118D01*
G03X42863Y1086404I1321J-715D01*
G03X44189Y1084912I1502J0D01*
G01X44243Y1084906D01*
G03X44365Y1084901I122J1498D01*
G03X45516Y1085438I0J1502D01*
G01X45521Y1085444D01*
X45551Y1085474D01*
G02X45586Y1085497I127J-155D01*
G01X45649Y1085528D01*
G02X45716Y1085553I102J-172D01*
G01X45733Y1085556D01*
X49858D01*
G02X49906Y1085550I-1J-200D01*
G01X49948Y1085537D01*
G03X50297Y1085480I415J1444D01*
G01X50303D01*
G03X50328Y1085479I73J1500D01*
G01X50345D01*
G03X50365I10J1502D01*
G01X50368D01*
G03X50814Y1085547I-1J1502D01*
G01X50843Y1085556D01*
X54358D01*
G02X54393Y1085553I0J-200D01*
G01X54447Y1085542D01*
X54463Y1085536D01*
G03X55004Y1085435I541J1401D01*
G03X55560Y1085542I-1J1502D01*
G01X55596Y1085556D01*
X60274D01*
G02X60433Y1085477I0J-200D01*
G01X60549Y1085325D01*
G02X60551Y1085323I-140J-142D01*
G01X60625Y1085224D01*
G02X60660Y1085111I-165J-113D01*
G01Y1085052D01*
X60654Y1085028D01*
G03X60607Y1084656I1455J-373D01*
G03X62109Y1083154I1502J0D01*
G03X63284Y1083721I0J1501D01*
G01X63291Y1083730D01*
X63302Y1083741D01*
G02X63582Y1083738I138J-144D01*
G01X63650Y1083670D01*
G02X63686Y1083620I-142J-140D01*
G02X63708Y1083529I-178J-91D01*
G01Y1081139D01*
G02X63686Y1081048I-200J0D01*
G01X63676Y1081027D01*
X63646Y1080992D01*
X63627Y1080978D01*
G03X63619Y1080971I123J-148D01*
G01X63602Y1080957D01*
X63489Y1080903D01*
X63271Y1080800D01*
G02X63218Y1080783I-87J180D01*
G01X63191Y1080779D01*
X63163Y1080782D01*
X63103Y1080788D01*
G03X62110Y1081162I-993J-1132D01*
G01X62109D01*
G03Y1078150I0J-1506D01*
G03X63042Y1078475I-1J1506D01*
G01X63070Y1078497D01*
X63115Y1078512D01*
G02X63171Y1078520I56J-192D01*
G01X63213D01*
G02X63293Y1078503I-1J-200D01*
G01X63412Y1078446D01*
X63594Y1078359D01*
G02X63708Y1078179I-86J-181D01*
G01Y1005259D01*
G02X63686Y1005168I-200J0D01*
G02X63650Y1005118I-178J90D01*
G01X63360Y1004828D01*
G03X63301Y1004686I141J-142D01*
G01Y939231D01*
G03X63360Y939089I200J0D01*
G01X67998Y934451D01*
G02X68041Y934387I-141J-141D01*
G01X68057Y934349D01*
Y934318D01*
X68918Y933457D01*
G03X69060Y933398I142J141D01*
G01X365714D01*
X365758Y933387D01*
X365846Y933357D01*
X365871Y933339D01*
G03X367651I890J1212D01*
G01X367676Y933357D01*
X367764Y933387D01*
X367808Y933398D01*
X379945D01*
G02X379983Y933394I-2J-200D01*
G02X380085Y933341I-37J-196D01*
G01X384078Y929348D01*
G02X384120Y929285I-142J-140D01*
G01X384136Y929248D01*
Y871729D01*
G02X384030Y871553I-200J1D01*
G01X383883Y871474D01*
X383881D01*
X383781Y871421D01*
X383780D01*
G02X383688Y871398I-93J177D01*
G01X383573D01*
G02X383521Y871405I0J200D01*
G01X383491Y871413D01*
X383467Y871428D01*
G03X382678Y871653I-791J-1277D01*
G01X382675D01*
G03X382666I-5J-1502D01*
G01X381920D01*
G03X381819Y871625I1J-200D01*
G01X381774Y871599D01*
G03X381754Y871545I176J-96D01*
G03X381753Y871540I196J-42D01*
G01X381752Y871536D01*
X381743Y871494D01*
G03X381739Y871460I196J-40D01*
G03X381740Y871438I200J-2D01*
G01X381743Y871399D01*
X381731Y871360D01*
G02X381709Y871311I-192J57D01*
G01X381695Y871290D01*
X381673Y871271D01*
G03X381173Y870152I1003J-1119D01*
G01Y870151D01*
G03X382675Y868649I1502J0D01*
G01X382677D01*
G03X383513Y868904I-1J1502D01*
G01X383515D01*
X383516Y868905D01*
G02X383615Y868938I111J-167D01*
G01X383669Y868941D01*
X383874Y868832D01*
X384022Y868753D01*
X384031Y868747D01*
G03X384072Y868726I110J165D01*
G01X384080Y868722D01*
X384108Y868675D01*
G02X384136Y868573I-172J-102D01*
G01Y862418D01*
G02X384075Y862274I-200J0D01*
G01X383953Y862167D01*
X383841Y862070D01*
G02X383710Y862021I-131J151D01*
G01X383681D01*
X383667Y862023D01*
G03X383458Y862037I-205J-1488D01*
G03X381960Y860535I4J-1502D01*
G03X383462Y859033I1502J0D01*
G03X383672Y859047I5J1502D01*
G01X383679Y859048D01*
X383708Y859050D01*
G02X383761Y859043I1J-200D01*
G01X383806Y859031D01*
X383950Y858905D01*
X383953Y858902D01*
X384061Y858809D01*
G02X384072Y858799I-129J-153D01*
G01X384079Y858792D01*
G02X384132Y858690I-143J-139D01*
G02X384136Y858652I-196J-40D01*
G01Y842194D01*
G02X384114Y842103I-200J0D01*
G02X384078Y842053I-178J90D01*
G01X379812Y837787D01*
G02X379790Y837768I-141J141D01*
G01X358951D01*
X358934Y837777D01*
G03X358208Y837964I-726J-1317D01*
G01X358207D01*
G03X356880Y837166I0J-1502D01*
G01X356875Y837156D01*
X356863Y837139D01*
G02X356698Y837051I-166J112D01*
G01X253740D01*
G02X253618Y837093I1J200D01*
G01X253593Y837112D01*
X253558Y837164D01*
X253548Y837198D01*
G03X250652Y837199I-1448J-397D01*
G01Y837197D01*
X250651Y837195D01*
G02X250581Y837092I-192J55D01*
G01X250556Y837072D01*
X250493Y837051D01*
X240065D01*
G02X240046Y837052I1J200D01*
G02X239872Y837200I19J199D01*
G01X239870Y837210D01*
G03X236930I-1470J-310D01*
G01X236928Y837200D01*
G02X236754Y837052I-193J51D01*
G02X236735Y837051I-20J199D01*
G01X199078D01*
G02X199001Y837066I-1J200D01*
G01X165186Y851073D01*
G02X165121Y851116I76J185D01*
G01X165040Y851197D01*
G03X164973Y851241I-141J-142D01*
G01X158450Y853863D01*
X158448D01*
X132900Y864446D01*
G03X132400Y864546I-501J-1207D01*
G01X126646D01*
G02X126504Y864605I0J200D01*
G01X102131Y888977D01*
G02X102134Y889050I198J28D01*
G02X102141Y889075I196J-41D01*
G01X102221Y889292D01*
Y889294D01*
X102250Y889370D01*
G02X102314Y889451I184J-79D01*
G01X102323Y889458D01*
X102395Y889513D01*
G02X102442Y889539I120J-161D01*
G01X102465Y889548D01*
X102492Y889551D01*
G03X103822Y891043I-172J1492D01*
G03X102496Y892535I-1502J0D01*
G01X102442Y892541D01*
G03X100909Y891562I-122J-1498D01*
G01X100907Y891556D01*
X100905Y891551D01*
X100891Y891523D01*
G02X100856Y891475I-177J92D01*
G01X100834Y891453D01*
G02X100753Y891406I-138J145D01*
G01X100578Y891365D01*
X100576D01*
X100419Y891330D01*
G02X100241Y891385I-37J197D01*
G01X97214Y894412D01*
G02X97196Y894433I142J140D01*
G01Y895213D01*
G03X97160Y895514I-1307J-4D01*
G01X97155Y895537D01*
Y895655D01*
G03X97097Y895796I-200J0D01*
G01X97012Y895881D01*
X97000Y895901D01*
G03X96813Y896137I-1111J-688D01*
G01X74329Y918621D01*
G03X74093Y918808I-924J-924D01*
G01X74073Y918820D01*
X73988Y918905D01*
G03X73847Y918963I-141J-142D01*
G01X73729D01*
X73706Y918968D01*
G03X73405Y919004I-305J-1271D01*
G01X55268D01*
G03X54967Y918968I4J-1307D01*
G01X54944Y918963D01*
X54826D01*
G03X54685Y918905I0J-200D01*
G01X54600Y918820D01*
X54580Y918808D01*
G03X54344Y918621I688J-1111D01*
G01X53519Y917795D01*
G02X53377Y917736I-142J141D01*
G01X49173D01*
X49156Y917745D01*
G03X48430Y917932I-726J-1317D01*
G01X48429D01*
G03Y914928I0J-1502D01*
G01X48432D01*
G03X49165Y915119I0J1503D01*
G01X49173Y915124D01*
X54002D01*
G03X54302Y915159I0J1306D01*
G01X54325Y915164D01*
X54442D01*
G03X54584Y915223I0J200D01*
G01X54666Y915305D01*
X54686Y915318D01*
G03X54925Y915506I-683J1114D01*
G01X55750Y916331D01*
G02X55892Y916390I142J-141D01*
G01X72781D01*
G02X72923Y916331I0J-200D01*
G01X80785Y908470D01*
G02X80828Y908251I-141J-141D01*
G01X80785Y908147D01*
G02X80700Y908128I-85J181D01*
G01X73757D01*
G03X73557Y907928I0J-200D01*
G01Y902953D01*
G02X73534Y902859I-200J-1D01*
G01X73523Y902838D01*
X73490Y902802D01*
X73417Y902752D01*
X73393Y902744D01*
G03X73366Y902734I440J-1230D01*
G01X73364Y902733D01*
X73343Y902726D01*
G03X73282Y902701I450J-1184D01*
G01X73280D01*
G03X72880Y902431I496J-1166D01*
G01X72860Y902411D01*
G03X72836Y902388I892J-955D01*
G01X71184Y900736D01*
G03X71161Y900712I932J-916D01*
G01X71139Y900690D01*
G03X70768Y899797I896J-896D01*
G01Y899787D01*
G03X70766Y899729I1304J-74D01*
G01Y899373D01*
G03X70768Y899320I1306J23D01*
G01Y899226D01*
G02X70766Y899200I-200J2D01*
G01X70758Y899139D01*
X70738Y899105D01*
G03X70550Y898572I1297J-757D01*
G03X70533Y898375I1485J-227D01*
G01Y898321D01*
G03X71859Y896854I1502J25D01*
G01X71944Y896844D01*
G03X71964Y896843I20J199D01*
G01X72036D01*
G03X72907Y897121I0J1503D01*
G01X72915Y897127D01*
X72938Y897142D01*
G02X73123Y897153I103J-171D01*
G01X73264Y897081D01*
X73266D01*
X73337Y897045D01*
X73352Y897039D01*
G03X73365Y897035I65J189D01*
G01X73366D01*
X73395Y897028D01*
G02X73469Y896991I-51J-194D01*
G01X73503Y896964D01*
X73523Y896925D01*
X73538Y896896D01*
G02X73556Y896826I-181J-84D01*
G02X73557Y896811I-199J-21D01*
G01Y890628D01*
G02X73524Y890518I-200J0D01*
G01X73508Y890494D01*
X73464Y890457D01*
X73436Y890445D01*
G03Y887685I591J-1380D01*
G01X73437D01*
G02X73525Y887611I-79J-184D01*
G01X73541Y887587D01*
X73557Y887532D01*
Y849660D01*
G03X73616Y849518I200J0D01*
G01X79259Y843875D01*
G03X79401Y843816I142J141D01*
G01X115912D01*
G02X115989Y843801I1J-200D01*
G01X164392Y823751D01*
G02X164457Y823708I-76J-185D01*
G01X202678Y785487D01*
G03X202820Y785428I142J141D01*
G01X346131D01*
G02X346169Y785424I-2J-200D01*
G02X346271Y785371I-37J-196D01*
G01X358844Y772798D01*
G02X358886Y772735I-142J-140D01*
G01X358902Y772698D01*
Y730602D01*
G02X358702Y730402I-200J0D01*
G01X150620D01*
G02X150478Y730461I0J200D01*
G01X121699Y759240D01*
X121690Y759270D01*
G03X120250Y760343I-1440J-430D01*
G03X118748Y758841I0J-1502D01*
G01Y758838D01*
G03X118949Y758089I1502J2D01*
G01X118957Y758074D01*
X118965Y758046D01*
X118977Y758003D01*
G02X118984Y757951I-193J-52D01*
G01Y756724D01*
G02X118983Y756702I-200J-2D01*
G02X118831Y756530I-199J23D01*
G01X118821Y756528D01*
G03X117597Y755052I278J-1476D01*
G03X117610Y754852I1502J-3D01*
G03X118101Y753929I1489J200D01*
G03X118376Y753735I998J1123D01*
G03X118653Y753617I724J1316D01*
G01X118676Y753610D01*
X118719Y753585D01*
X143990Y728314D01*
G02X144046Y728203I-142J-141D01*
G02X143652Y727742I-395J-61D01*
G01X128365D01*
G03X127510Y727410I0J-1268D01*
G02X127480Y727387I-136J147D01*
G03X127242Y727199I685J-1112D01*
G01X111594Y711551D01*
X111568Y711543D01*
G03X110491Y710102I426J-1441D01*
G03X111993Y708600I1502J0D01*
G03X113434Y709677I0J1503D01*
G01X113442Y709703D01*
X128648Y724909D01*
G02X128790Y724968I142J-141D01*
G01X358702D01*
G02X358902Y724768I0J-200D01*
G01Y493478D01*
G02X358833Y493334I-200J7D01*
G01X358806Y493312D01*
X358772Y493285D01*
X358742Y493273D01*
G03X357776Y491870I536J-1403D01*
G03X358768Y490456I1504J0D01*
G01X358795Y490446D01*
X358814Y490432D01*
G02X358859Y490389I-114J-164D01*
G01X358866Y490379D01*
G02X358902Y490265I-164J-114D01*
G01Y478792D01*
G02X358834Y478646I-200J4D01*
G02X358811Y478629I-130J152D01*
G01X358676Y478540D01*
X358674D01*
X358535Y478450D01*
G02X358444Y478418I-110J167D01*
G02X358383Y478422I-18J199D01*
G01X358344Y478430D01*
X358325Y478438D01*
G03X357760Y478555I-581J-1385D01*
G01X357730D01*
G03X356250Y477229I12J-1502D01*
G01X356248Y477211D01*
G03X356240Y477053I1494J-155D01*
G03X357723Y475551I1502J0D01*
G01X357743D01*
G03X358289Y475654I-1J1502D01*
G01X358302Y475659D01*
X358344Y475676D01*
X358390Y475686D01*
G02X358532Y475659I36J-197D01*
G01X358558Y475642D01*
X358812Y475475D01*
G02X358902Y475308I-110J-167D01*
G01Y463842D01*
G02X358846Y463703I-200J0D01*
G01X358787Y463643D01*
X358762Y463617D01*
X358696Y463586D01*
X358637Y463558D01*
X358602Y463554D01*
G03X357896Y463293I151J-1494D01*
G03X357415Y462741I858J-1233D01*
G03Y461379I1339J-681D01*
G03X358602Y460566I1338J681D01*
G01X358637Y460562D01*
X358730Y460517D01*
G02X358786Y460477I-87J-180D01*
G01X358845Y460416D01*
G02X358902Y460276I-143J-140D01*
G01Y451873D01*
G02X358846Y451734I-200J0D01*
G01X358787Y451674D01*
X358762Y451648D01*
X358696Y451617D01*
X358637Y451589D01*
X358602Y451585D01*
G03X357262Y450267I152J-1494D01*
G01X357256Y450213D01*
G03X357251Y450092I1498J-122D01*
G01Y450011D01*
X357254Y449978D01*
Y449976D01*
G03X357549Y449192I1498J116D01*
G03X358084Y448746I1203J899D01*
G01X358117Y448730D01*
G02X358214Y448580I-102J-172D01*
G01Y448579D01*
X358253Y448335D01*
Y448333D01*
X358264Y448262D01*
G02X358255Y448168I-198J-28D01*
G01X358248Y448146D01*
X358223Y448106D01*
X358204Y448088D01*
G03X358150Y448034I1035J-1089D01*
G01X358142Y448026D01*
G03X358131Y448014I1101J-1020D01*
G01X358125Y448007D01*
X358119Y448001D01*
G03X358083Y447959I1123J-999D01*
G01X358057Y447927D01*
X358006Y447900D01*
X357996Y447895D01*
G02X357993Y447894I-64J188D01*
G01X357952Y447874D01*
X357950D01*
X357934Y447866D01*
G02X357851Y447847I-85J181D01*
G01X357628D01*
G02X357539Y447868I0J200D01*
G01X357468Y447904D01*
G02X357424Y447934I89J179D01*
G01X357399Y447959D01*
X357396Y447964D01*
X357389Y447972D01*
G03X356242Y448504I-1147J-971D01*
G01X356241D01*
X356208Y448503D01*
X356207D01*
G03X355691Y448399I34J-1502D01*
G01X355690D01*
G02X355587Y448387I-74J186D01*
G01X355536Y448395D01*
X355324Y448564D01*
X355321Y448567D01*
X355225Y448642D01*
G02X355149Y448798I124J157D01*
G01Y448821D01*
X355151Y448834D01*
G03X355165Y449034I-1488J205D01*
G01Y449049D01*
G03X353663Y450547I-1502J-4D01*
G03X352161Y449045I0J-1502D01*
G03X353652Y447543I1502J0D01*
G01X353665D01*
G03X354213Y447647I-1J1502D01*
G01X354214D01*
G02X354317Y447659I74J-186D01*
G01X354368Y447651D01*
X354688Y447396D01*
G02X354755Y447259I-133J-150D01*
G01Y447225D01*
X354753Y447212D01*
G03X354739Y447012I1488J-205D01*
G01Y446997D01*
G03X356065Y445509I1502J4D01*
G01X356122Y445503D01*
G03X356241Y445498I123J1498D01*
G01X356242D01*
G03X357394Y446036I0J1503D01*
G01X357408Y446055D01*
X357426Y446071D01*
G02X357467Y446098I130J-152D01*
G01X357539Y446134D01*
G02X357628Y446155I89J-179D01*
G01X357853D01*
G02X357929Y446140I0J-200D01*
G01X357941Y446135D01*
X358007Y446103D01*
X358036Y446088D01*
X358068Y446062D01*
X358082Y446045D01*
G03X358763Y445576I1160J955D01*
G01X358764D01*
X358774Y445572D01*
G02X358864Y445501I-74J-186D01*
G01X358866Y445498D01*
G02X358898Y445424I-164J-115D01*
G02X358902Y445384I-196J-40D01*
G01Y437362D01*
G02X358867Y437249I-200J0D01*
G01X358852Y437227D01*
X358798Y437185D01*
X358687Y437098D01*
X358578Y437013D01*
G02X358461Y436975I-117J162D01*
G01X358408D01*
X358385Y436980D01*
G03X358042Y437020I-344J-1462D01*
G03X356540Y435518I0J-1502D01*
G03X356995Y434441I1502J0D01*
G02X356997Y434439I-140J-142D01*
G01X357026Y434410D01*
X357063Y434328D01*
Y434326D01*
X357085Y434276D01*
X357090Y434235D01*
Y434029D01*
G02X357084Y433982I-200J2D01*
G01X357077Y433952D01*
X357073Y433930D01*
X357052Y433883D01*
X357006Y433819D01*
G03X356530Y432718I1036J-1101D01*
G03X358042Y431206I1512J0D01*
G03X358426Y431256I-2J1512D01*
G01X358477Y431262D01*
G02X358508Y431260I3J-200D01*
G01X358534Y431256D01*
X358753Y431086D01*
X358754Y431085D01*
X358824Y431030D01*
G02X358900Y430901I-122J-159D01*
G01X358902Y430886D01*
Y428446D01*
G02X358879Y428354I-200J1D01*
G01X358825Y428260D01*
G02X358757Y428191I-172J102D01*
G01X358523Y428045D01*
G02X358371Y428020I-106J170D01*
G01X358347Y428026D01*
X358326Y428036D01*
X358325Y428037D01*
G03X357658Y428194I-669J-1348D01*
G01X357655D01*
G03X356150Y426689I0J-1505D01*
G03X356532Y425689I1506J2D01*
G01X356546Y425672D01*
X356547Y425671D01*
X356554Y425663D01*
X356583Y425634D01*
X356598Y425596D01*
G02X356613Y425521I-185J-76D01*
G01Y425310D01*
G02X356598Y425235I-200J1D01*
G01X356584Y425200D01*
X356556Y425171D01*
G03Y423007I1099J-1082D01*
G01X356584Y422978D01*
X356598Y422943D01*
G02X356613Y422868I-185J-76D01*
G01Y422710D01*
G02X356598Y422635I-200J1D01*
G01X356584Y422600D01*
X356556Y422571D01*
G03Y420407I1099J-1082D01*
G01X356584Y420378D01*
X356598Y420343D01*
G02X356613Y420268I-185J-76D01*
G01Y420110D01*
G02X356598Y420035I-200J1D01*
G01X356584Y420000D01*
X356556Y419971D01*
G03Y417807I1099J-1082D01*
G01X356584Y417778D01*
X356598Y417743D01*
G02X356613Y417668I-185J-76D01*
G01Y417510D01*
G02X356598Y417435I-200J1D01*
G01X356584Y417400D01*
X356556Y417371D01*
G03Y415207I1099J-1082D01*
G01X356584Y415178D01*
X356598Y415143D01*
G02X356613Y415068I-185J-76D01*
G01Y414910D01*
G02X356598Y414835I-200J1D01*
G01X356584Y414800D01*
X356556Y414771D01*
G03Y412607I1099J-1082D01*
G01X356584Y412578D01*
X356598Y412543D01*
G02X356613Y412468I-185J-76D01*
G01Y412310D01*
G02X356598Y412235I-200J1D01*
G01X356584Y412200D01*
X356556Y412171D01*
G03Y410007I1099J-1082D01*
G01X356584Y409978D01*
X356598Y409943D01*
G02X356613Y409868I-185J-76D01*
G01Y409710D01*
G02X356598Y409635I-200J1D01*
G01X356584Y409600D01*
X356556Y409571D01*
G03Y407407I1099J-1082D01*
G01X356584Y407378D01*
X356598Y407343D01*
G02X356613Y407268I-185J-76D01*
G01Y407111D01*
G02X356599Y407036I-200J-1D01*
G01X356584Y407000D01*
X356556Y406972D01*
G03X356112Y405889I1099J-1083D01*
G03X356848Y404574I1543J0D01*
G02X356939Y404448I-104J-171D01*
G01X356957Y404369D01*
X356989Y404230D01*
G02X356992Y404154I-195J-46D01*
G01X356986Y404115D01*
X356965Y404081D01*
G03X356746Y403300I1283J-781D01*
G03X358248Y401798I1502J0D01*
G01X358250D01*
G03X358446Y401811I-1J1502D01*
G01X358450D01*
G02X358580Y401781I23J-199D01*
G01X358607Y401764D01*
X358769Y401622D01*
X358809Y401587D01*
X358812Y401584D01*
X358835Y401564D01*
G02X358901Y401434I-133J-149D01*
G02X358902Y401415I-199J-20D01*
G01Y386633D01*
G02X358873Y386529I-200J0D01*
G01X358859Y386506D01*
X358819Y386469D01*
X358794Y386456D01*
G03Y383790I692J-1333D01*
G02X358902Y383613I-92J-178D01*
G01Y379075D01*
G02X358880Y378984I-200J0D01*
G02X358844Y378934I-178J90D01*
G01X358742Y378832D01*
X358723Y378814D01*
X358641Y378733D01*
G02X358500Y378675I-141J142D01*
G01X358491D01*
G03Y375671I0J-1502D01*
G01X358500D01*
G02X358635Y375619I0J-200D01*
G01X358738Y375517D01*
X358833Y375423D01*
G02X358902Y375258I-131J-152D01*
G01Y312144D01*
G02X358880Y312053I-200J0D01*
G02X358844Y312003I-178J90D01*
G01X356326Y309485D01*
G02X356184Y309426I-142J141D01*
G01X356000D01*
G03X354355Y308745I0J-2327D01*
G01X348695Y303085D01*
G02X348553Y303026I-142J141D01*
G01X328857D01*
G02X328697Y303106I0J200D01*
G01X328476Y303401D01*
X328460Y303493D01*
X328466Y303514D01*
G03X328534Y303960I-1436J447D01*
G01Y303962D01*
G03X325530I-1502J0D01*
G01Y303901D01*
G03X325589Y303539I1502J59D01*
G01X325603Y303494D01*
X325586Y303401D01*
X325366Y303106D01*
G02X325206Y303026I-160J120D01*
G01X161730D01*
G03X160649Y302759I1J-2325D01*
G02X160637Y302753I-95J176D01*
G03X159953Y302282I936J-2092D01*
G01X147918Y290247D01*
G03X147590Y289833I1620J-1621D01*
G01X147577Y289814D01*
G03X147074Y288370I1823J-1445D01*
G01Y233542D01*
X147011Y232497D01*
X146989Y232138D01*
Y232130D01*
X143494Y196641D01*
G02X143487Y196604I-199J19D01*
G01X143108Y195329D01*
G03X143014Y194676I2197J-650D01*
G01Y191781D01*
G02X143013Y191761I-200J0D01*
G01X142063Y182117D01*
G02X142005Y181995I-199J20D01*
G01X100955Y140945D01*
G03X100319Y139759I1645J-1646D01*
G01X100314Y139741D01*
G03X100220Y139092I2197J-650D01*
G01Y127611D01*
G02X100198Y127520I-200J0D01*
G02X100162Y127470I-178J90D01*
G01X98420Y125728D01*
G02X98373Y125693I-142J141D01*
G01X98349Y125680D01*
X98320Y125674D01*
G03X97179Y125053I480J-2241D01*
G01X95948Y123822D01*
G03X95581Y123344I1618J-1622D01*
G01X95499Y123266D01*
G03X94911Y122838I1058J-2072D01*
G01X93531Y121458D01*
G03X93273Y121151I1645J-1645D01*
G01X93263Y121137D01*
X92921Y120795D01*
G03X92434Y120076I1619J-1621D01*
G01X92322Y119968D01*
G03X91516Y119443I839J-2170D01*
G01X90136Y118063D01*
G03X89876Y117753I1646J-1644D01*
G02X89857Y117730I-164J116D01*
G03X89461Y117165I1657J-1583D01*
G03X89314Y116790I2052J-1021D01*
G01X89173Y116653D01*
G03X88121Y116048I594J-2250D01*
G01X86846Y114774D01*
X86827Y114762D01*
G03X86429Y114443I1225J-1937D01*
G01X85198Y113212D01*
G03X84865Y112792I1617J-1624D01*
G01X84828Y112748D01*
G03X84727Y112653I1543J-1741D01*
G01X83347Y111273D01*
G03X82707Y110065I1645J-1645D01*
G01Y110064D01*
G02X82652Y109961I-196J39D01*
G01X82576Y109885D01*
G02X82434Y109826I-142J141D01*
G01X77824D01*
G02X77650Y109927I0J200D01*
G01X77609Y110000D01*
Y110002D01*
X77554Y110097D01*
G02X77531Y110190I177J93D01*
G01Y110249D01*
X77559Y110309D01*
X77562Y110314D01*
X77564Y110317D01*
G03X77773Y110871I-1559J905D01*
G03X77808Y111223I-1767J353D01*
G01Y114623D01*
G03X74202I-1803J0D01*
G01Y111223D01*
G03X74455Y110302I1803J0D01*
G01Y110301D01*
G02X74484Y110201I-171J-104D01*
G01Y110148D01*
X74378Y109961D01*
X74359Y109927D01*
G02X74185Y109826I-174J99D01*
G01X72400D01*
G03X70755Y109145I0J-2327D01*
G01X70495Y108885D01*
G02X70353Y108826I-142J141D01*
G01X69052D01*
G02X68910Y108885I0J200D01*
G01X68501Y109294D01*
G03X66856Y109976I-1646J-1645D01*
G03X64530Y107649I0J-2326D01*
G03X65012Y106230I2326J-1D01*
G01X65032Y106204D01*
X65054Y106142D01*
Y105756D01*
X65031Y105692D01*
X65012Y105668D01*
G03X64530Y104251I1844J-1418D01*
G01Y104249D01*
G03X66856Y101922I2327J0D01*
G03X68501Y102604I-1J2327D01*
G01X68902Y103005D01*
G02X69044Y103064I142J-141D01*
G01X71862D01*
G03X73320Y103578I-1J2326D01*
G01X73324Y103582D01*
G03X73562Y103789I-1381J1828D01*
G01X73688Y103914D01*
X73751Y103977D01*
G02X73853Y104030I139J-143D01*
G02X73891Y104034I40J-196D01*
G01X74764D01*
G02X74899Y103981I-1J-200D01*
G01X75035Y103855D01*
X75037Y103853D01*
X75100Y103795D01*
G02X75143Y103737I-136J-146D01*
G01X75159Y103705D01*
X75163Y103665D01*
G03X76660Y102281I1497J118D01*
G03X77658Y102661I0J1501D01*
G03X78061Y103240I-997J1124D01*
G03X78157Y103655I-1401J543D01*
G01X78158Y103669D01*
G02X78223Y103798I199J-19D01*
G01X78283Y103853D01*
X78285Y103855D01*
X78421Y103981D01*
G02X78556Y104034I136J-147D01*
G01X83787D01*
G03X84246Y104081I-3J2292D01*
G02X84260Y104083I35J-197D01*
G03X85605Y104745I-300J2307D01*
G01X105355Y124495D01*
G03X106036Y126140I-1646J1645D01*
G01Y137763D01*
G02X106095Y137905I200J0D01*
G01X148005Y179815D01*
G03X148676Y181435I-1620J1620D01*
G01Y190450D01*
G02X148677Y190470I200J0D01*
G01X149222Y196007D01*
G02X149229Y196044I199J-19D01*
G01X150271Y199548D01*
X150745Y201143D01*
G03X150835Y201659I-2198J649D01*
G01X152481Y229094D01*
Y229102D01*
X152825Y232593D01*
G03X152836Y232817I-2315J226D01*
G01Y235026D01*
X152916Y236354D01*
G03X152920Y236496I-2287J135D01*
G01X152910Y241937D01*
Y286937D01*
G02X152969Y287079I200J0D01*
G01X163095Y297205D01*
G02X163237Y297264I142J-141D01*
G01X241273D01*
G02X241348Y297249I-1J-200D01*
G01X241359Y297245D01*
X241388Y297233D01*
X241414Y297209D01*
X241416Y297207D01*
G03X241528Y297108I1573J1666D01*
G03X242986Y296584I1458J1768D01*
G01X256911D01*
G02X257096Y296460I0J-200D01*
G01X257120Y296404D01*
X257096Y296286D01*
X248955Y288145D01*
G03X248274Y286500I1646J-1645D01*
G01Y223683D01*
X246323Y183987D01*
G02X246264Y183855I-200J10D01*
G01X210713Y148303D01*
X210659Y148274D01*
X210629Y148269D01*
G03X209398Y147625I414J-2289D01*
G01X208018Y146245D01*
G03X207374Y145015I1645J-1645D01*
G01X207319Y144909D01*
X207294Y144884D01*
G03X206003Y144230I354J-2299D01*
G01X204623Y142850D01*
G03X203979Y141620I1645J-1645D01*
G01X203924Y141514D01*
X203899Y141489D01*
G03X202608Y140835I354J-2299D01*
G01X201228Y139455D01*
G03X200584Y138225I1645J-1645D01*
G01X200529Y138119D01*
X200504Y138094D01*
G03X199213Y137440I354J-2299D01*
G01X197833Y136060D01*
G03X197189Y134829I1645J-1645D01*
G01X197184Y134799D01*
X197155Y134745D01*
X196455Y134045D01*
G03X195855Y133010I1645J-1645D01*
G01X195848Y132984D01*
X195823Y132941D01*
X195740Y132858D01*
G03X195091Y131565I1620J-1623D01*
G01X195088Y131543D01*
X195057Y131463D01*
X195040Y131440D01*
X195039Y131439D01*
G03X194570Y130049I1825J-1390D01*
G01Y128308D01*
G03X194946Y127050I2292J0D01*
G01X194947Y127049D01*
G02X194979Y126951I-168J-109D01*
G01X194982Y126899D01*
X194948Y126832D01*
X194942Y126822D01*
X194940Y126819D01*
G03X194826Y126623I1921J-1249D01*
G03X194764Y126493I2036J-1051D01*
G03X194570Y125571I2097J-923D01*
G01Y123830D01*
G03X194945Y122574I2291J0D01*
G01X194946Y122573D01*
X194962Y122548D01*
X194971Y122519D01*
G02X194958Y122373I-192J-56D01*
G01X194948Y122354D01*
X194942Y122344D01*
X194940Y122341D01*
G03X194826Y122145I1921J-1249D01*
G03X194764Y122015I2036J-1051D01*
G03X194570Y121093I2097J-923D01*
G01Y119413D01*
G03X194723Y118529I2291J-59D01*
G01X194724Y118527D01*
X194727Y118519D01*
G03X194731Y118510I2094J925D01*
G01Y118508D01*
G03X194741Y118485I2107J902D01*
G01X194756Y118448D01*
Y118329D01*
G02X194735Y118240I-200J0D01*
G01X194717Y118203D01*
X194716Y118202D01*
X194680Y118120D01*
X194678Y118114D01*
X194666Y118088D01*
X194669Y118077D01*
X194632Y118009D01*
G02X194520Y117915I-176J96D01*
G01X194511Y117912D01*
G03X193894Y117569I792J-2151D01*
G03X193731Y117430I1404J-1811D01*
G03X193711Y117411I1568J-1671D01*
G01X192450Y116149D01*
G03X192092Y115687I1618J-1623D01*
G03X191874Y115187I1977J-1159D01*
G03X191837Y115049I2194J-662D01*
G01X191830Y115020D01*
X190240Y113430D01*
G02X190137Y113375I-142J141D01*
G01X189285Y113206D01*
G02X189246Y113202I-40J196D01*
G01X184772D01*
G03X183152Y112530I1J-2292D01*
G01X182168Y111546D01*
G02X182026Y111487I-142J141D01*
G01X181890Y111541D01*
G03X180863Y111947I-1027J-1096D01*
G01X180861D01*
G03X180428Y111883I1J-1502D01*
G01X180370Y111874D01*
G02X180170Y112074I0J200D01*
G01Y114623D01*
G03X176564I-1803J0D01*
G01Y111220D01*
G03X176638Y110709I1803J0D01*
G01X176642Y110696D01*
X176646Y110673D01*
G02X176604Y110516I-197J-31D01*
G01Y110515D01*
G02X176448Y110440I-156J125D01*
G01X176392D01*
G03X174772Y109769I0J-2291D01*
G01X174239Y109236D01*
G02X174137Y109181I-142J141D01*
G01X172372Y108830D01*
G02X172333Y108826I-40J196D01*
G01X171414D01*
G02X171272Y108885I0J200D01*
G01X170863Y109294D01*
G03X169218Y109976I-1646J-1645D01*
G03X166892Y107649I0J-2326D01*
G03X167374Y106230I2326J-1D01*
G01X167394Y106204D01*
X167416Y106142D01*
Y105756D01*
X167393Y105692D01*
X167374Y105668D01*
G03X166892Y104251I1844J-1418D01*
G01Y104249D01*
G03X169218Y101922I2327J0D01*
G03X170863Y102604I-1J2327D01*
G01X171264Y103005D01*
G02X171406Y103064I142J-141D01*
G01X172692D01*
G03X173146Y103108I4J2326D01*
G01X173195Y103118D01*
X175180D01*
G03X176798Y103787I0J2291D01*
G01X176800Y103789D01*
X176821Y103809D01*
X176830Y103818D01*
X176860Y103847D01*
X177006Y103876D01*
G02X177110Y103869I39J-196D01*
G01X177277Y103811D01*
X177397Y103770D01*
G02X177457Y103737I-65J-189D01*
G01X177489Y103705D01*
G02X177518Y103653I-158J-122D01*
G01X177530Y103607D01*
X177531Y103598D01*
G03X179022Y102281I1491J185D01*
G03X180524Y103779I0J1502D01*
G01Y103786D01*
G03X180450Y104249I-1502J-3D01*
G01X180442Y104274D01*
X180440Y104300D01*
G02X180447Y104370I199J15D01*
G01X180456Y104404D01*
X180478Y104434D01*
X180544Y104525D01*
G02X180661Y104603I162J-117D01*
G01X180662D01*
G03X181039Y104723I-515J2269D01*
G01X181135Y104763D01*
G02X181212Y104778I76J-185D01*
G01X182460D01*
G03X184080Y105449I0J2291D01*
G01X184203Y105571D01*
X184263Y105631D01*
G02X184545I141J-142D01*
G01X184571Y105605D01*
X184587Y105571D01*
G03X185957Y104684I1370J615D01*
G03X187459Y106154I0J1502D01*
G01Y106181D01*
G03X187418Y106535I-1502J5D01*
G02X187444Y106690I194J47D01*
G01X187599Y106932D01*
G02X187729Y107021I169J-107D01*
G01X190313Y107534D01*
G02X190352Y107538I40J-196D01*
G01X191606D01*
G03X193226Y108210I-1J2292D01*
G01X195978Y110962D01*
G02X196041Y111004I140J-142D01*
G01X196078Y111020D01*
X196241D01*
X196281Y111003D01*
X196372Y110968D01*
X196395Y110949D01*
X196399Y110945D01*
G03X197011Y110627I980J1138D01*
G03X197379Y110581I369J1456D01*
G01X197380D01*
G03X198882Y112083I0J1502D01*
G03X198443Y113144I-1502J0D01*
G01X198442Y113145D01*
Y113344D01*
G02X198501Y113486I200J0D01*
G01X200061Y115046D01*
G03X200325Y115362I-1619J1621D01*
G01X200331Y115370D01*
X200855Y115895D01*
G03X201536Y117540I-1646J1645D01*
G01Y130561D01*
G02X201595Y130703I200J0D01*
G01X251346Y180454D01*
G03X252013Y181937I-1620J1620D01*
G01X255261Y236060D01*
X255262Y236062D01*
Y236074D01*
X255263Y236084D01*
Y236096D01*
X255264Y236108D01*
Y236120D01*
G03X255265Y236141I-2288J119D01*
G01Y236156D01*
G03X255266Y236199I-2290J75D01*
G01Y236205D01*
G03X255172Y236850I-2292J-5D01*
G01X254737Y238320D01*
X254606Y238764D01*
X254360Y239596D01*
X254277Y239877D01*
X254114Y240428D01*
X254102Y240467D01*
Y284902D01*
G02X254106Y284940I200J-2D01*
G02X254159Y285042I196J-37D01*
G01X254246Y285129D01*
X261750Y292632D01*
G02X261948Y292683I142J-141D01*
G01X262023Y292657D01*
X262051Y292634D01*
G03X263003Y292294I952J1163D01*
G03X263018I7J1502D01*
G01X263048D01*
G03X263139Y292299I-37J1502D01*
G01X263152Y292301D01*
X263160Y292302D01*
G03X263186Y292305I-159J1494D01*
G03X263384Y292343I-183J1491D01*
G01X263386D01*
G03X263419Y292353I-419J1442D01*
G01X263421D01*
G03X263862Y292562I-414J1444D01*
G01X263938Y292615D01*
X263936Y292617D01*
G03X263993Y292664I-927J1182D01*
G01X264009Y292678D01*
G02X264119Y292713I113J-165D01*
G01X264385D01*
G02X264404Y292712I-1J-200D01*
G02X264511Y292668I-19J-199D01*
G01X264515Y292664D01*
G03X264950Y292399I988J1132D01*
G03X265362Y292300I554J1397D01*
G01X265400Y292297D01*
G03X265502Y292293I110J1499D01*
G01X265504D01*
G03X266958Y293419I-1J1503D01*
G01X266965Y293447D01*
X266981Y293473D01*
G02X267025Y293524I171J-103D01*
G01X267032Y293530D01*
X267112Y293595D01*
G02X267238Y293640I126J-155D01*
G01X294924D01*
G02X295122Y293467I0J-200D01*
G01Y293462D01*
X295129Y293420D01*
G03X295824Y292367I1485J224D01*
G03X296595Y292143I789J1278D01*
G01X296616D01*
G03X297602Y292513I-1J1502D01*
G01X297630Y292537D01*
X297662Y292549D01*
G02X297733Y292562I71J-187D01*
G01X297995D01*
X298022Y292557D01*
X298063Y292549D01*
X298109Y292528D01*
X298130Y292509D01*
G03X298433Y292306I981J1137D01*
G03X298708Y292199I680J1340D01*
G01X298732Y292192D01*
X298750Y292182D01*
X298762Y292175D01*
G03X298881Y292152I96J176D01*
G01X298899Y292155D01*
X298968Y292150D01*
X298969Y292149D01*
G03X299087Y292143I135J1497D01*
G01X299137D01*
G03X300605Y293463I-23J1502D01*
G01Y293466D01*
G02X300671Y293590I198J-26D01*
G02X300804Y293640I132J-150D01*
G01X350978D01*
G02X350997Y293639I-1J-200D01*
G01X350998D01*
G02X351096Y293600I-22J-199D01*
G02X351117Y293582I-119J-160D01*
G01X352434Y292265D01*
X352458Y292151D01*
X352436Y292095D01*
G03X352280Y291256I2170J-838D01*
G01Y291206D01*
X353043Y255651D01*
Y255635D01*
X348571Y181060D01*
G02X348512Y180930I-200J12D01*
G01X305856Y138274D01*
G03X305192Y136840I1620J-1621D01*
G02X305190Y136826I-199J21D01*
G03X305164Y136482I2301J-347D01*
G01Y132081D01*
X305128Y131967D01*
G03X304714Y130643I1912J-1325D01*
G01Y130471D01*
X304712Y130456D01*
G03X304684Y130100I2264J-357D01*
G01Y128360D01*
G03X304832Y127551I2293J1D01*
G01X304834Y127548D01*
X304837Y127539D01*
X304834Y127463D01*
X304690Y127137D01*
X304634Y127083D01*
X304598Y127069D01*
G03X303831Y126559I879J-2154D01*
G01X302451Y125179D01*
G03X302065Y124669I1644J-1646D01*
G01X302051Y124645D01*
X301958Y124551D01*
G03X301473Y123839I1619J-1624D01*
G01X301352Y123728D01*
G03X300436Y123164I729J-2209D01*
G01X299056Y121784D01*
G03X298646Y121228I1646J-1643D01*
G02X298625Y121196I-177J93D01*
G03X298422Y120899I1784J-1437D01*
G03X298244Y120506I1989J-1138D01*
G02X298105Y120377I-189J65D01*
G03X297041Y119769I582J-2253D01*
G01X295661Y118389D01*
G03X295017Y117159I1645J-1645D01*
G01Y117157D01*
X295012Y117129D01*
X294984Y117077D01*
X294802Y116895D01*
X294794Y116893D01*
G03X293689Y116280I516J-2233D01*
G01X292458Y115049D01*
G03X292115Y114611I1619J-1621D01*
G01X292098Y114583D01*
X292051Y114542D01*
X291335Y114246D01*
G02X291258Y114231I-76J185D01*
G01X291217Y114235D01*
G03X290723Y114288I-494J-2273D01*
G03X289833Y114112I-2J-2326D01*
G01X289079Y113799D01*
G02X289002Y113784I-76J185D01*
G01X288103D01*
G03X286483Y113113I0J-2291D01*
G01X285525Y112156D01*
X285054Y111685D01*
G02X284999Y111646I-142J141D01*
G01X284840Y111579D01*
X284838D01*
X284515Y111445D01*
G02X284407Y111437I-68J188D01*
G01X284406D01*
X284375Y111443D01*
X284324Y111470D01*
X284303Y111492D01*
X284302Y111493D01*
G03X283243Y111947I-1076J-1048D01*
G01X283209D01*
G03X282803Y111887I15J-1502D01*
G01X282789Y111883D01*
X282760Y111879D01*
G02X282608Y111920I-28J198D01*
G01X282594Y111932D01*
G02X282532Y112066I138J145D01*
G01Y114623D01*
G03X278926I-1803J0D01*
G01Y111223D01*
G03X279455Y109947I1803J0D01*
G02X279513Y109824I-141J-142D01*
G01X279514Y109814D01*
G02X279511Y109773I-200J-6D01*
G01X279500Y109716D01*
G02X279343Y109558I-196J38D01*
G01X275740Y108840D01*
G02X275701Y108836I-40J196D01*
G01X273766D01*
G02X273624Y108895I0J200D01*
G01X273225Y109294D01*
G03X271580Y109976I-1646J-1645D01*
G03X269254Y107649I0J-2326D01*
G03X269736Y106230I2326J-1D01*
G01X269756Y106204D01*
X269778Y106142D01*
Y105756D01*
X269755Y105692D01*
X269736Y105668D01*
G03X269254Y104251I1844J-1418D01*
G01Y104249D01*
G03X271580Y101922I2327J0D01*
G03X273225Y102604I-1J2327D01*
G01X273636Y103015D01*
G02X273778Y103074I142J-141D01*
G01X276060D01*
G03X276495Y103114I5J2326D01*
G01X276513Y103118D01*
X278679D01*
X278687Y103117D01*
X278694D01*
G03X278754Y103116I68J2292D01*
G01X278756D01*
G03X279632Y103291I-3J2293D01*
G01X279728Y103331D01*
G02X279959Y103272I76J-185D01*
G01X279982Y103242D01*
X279991Y103221D01*
X279992Y103219D01*
X279995Y103212D01*
G03X281384Y102281I1389J571D01*
G03X282886Y103776I0J1502D01*
G01Y103785D01*
G03X282804Y104273I-1502J-2D01*
G01X282754Y104418D01*
G02X282752Y104455I198J29D01*
G01X286512Y106011D01*
X286597Y106008D01*
X286611Y106001D01*
X286613D01*
X286761Y105928D01*
G02X286782Y105917I-82J-182D01*
G02X286861Y105818I-109J-168D01*
G01X286866Y105804D01*
X286869Y105793D01*
G03X288319Y104684I1450J393D01*
G03X289821Y106186I0J1502D01*
G03X289658Y106866I-1502J0D01*
G02X289656Y106870I178J91D01*
G01X289645Y106892D01*
X289641Y106973D01*
X289759Y107287D01*
G02X289869Y107401I187J-70D01*
G01X291573Y108107D01*
G02X291650Y108122I76J-185D01*
G01X293296D01*
G03X294916Y108793I0J2291D01*
G01X295485Y109361D01*
X297720Y111596D01*
G02X297745Y111617I141J-142D01*
G02X297882Y111653I116J-163D01*
G01X297889Y111652D01*
X298063Y111621D01*
X298065D01*
X298225Y111589D01*
G02X298308Y111551I-40J-196D01*
G01X298328Y111535D01*
X298358Y111497D01*
X298368Y111474D01*
G03X299742Y110581I1374J611D01*
G03X301244Y112083I0J1502D01*
G03X300351Y113457I-1504J0D01*
G01X300319Y113471D01*
X300296Y113493D01*
G02X300255Y113546I135J147D01*
G01X300238Y113579D01*
X300231Y113616D01*
X300170Y113942D01*
Y113963D01*
G02X300211Y114085I200J1D01*
G01X300224Y114100D01*
X310176Y124052D01*
G03X310615Y124667I-1620J1621D01*
G01X310621Y124677D01*
G03X310682Y124793I-2028J1140D01*
G02X310754Y124873I179J-89D01*
G01X310887Y124957D01*
G02X311087Y124757I0J-200D01*
G01X311081Y124714D01*
G02X311076Y124689I-198J27D01*
G03X311020Y124285I1446J-406D01*
G01Y124283D01*
G03X312522Y125785I1502J0D01*
G03X311578Y125451I0J-1501D01*
G01X311577Y125450D01*
G02X311364Y125427I-125J157D01*
G01X310985Y125614D01*
X310925Y125714D01*
X310927Y125773D01*
G03X310928Y125832I-2326J69D01*
G01Y134975D01*
G02X310987Y135117I200J0D01*
G01X353555Y177686D01*
G03X354232Y179192I-1645J1645D01*
G01X358804Y255438D01*
G03X358808Y255577I-2322J136D01*
G01Y255627D01*
X358805Y255774D01*
Y255790D01*
X358830Y256205D01*
G03X358834Y256340I-2287J135D01*
G01Y256391D01*
X358811Y257485D01*
X358565Y269072D01*
X358459Y274075D01*
X358365Y278498D01*
X358180Y287177D01*
X358144Y288870D01*
G02X358236Y289043I200J5D01*
G01X358315Y289094D01*
X358524Y289228D01*
G02X358614Y289259I108J-168D01*
G01X358643Y289262D01*
X358696Y289252D01*
X358721Y289240D01*
G03X359375Y289090I654J1352D01*
G01X359408D01*
G03X360868Y290416I-32J1502D01*
G01X360874Y290472D01*
G03X360767Y291159I-1498J119D01*
G03X360731Y291240I-1390J-569D01*
G01Y291242D01*
G03X360528Y291555I-1352J-655D01*
G01Y291556D01*
X360527Y291557D01*
G02X360482Y291693I155J127D01*
G01X360485Y291758D01*
X360493Y291961D01*
G02X360509Y292032I200J-8D01*
G01X360522Y292061D01*
X360546Y292088D01*
X360549Y292092D01*
X362741Y294284D01*
X363683Y295227D01*
G02X363693Y295236I139J-144D01*
G01X401421D01*
G02X401563Y295177I0J-200D01*
G01X404919Y291820D01*
G02X404978Y291678I-141J-142D01*
G01Y275163D01*
G03X405660Y273518I2327J1D01*
G01X406949Y272229D01*
G03X408594Y271548I1645J1646D01*
G01X425330D01*
G03X425626Y271566I7J2326D01*
G01X425638Y271568D01*
X448651D01*
X448692Y271564D01*
X448784Y271525D01*
X448822Y271506D01*
X448848Y271482D01*
X448850Y271480D01*
G03X448972Y271361I14516J14760D01*
G03X449955Y270467I14414J14861D01*
G03X450132Y270318I13421J15763D01*
G03X450173Y270284I13235J15919D01*
G03X450196Y270265I13196J15951D01*
G03X450399Y270100I13159J15982D01*
G01X450407Y270093D01*
X458303Y262197D01*
G02X458361Y262077I-141J-142D01*
G01X458362Y262066D01*
Y254206D01*
G02X458303Y254064I-200J0D01*
G01X452859Y248620D01*
G02X452577I-141J142D01*
G01X449726Y251470D01*
G03X448081Y252152I-1646J-1645D01*
G01X446365D01*
G03X444720Y251470I1J-2327D01*
G01X442339Y249089D01*
G03X441658Y247444I1646J-1645D01*
G01Y245729D01*
G02X441599Y245587I-200J0D01*
G01X441584Y245572D01*
X439744D01*
G03X438099Y244891I0J-2327D01*
G01X435730Y242522D01*
G03X435048Y240877I1645J-1646D01*
G01Y239119D01*
G02X434989Y238977I-200J0D01*
G01X434976Y238964D01*
X433135D01*
G03X431490Y238282I1J-2327D01*
G01X429121Y235913D01*
G03X428440Y234268I1646J-1645D01*
G01Y232511D01*
G02X428381Y232369I-200J0D01*
G01X428361Y232349D01*
G02X428331Y232324I-142J140D01*
G01X426538D01*
G03X424893Y231643I0J-2327D01*
G01X422542Y229292D01*
G03X421860Y227647I1645J-1646D01*
G01Y225889D01*
G03X422542Y224244I2327J1D01*
G01X430525Y216261D01*
G02X430467Y216128I-200J8D01*
G01X423400Y209061D01*
G03X422728Y207441I1620J-1621D01*
G01Y207404D01*
X422723Y207382D01*
G03X422664Y206863I2267J-521D01*
G01Y203501D01*
X422627Y203386D01*
G03X422620Y203375I1928J-1235D01*
G01X422601Y203347D01*
X422587Y203324D01*
X422586Y203322D01*
G03X422347Y202822I1933J-1231D01*
G01X422346Y202818D01*
G03X422229Y201785I2158J-768D01*
G01X422230Y201773D01*
Y200354D01*
G03X422289Y199834I2291J-3D01*
G03X422390Y199510I2232J518D01*
G01X422403Y199478D01*
G03X422494Y199285I2116J880D01*
G03X422661Y199016I2025J1071D01*
G01X422664Y199011D01*
Y198176D01*
X422660Y198170D01*
G03X422500Y197913I1861J-1337D01*
G03X422477Y197869I2019J-1083D01*
G03X422352Y197571I2045J-1033D01*
G01X422348Y197561D01*
X422334Y197525D01*
X422299Y197399D01*
G03X422230Y196883I2222J-560D01*
G01Y195091D01*
G03X422233Y194963I2291J-10D01*
G03X422236Y194913I2288J112D01*
G01X422237Y194901D01*
G03X422271Y194656I2284J192D01*
G03X422290Y194567I2250J434D01*
G01X422297Y194538D01*
G03X422310Y194489I2222J563D01*
G03X422412Y194195I2211J602D01*
G03X422435Y194144I2100J916D01*
G02X422439Y194134I-184J-79D01*
G03X422466Y194077I2085J953D01*
G03X422629Y193799I2054J1017D01*
G02X422664Y193686I-165J-113D01*
G01Y175243D01*
G02X422640Y175149I-200J1D01*
G01X419279Y168864D01*
X419245Y168827D01*
X419223Y168813D01*
G03X418422Y167949I1250J-1962D01*
G01X417501Y166228D01*
G03X417226Y165130I2051J-1097D01*
G01Y165080D01*
X417227Y165027D01*
X417015Y164631D01*
X416981Y164594D01*
X416959Y164580D01*
G03X416157Y163715I1249J-1963D01*
G01X415237Y161994D01*
G03X414962Y160898I2052J-1097D01*
G01Y160896D01*
G03X414963Y160848I2327J24D01*
G01X414964Y160796D01*
X414787Y160467D01*
Y160465D01*
X414751Y160398D01*
X414717Y160361D01*
X414695Y160347D01*
G03X413893Y159482I1249J-1963D01*
G01X412973Y157761D01*
G03X412698Y156665I2052J-1097D01*
G01Y156663D01*
G03X412699Y156615I2327J24D01*
G01X412700Y156563D01*
X412487Y156165D01*
X412453Y156128D01*
X412431Y156114D01*
G03X411629Y155249I1249J-1963D01*
G01X410709Y153528D01*
G03X410434Y152432I2052J-1097D01*
G01Y152430D01*
G03X410435Y152382I2327J24D01*
G01X410436Y152330D01*
X410223Y151932D01*
X410189Y151895D01*
X410167Y151881D01*
G03X409365Y151016I1249J-1963D01*
G01X408445Y149295D01*
G03X408170Y148199I2052J-1097D01*
G01Y148197D01*
G03X408171Y148149I2327J24D01*
G01X408172Y148096D01*
X407972Y147723D01*
G02X407904Y147649I-176J94D01*
G01X407903Y147648D01*
G03X407101Y146783I1249J-1963D01*
G01X406181Y145062D01*
G03X405906Y143966I2052J-1097D01*
G01Y143964D01*
G03X405907Y143916I2327J24D01*
G01X405908Y143863D01*
X405477Y143057D01*
G03X405207Y142055I2020J-1082D01*
G01X405205Y142029D01*
G03X405172Y141640I2293J-390D01*
G01Y140676D01*
X405136Y140562D01*
G03X404722Y139238I1912J-1325D01*
G01Y137286D01*
G03X405136Y135962I2326J1D01*
G01X405172Y135848D01*
Y135812D01*
G03X404722Y134437I1876J-1375D01*
G01Y132484D01*
G03X404806Y131866I2326J1D01*
G01X404814Y131837D01*
X404812Y131778D01*
X404799Y131739D01*
X404785Y131683D01*
X404778Y131654D01*
X404777Y131652D01*
G03X404761Y131587I2217J-580D01*
G01Y131585D01*
G03X404757Y131567I2234J-506D01*
G01Y131565D01*
X404753Y131545D01*
G03X404743Y131496I2240J-483D01*
G01X404740Y131479D01*
G03X404708Y131090I2260J-382D01*
G01Y129347D01*
G03X404720Y129109I2291J-4D01*
G01X404721Y129104D01*
G03X404722Y129095I2278J249D01*
G01Y127684D01*
G03X404769Y127220I2326J1D01*
G02X404768Y127135I-196J-40D01*
G03X404708Y126615I2231J-521D01*
G01Y124870D01*
G03X405053Y123662I2291J1D01*
G01X405056Y123658D01*
X405058Y123653D01*
X405067Y123636D01*
G02X405085Y123511I-179J-90D01*
G01X402673Y121098D01*
X402624Y121091D01*
G03X402595Y121086I375J-2261D01*
G01X402591Y121085D01*
X402583Y121084D01*
X402577Y121083D01*
G03X401338Y120421I409J-2256D01*
G02X401336Y120419I-142J140D01*
G01X400134Y119217D01*
G03X399517Y118091I1621J-1620D01*
G02X399490Y118041I-188J69D01*
G03X399479Y118029I141J-140D01*
G01X399473Y118021D01*
X399398Y117946D01*
X399393Y117942D01*
G03X399387Y117936I138J-144D01*
G02X399317Y117896I-132J150D01*
G03X398199Y117280I503J-2235D01*
G01X396968Y116049D01*
G03X396483Y115335I1619J-1621D01*
G01X396474Y115314D01*
X396450Y115281D01*
X396439Y115271D01*
G02X396377Y115229I-141J142D01*
G01X396248Y115176D01*
X396246D01*
X396143Y115134D01*
G02X396075Y115121I-71J187D01*
G01X395968D01*
X395934Y115134D01*
G03X395125Y115284I-816J-2142D01*
G01X393377D01*
G03X392045Y114857I0J-2292D01*
G01X392019Y114839D01*
X391961Y114820D01*
X391593D01*
G03X390985Y114739I1J-2327D01*
G01X390973Y114736D01*
G03X389822Y114113I470J-2243D01*
G01X389656Y113948D01*
X389297Y113589D01*
G02X389245Y113551I-143J140D01*
G01X389216Y113537D01*
X389196Y113534D01*
X389180Y113532D01*
G03X389115Y113522I316J-2271D01*
G01X389111Y113521D01*
X389103Y113520D01*
X389097Y113519D01*
G03X387858Y112857I409J-2256D01*
G02X387856Y112855I-142J140D01*
G01X386654Y111653D01*
G03X386329Y111243I1622J-1620D01*
G01X386328Y111242D01*
X386314Y111220D01*
X386311Y111215D01*
X386310Y111213D01*
G03X386301Y111198I1961J-1187D01*
G03X386005Y110354I1974J-1166D01*
G01X386000Y110321D01*
X385987Y110294D01*
G02X385949Y110241I-179J89D01*
G01X385536Y109828D01*
G02X385507Y109804I-141J141D01*
G01X384878D01*
G02X384800Y109906I111J166D01*
G01X384768Y110001D01*
G03X384750Y110040I-189J-64D01*
G01X384678Y110161D01*
G02X384649Y110258I171J104D01*
G01X384648Y110309D01*
X384672Y110356D01*
G03X384674Y110360I-178J91D01*
G01X384675Y110361D01*
X384696Y110402D01*
G03X384894Y111221I-1605J821D01*
G01Y114623D01*
G03X381288I-1803J0D01*
G01Y111206D01*
G03X381565Y110263I1803J17D01*
G01X381580Y110239D01*
X381598Y110176D01*
G02X381596Y110061I-192J-54D01*
G01X381589Y110037D01*
X381544Y109905D01*
X381388Y109772D01*
G03X380132Y109123I390J-2294D01*
G01X379883Y108874D01*
G02X379741Y108816I-141J142D01*
G01X376149D01*
G02X376007Y108874I-1J200D01*
G01X375587Y109294D01*
G03X373942Y109976I-1646J-1645D01*
G03X371616Y107649I0J-2326D01*
G03X372098Y106230I2326J-1D01*
G01X372118Y106204D01*
X372140Y106142D01*
Y105764D01*
G02X372133Y105712I-200J0D01*
G01X372098Y105668D01*
G03X371616Y104251I1844J-1418D01*
G01Y104249D01*
G03X373942Y101922I2327J0D01*
G03X375587Y102604I-1J2327D01*
G01X375977Y102994D01*
G02X376119Y103052I141J-142D01*
G01X381249D01*
G03X381846Y103130I0J2327D01*
G01X381872Y103136D01*
G03X382149Y103188I-283J2274D01*
G01X382187Y103198D01*
X382223Y103193D01*
G02X382296Y103169I-25J-199D01*
G01X382351Y103137D01*
G02X382396Y103103I-97J-175D01*
G01X382412Y103086D01*
X382426Y103060D01*
G03X383739Y102280I1318J724D01*
G01X383746D01*
G03X385248Y103721I0J1503D01*
G01X385250Y103759D01*
X385271Y103807D01*
G02X385306Y103856I178J-90D01*
G01X385373Y103920D01*
X385442Y103986D01*
G02X385581Y104042I139J-144D01*
G01X387039D01*
G03X388684Y104723I0J2327D01*
G01X389186Y105224D01*
G02X389335Y105283I142J-141D01*
G01X389395Y105281D01*
G02X389475Y105261I-8J-200D01*
G01X389509Y105244D01*
X389537Y105212D01*
X389539Y105210D01*
G03X390681Y104684I1142J977D01*
G03X392173Y106010I0J1502D01*
G01X392179Y106064D01*
G03X392184Y106186I-1498J122D01*
G01Y106187D01*
G03X391676Y107313I-1503J0D01*
G01X391656Y107331D01*
X391627Y107368D01*
G02X391587Y107474I159J121D01*
G01X391585Y107527D01*
Y107532D01*
G02X391643Y107682I200J9D01*
G01X392959Y108997D01*
G02X393101Y109056I142J-141D01*
G01X397818D01*
G03X399463Y109738I-1J2327D01*
G01X400664Y110938D01*
G02X400798Y110997I142J-141D01*
G01X400829Y110998D01*
X400831D01*
X400978Y111002D01*
G02X401052Y110990I6J-200D01*
G01X401082Y110979D01*
X401108Y110957D01*
X401114Y110952D01*
G03X401136Y110934I962J1154D01*
G01X401137Y110933D01*
G03X401142Y110929I941J1171D01*
G01X401143Y110928D01*
X401581Y110550D01*
G03X401834Y110543I131J151D01*
G01X401859Y110562D01*
X401934Y110590D01*
X401980Y110586D01*
G03X402101Y110581I122J1497D01*
G01X402200D01*
G03X402228Y110583I0J200D01*
G01X402318Y110596D01*
G03X403589Y111857I-214J1487D01*
G01Y111859D01*
X403598Y111915D01*
X403601Y111964D01*
Y111966D01*
G03X403606Y112063I-1496J126D01*
G01Y112085D01*
G03X403601Y112208I-1502J1D01*
G01X403597Y112252D01*
X403613Y112294D01*
G02X403659Y112366I188J-69D01*
G01X403683Y112390D01*
X403686Y112467D01*
G03X403637Y112606I-200J8D01*
G01X403259Y113044D01*
X403258Y113045D01*
G03X403254Y113050I-1175J-936D01*
G01X403253Y113051D01*
G03X403235Y113073I-1172J-940D01*
G01X403230Y113079D01*
X403208Y113105D01*
X403197Y113135D01*
G02X403185Y113209I188J68D01*
G01X403189Y113356D01*
Y113358D01*
X403190Y113389D01*
G02X403249Y113524I200J-7D01*
G01X410253Y120528D01*
G03X410934Y122173I-1646J1645D01*
G01Y140725D01*
G02X410958Y140819I200J-1D01*
G01X428152Y172967D01*
G03X428426Y174061I-2052J1095D01*
G01Y205353D01*
G02X428485Y205495I200J0D01*
G01X435725Y212735D01*
G03X436382Y214039I-1644J1646D01*
G02X436414Y214123I198J-27D01*
G03X436812Y215412I-1893J1291D01*
G01Y217088D01*
G02X436816Y217126I200J-2D01*
G02X436869Y217228I196J-37D01*
G01X436870Y217229D01*
X436968Y217326D01*
G02X436983Y217338I132J-150D01*
G01X438773D01*
G03X440418Y218020I-1J2327D01*
G01X442774Y220376D01*
G03X443456Y222021I-1645J1646D01*
G01Y223811D01*
G02X443468Y223826I162J-117D01*
G01X443521Y223880D01*
G02X443523Y223882I142J-140D01*
G01X443530Y223889D01*
G02X443672Y223948I142J-141D01*
G01X445382D01*
G03X447027Y224629I0J2327D01*
G01X449383Y226985D01*
G03X450064Y228630I-1646J1645D01*
G01Y230418D01*
G02X450089Y230448I165J-112D01*
G01X450130Y230489D01*
G02X450132Y230491I142J-140D01*
G01X450186Y230544D01*
G02X450201Y230556I132J-150D01*
G01X451991D01*
G03X453636Y231238I-1J2327D01*
G01X455992Y233594D01*
G03X456674Y235239I-1645J1646D01*
G01Y236953D01*
G03X455992Y238598I-2327J-1D01*
G01X452536Y242054D01*
G02X452493Y242273I141J141D01*
G02X452677Y242396I185J-77D01*
G01X453822D01*
G03X455450Y243061I0J2326D01*
G01X455454Y243065D01*
G03X455524Y243132I-1549J1689D01*
G01X463310Y250918D01*
G02X463321Y250928I140J-143D01*
G01X463328Y250934D01*
G02X463485Y250973I123J-158D01*
G01X463528Y250964D01*
X463542Y250959D01*
G03X464026Y250869I513J1411D01*
G01X464056D01*
G03X465494Y251940I-2J1503D01*
G01Y251941D01*
X465506Y251980D01*
X465608Y252104D01*
X465645Y252123D01*
G03X465692Y252148I-1052J2035D01*
G03X466217Y252541I-1096J2012D01*
G01X466460Y252784D01*
X466473Y252793D01*
G03X466771Y253045I-1348J1896D01*
G01X477008Y263282D01*
G02X477023Y263284I34J-197D01*
G01X477034Y263285D01*
X488652D01*
G02X488820Y263192I-1J-200D01*
G01Y262725D01*
G03X489075Y261667I2326J1D01*
G02X489077Y261663I-178J-91D01*
G03X489524Y261032I2067J990D01*
G01X490497Y260059D01*
X490736Y259821D01*
G03X491572Y259288I1621J1620D01*
G01X491576Y259286D01*
G03X492417Y259130I838J2171D01*
G01X503064D01*
G02X503264Y258930I0J-200D01*
G01Y167740D01*
G03X503945Y166095I2327J0D01*
G01X509080Y160960D01*
X509109Y160906D01*
X509114Y160876D01*
G03X509758Y159645I2289J414D01*
G01X511138Y158265D01*
G03X511526Y157952I1646J1644D01*
G01X511544Y157941D01*
X511742Y157743D01*
G03X512490Y157244I1622J1621D01*
G01X512602Y157125D01*
G03X513153Y156250I2195J771D01*
G01X514533Y154870D01*
G03X514930Y154551I1647J1643D01*
G02X514960Y154528I-106J-170D01*
G03X515580Y154112I1570J1669D01*
G03X515820Y154018I954J2083D01*
G01X515950Y153881D01*
G03X516548Y152855I2243J620D01*
G01X517928Y151475D01*
G03X518737Y150949I1645J1645D01*
G01X518748Y150945D01*
G03X518900Y150882I953J2084D01*
G03X519113Y150814I803J2146D01*
G01X519258Y150776D01*
X519262Y150771D01*
Y143442D01*
G03X519943Y141797I2327J0D01*
G01X524153Y137587D01*
G02X524212Y137445I-141J-142D01*
G01Y136844D01*
X524196Y136789D01*
X524180Y136765D01*
G03X523814Y135514I1960J-1253D01*
G01Y135334D01*
G03X523807Y135314I2158J-766D01*
G01X523804Y135304D01*
G03X523738Y135043I2184J-691D01*
G03X523713Y134348I2250J-429D01*
G01X523714Y134336D01*
Y132915D01*
G03X523936Y131931I2292J0D01*
G03X523997Y131810I2076J971D01*
G01X524021Y131714D01*
X524005Y131635D01*
G03X523821Y130889I2136J-922D01*
G02X523813Y130846I-200J15D01*
G03X523714Y130182I2192J-666D01*
G01Y128437D01*
G03X523936Y127453I2292J0D01*
G03X524074Y127202I2073J977D01*
G01X524089Y127177D01*
X524096Y127152D01*
G02X524105Y127094I-191J-59D01*
G01Y127040D01*
X524082Y126996D01*
G03X523983Y126784I2056J-1089D01*
G01X523976Y126768D01*
G03X523936Y126688I2030J-1065D01*
G01Y126686D01*
G03X523714Y125703I2069J-984D01*
G01Y123959D01*
G03X523936Y122975I2292J0D01*
G03X524074Y122724I2073J977D01*
G01X524089Y122699D01*
X524096Y122674D01*
G02X524105Y122616I-191J-59D01*
G01Y122568D01*
G02X524096Y122510I-200J1D01*
G01X524089Y122485D01*
X524074Y122460D01*
G03X523936Y122209I1935J-1228D01*
G03X523714Y121225I2070J-984D01*
G01Y119478D01*
G03X523866Y118659I2292J2D01*
G02X523874Y118633I-187J-72D01*
G03X524100Y118042I2266J528D01*
G01X524089Y118007D01*
X524074Y117982D01*
G03X523936Y117731I1935J-1228D01*
G03X523714Y116747I2070J-984D01*
G01Y115000D01*
G03X523806Y114358I2292J1D01*
G01X523814Y114307D01*
G03X523981Y113494I2326J54D01*
G02X523973Y113328I-186J-74D01*
G03X523936Y113253I2037J-1051D01*
G03X523714Y112269I2070J-984D01*
G01Y110524D01*
G03Y110494I2291J-15D01*
G01Y110462D01*
G03X523715Y110428I2291J50D01*
G01Y110426D01*
G03X523718Y110373I2289J103D01*
G01Y110366D01*
X523719Y110350D01*
G03X523728Y110262I2284J189D01*
G01Y110260D01*
X523729Y110253D01*
G03X523731Y110237I2275J276D01*
G01Y110234D01*
X523732Y110227D01*
X523736Y110198D01*
X523721Y110131D01*
G02X523696Y110076I-192J54D01*
G01X523664Y110028D01*
G02X523640Y110000I-163J116D01*
G01X523617Y109977D01*
G02X523585Y109951I-141J141D01*
G01X523579Y109947D01*
X523528Y109938D01*
G03X521616Y107649I414J-2289D01*
G03X522099Y106231I2327J1D01*
G01Y106230D01*
X522119Y106204D01*
X522140Y106143D01*
Y105788D01*
G02X522099Y105667I-200J0D01*
G03X521616Y104249I1844J-1419D01*
G03X523943Y101922I2327J0D01*
G03X525588Y102604I-1J2327D01*
G01X525989Y103005D01*
G02X526131Y103064I142J-141D01*
G01X526389D01*
G03X528034Y103745I0J2327D01*
G01X529345Y105056D01*
G03X530026Y106701I-1646J1645D01*
G01Y138903D01*
G03X529888Y139691I-2326J-1D01*
G01X529876Y139724D01*
Y139832D01*
G03X529204Y141452I-2292J-1D01*
G01X526278Y144378D01*
X525063Y145592D01*
G02X525024Y145647I141J142D01*
G01Y152204D01*
G03X524726Y153342I-2326J-1D01*
G01X524724Y153344D01*
G03X524333Y153868I-2013J-1094D01*
G01X509113Y169089D01*
G02X509093Y169112I141J142D01*
G02X509054Y169230I161J119D01*
G01Y259316D01*
G02X509055Y259335I200J-1D01*
G01Y259336D01*
G02X509094Y259434I199J-22D01*
G02X509112Y259455I160J-119D01*
G01X509941Y260284D01*
G03X510000Y260426I-141J142D01*
G01Y301654D01*
G02X510001Y301673I200J-1D01*
G01Y301674D01*
G02X510056Y301791I199J-22D01*
G01X511339Y303073D01*
G02X511353Y303084I131J-152D01*
G01X549142D01*
G02X549284Y303025I0J-200D01*
G01X563475Y288835D01*
G02Y288553I-142J-141D01*
G01X560695Y285773D01*
G03X560443Y285475I1644J-1646D01*
G01X560434Y285462D01*
X560108Y285136D01*
G03X560049Y284994I141J-142D01*
G01Y284533D01*
X560046Y284517D01*
G03X560014Y284128I2294J-385D01*
G01Y282414D01*
G03X560046Y282025I2326J-4D01*
G01X560049Y282009D01*
Y281548D01*
G03X560108Y281406I200J0D01*
G01X560434Y281080D01*
X560443Y281067D01*
G03X560695Y280769I1896J1348D01*
G01X563081Y278383D01*
G03X563379Y278131I1646J1644D01*
G01X563392Y278122D01*
X563688Y277826D01*
G03X563830Y277767I142J141D01*
G01X564177D01*
X564200Y277762D01*
G03X564724Y277702I525J2266D01*
G01X566436D01*
G02X566578Y277643I0J-200D01*
G01X566592Y277629D01*
Y275793D01*
G03X566653Y275267I2327J3D01*
G01X566658Y275244D01*
Y274939D01*
G03X566717Y274797I200J0D01*
G01X566917Y274597D01*
G02X566945Y274562I-141J-142D01*
G03X567274Y274148I1974J1231D01*
G01X569648Y271774D01*
G03X570062Y271445I1645J1645D01*
G01X570081Y271433D01*
X570297Y271217D01*
G03X570439Y271158I142J141D01*
G01X570744D01*
X570767Y271153D01*
G03X571293Y271092I529J2266D01*
G01X573046D01*
G02X573188Y271033I0J-200D01*
G01X573204Y271017D01*
Y269169D01*
G03X573262Y268655I2327J2D01*
G01X573267Y268633D01*
Y268330D01*
G03X573326Y268188I200J0D01*
G01X573527Y267987D01*
X573540Y267966D01*
G03X573886Y267524I1991J1203D01*
G01X576242Y265168D01*
G03X576684Y264822I1645J1645D01*
G01X576705Y264809D01*
X576906Y264608D01*
G03X577048Y264549I142J141D01*
G01X577351D01*
X577373Y264544D01*
G03X577887Y264486I516J2269D01*
G01X579643D01*
G03X580157Y264544I-2J2327D01*
G01X580179Y264549D01*
X580494D01*
G03X580636Y264608I0J200D01*
G01X580855Y264827D01*
X580874Y264839D01*
G03X581288Y265168I-1231J1974D01*
G01X584209Y268089D01*
G02X584491I141J-142D01*
G01X603974Y248606D01*
G02X604032Y248480I-141J-141D01*
G01X604588Y241289D01*
Y241261D01*
X602132Y200292D01*
G03X602128Y200153I2322J-136D01*
G03X602129Y200078I2326J-6D01*
G01X603097Y170202D01*
G03X603142Y169812I2325J71D01*
G01X603146Y169797D01*
X603162Y169297D01*
G03X603221Y169162I200J7D01*
G01X603773Y168610D01*
G02X603775Y168608I-140J-142D01*
G03X603804Y168579I1635J1606D01*
G01X615232Y157150D01*
X615260Y157098D01*
X615265Y157069D01*
G03X615904Y155868I2284J445D01*
G01X617284Y154488D01*
G03X618458Y153855I1645J1645D01*
G01X618486Y153849D01*
G02X618587Y153795I-40J-196D01*
G01X618593Y153789D01*
G02X618618Y153759I-140J-142D01*
G01Y151123D01*
G03X618650Y150734I2326J-4D01*
G01X618653Y150718D01*
Y150257D01*
G03X618712Y150115I200J0D01*
G01X619038Y149789D01*
X619047Y149776D01*
G03X619299Y149478I1896J1348D01*
G01X623209Y145568D01*
G03X623217Y145517I2302J335D01*
G01Y144987D01*
G03X623276Y144845I200J0D01*
G01X623808Y144313D01*
G03X623832Y144287I1697J1543D01*
G03X623909Y144209I1670J1572D01*
G02X623911Y144207I-140J-142D01*
G01X625119Y143000D01*
G03X625171Y142950I1615J1628D01*
G02X625175Y142946I-139J-143D01*
G01X625732Y142389D01*
G03X625874Y142330I142J141D01*
G01X626166D01*
X626196Y142321D01*
G03X626417Y142264I691J2221D01*
G01X626507Y142245D01*
X626557Y142218D01*
X626576Y142199D01*
Y141912D01*
G02X626542Y141801I-200J1D01*
G01X626541Y141800D01*
G03X626126Y140475I1912J-1326D01*
G01Y138976D01*
X626121Y138955D01*
G03X626113Y138899I192J-56D01*
G01Y138091D01*
G03X626112Y138037I2291J-69D01*
G01Y136290D01*
G03X626113Y136233I2292J12D01*
G01Y135427D01*
G03X626121Y135371I200J0D01*
G01X626126Y135350D01*
Y134498D01*
X626121Y134477D01*
G03X626113Y134421I192J-56D01*
G01Y133615D01*
G03X626112Y133558I2291J-69D01*
G01Y131812D01*
G03X626113Y131755I2292J12D01*
G01Y130949D01*
G03X626121Y130893I200J0D01*
G01X626126Y130872D01*
Y130020D01*
X626121Y129999D01*
G03X626113Y129943I192J-56D01*
G01Y129137D01*
G03X626112Y129080I2291J-69D01*
G01Y127334D01*
G03X626113Y127277I2292J12D01*
G01Y126471D01*
G03X626126Y126399I200J-1D01*
G02X626138Y126308I-187J-71D01*
G03X626126Y126075I2315J-236D01*
G01Y125542D01*
X626121Y125521D01*
G03X626113Y125465I192J-56D01*
G01Y124659D01*
G03X626112Y124602I2291J-69D01*
G01Y122856D01*
G03X626113Y122799I2292J12D01*
G01Y121993D01*
G03X626172Y121851I200J0D01*
G01X626194Y121829D01*
G03X626126Y121275I2258J-558D01*
G01Y121064D01*
X626121Y121043D01*
G03X626113Y120987I192J-56D01*
G01Y120181D01*
G03X626112Y120124I2291J-69D01*
G01Y118378D01*
G03X626113Y118321I2292J12D01*
G01Y117515D01*
G03X626172Y117373I200J0D01*
G01X626181Y117364D01*
G02X626231Y117164I-141J-142D01*
G01Y117163D01*
G03X626131Y116616I2222J-689D01*
G02X626122Y116569I-200J14D01*
G03X626113Y116510I191J-59D01*
G01Y115703D01*
G03X626112Y115646I2291J-69D01*
G01Y113900D01*
G03X626113Y113843I2292J12D01*
G01Y113037D01*
G03X626172Y112895I200J0D01*
G01X626267Y112800D01*
G02X626310Y112581I-141J-141D01*
G03X626183Y112184I2143J-905D01*
G01X626172Y112173D01*
G03X626113Y112031I141J-142D01*
G01Y111225D01*
G03X626112Y111168I2291J-69D01*
G01Y110140D01*
G02X625985Y109954I-200J0D01*
G01X625943Y109947D01*
G03X625916Y109943I327J-2303D01*
G01X625900Y109940D01*
X625439D01*
G03X625297Y109881I0J-200D01*
G01X624971Y109555D01*
X624958Y109546D01*
G03X624408Y108996I1347J-1897D01*
G01X624399Y108983D01*
X624073Y108657D01*
G03X624014Y108515I141J-142D01*
G01Y108054D01*
X624011Y108038D01*
G03X623978Y107649I2294J-390D01*
G03X624011Y107260I2327J1D01*
G01X624014Y107244D01*
Y106783D01*
G03X624073Y106641I200J0D01*
G01X624399Y106315D01*
X624408Y106302D01*
G03X624460Y106232I1893J1352D01*
G01X624462Y106230D01*
X624493Y106189D01*
G02X624502Y106129I-191J-59D01*
G01Y105788D01*
G02X624461Y105667I-200J0D01*
G03X623978Y104249I1844J-1419D01*
G03X626305Y101922I2327J0D01*
G03X627950Y102604I-1J2327D01*
G01X628370Y103024D01*
G02X628512Y103082I141J-142D01*
G01X628862D01*
G03X630507Y103764I-1J2327D01*
G01X631658Y104915D01*
G03X632340Y106560I-1645J1646D01*
G01Y143624D01*
G03X631658Y145269I-2327J-1D01*
G01X631272Y145655D01*
Y145672D01*
X631276Y145693D01*
X631296Y145794D01*
X631341Y146018D01*
G02X631380Y146099I195J-44D01*
G01X631396Y146118D01*
X631435Y146148D01*
G03X631445Y146152I-553J1396D01*
G01X631457Y146157D01*
G03X632373Y147540I-586J1383D01*
G03X630871Y149042I-1502J0D01*
G03X629487Y148126I0J-1504D01*
G01X629486Y148125D01*
G02X629429Y148048I-184J77D01*
G01X629411Y148033D01*
X629368Y148013D01*
X629265Y147992D01*
X629263D01*
X629007Y147943D01*
G02X628987Y147941I-30J198D01*
G01X624439Y152488D01*
G02X624380Y152630I141J142D01*
G01Y155215D01*
G03X623699Y156860I-2327J0D01*
G01X620375Y160185D01*
G02X620333Y160406I142J141D01*
G01X620506Y160804D01*
X620610Y160869D01*
X620672Y160867D01*
G03X620727Y160866I55J1501D01*
G03X621754Y161272I0J1502D01*
G01X621781Y161298D01*
X621852Y161326D01*
X622202D01*
X622273Y161298D01*
X622300Y161272D01*
G03X624354I1027J1096D01*
G01X624381Y161298D01*
X624452Y161326D01*
X624802D01*
X624873Y161298D01*
X624900Y161272D01*
G03X625927Y160866I1027J1096D01*
G03Y163870I0J1502D01*
G03X624900Y163464I0J-1502D01*
G01X624873Y163438D01*
X624802Y163410D01*
X624452D01*
X624381Y163438D01*
X624354Y163464D01*
G03X622300I-1027J-1096D01*
G01X622273Y163438D01*
X622202Y163410D01*
X621852D01*
X621781Y163438D01*
X621754Y163464D01*
G03X620727Y163870I-1027J-1096D01*
G03X619225Y162368I0J-1502D01*
G03X619226Y162313I1502J0D01*
G01X619228Y162251D01*
X619163Y162147D01*
X618765Y161974D01*
G02X618544Y162016I-80J184D01*
G01X608869Y171691D01*
G02X608810Y171826I141J142D01*
G01X607895Y200097D01*
G02X607896Y200115I200J-2D01*
G01X610356Y241166D01*
G03X610360Y241304I-2322J136D01*
G01Y241306D01*
G03X610354Y241484I-2326J11D01*
G01X609675Y250265D01*
G03X609000Y251731I-2320J-180D01*
G01X586854Y273877D01*
G03X585209Y274558I-1645J-1646D01*
G01X583415D01*
G02X583386Y274582I112J165D01*
G01X583300Y274668D01*
G02X583276Y274697I141J141D01*
G01Y276490D01*
G03X582595Y278135I-2327J0D01*
G01X580244Y280486D01*
G03X578599Y281168I-1646J-1645D01*
G01X576804D01*
G02X576778Y281190I116J163D01*
G01X576690Y281278D01*
G02X576668Y281304I141J142D01*
G01Y283099D01*
G03X575986Y284744I-2327J-1D01*
G01X573635Y287095D01*
G03X571990Y287776I-1645J-1646D01*
G01X570197D01*
G02X570168Y287800I112J165D01*
G01X570082Y287886D01*
G02X570046Y287936I142J140D01*
G02X570024Y288027I178J91D01*
G01Y289709D01*
G03X569352Y291329I-2292J-1D01*
G01X563478Y297203D01*
G02X563442Y297253I142J140D01*
G02X563420Y297344I178J91D01*
G01Y303159D01*
G02X563421Y303178I200J-1D01*
G01Y303179D01*
G02X563460Y303277I199J-22D01*
G02X563478Y303298I160J-119D01*
G01X564231Y304051D01*
G02X564351Y304109I142J-141D01*
G01X564362Y304110D01*
X586462D01*
X586565Y304081D01*
G03X587767Y303746I1203J1991D01*
G01X644214D01*
G02X644356Y303687I0J-200D01*
G01X705305Y242739D01*
G02X705361Y242629I-142J-141D01*
G01X706546Y235072D01*
G02X706548Y235029I-198J-31D01*
G01X703933Y191424D01*
Y191422D01*
G03X703928Y191285I2321J-153D01*
G01Y191283D01*
G03X703963Y190884I2327J3D01*
G01X703965Y190871D01*
X704581Y172877D01*
G03X704627Y172491I2325J81D01*
G01X704630Y172474D01*
X704686Y170839D01*
Y170834D01*
G03X705358Y169213I2293J1D01*
G01X706579Y167991D01*
X706589Y167978D01*
G03X706836Y167687I1891J1355D01*
G01X712374Y162149D01*
X712403Y162095D01*
X712408Y162065D01*
G03X713052Y160834I2289J414D01*
G01X714432Y159454D01*
G03X715662Y158810I1645J1645D01*
G01X715768Y158755D01*
X715793Y158730D01*
G03X716447Y157439I2299J354D01*
G01X717827Y156059D01*
G03X719057Y155415I1645J1645D01*
G01X719163Y155360D01*
X719188Y155335D01*
G03X719842Y154044I2299J354D01*
G01X721222Y152664D01*
G03X722452Y152020I1645J1645D01*
G01X722558Y151965D01*
X722583Y151940D01*
G03X723237Y150649I2299J354D01*
G01X723329Y150557D01*
X723344Y150540D01*
G03X723464Y150401I1795J1428D01*
G03X723541Y150323I1670J1572D01*
G02X723543Y150321I-140J-142D01*
G01X724750Y149115D01*
G03X725800Y148515I1622J1620D01*
G01X725891Y148492D01*
G02X725950Y148455I-75J-185D01*
G01Y143754D01*
G03X726632Y142109I2327J1D01*
G01X728843Y139898D01*
G02X728902Y139756I-141J-142D01*
G01Y139525D01*
G02X728899Y139521I-161J118D01*
G01X728896Y139517D01*
Y139516D01*
X728864Y139473D01*
G03X728708Y139221I1866J-1329D01*
G03X728685Y139177I2019J-1083D01*
G03X728560Y138879I2045J-1033D01*
G01X728556Y138869D01*
X728542Y138833D01*
X728507Y138707D01*
G03X728438Y138191I2222J-560D01*
G01Y136397D01*
G03X728485Y135936I2292J1D01*
G01X728489Y135896D01*
X728486Y135862D01*
G03X728452Y135461I2292J-396D01*
G01Y133918D01*
G03X728451Y133908I2280J-233D01*
G01X728450Y133903D01*
G03X728438Y133665I2280J-234D01*
G01Y131921D01*
G03X728519Y131319I2291J2D01*
G02X728520Y131219I-193J-52D01*
G03X728452Y130662I2258J-558D01*
G01Y129440D01*
G03X728451Y129430I2280J-233D01*
G01X728450Y129425D01*
G03X728438Y129187I2280J-234D01*
G01Y127442D01*
G03X728562Y126699I2292J1D01*
G01X728573Y126633D01*
X728564Y126573D01*
G03X728452Y125862I2214J-713D01*
G01Y124962D01*
G03X728451Y124952I2280J-233D01*
G01X728450Y124947D01*
G03X728438Y124709I2280J-234D01*
G01Y122964D01*
G03X728617Y122077I2292J1D01*
G02X728618Y121926I-185J-77D01*
G03X728452Y121065I2160J-863D01*
G01Y120484D01*
G03X728451Y120474I2280J-233D01*
G01X728450Y120469D01*
G03X728438Y120231I2280J-234D01*
G01Y118487D01*
G03X728660Y117503I2292J0D01*
G03X728684Y117454I2070J984D01*
G02X728685Y117277I-179J-90D01*
G03X728452Y116265I2093J-1015D01*
G01Y116006D01*
G03X728451Y115996I2280J-233D01*
G01X728450Y115991D01*
G03X728438Y115753I2280J-234D01*
G01Y114009D01*
G03X728660Y113025I2292J0D01*
G03X728802Y112767I2075J974D01*
G01X728813Y112749D01*
X728822Y112721D01*
G03X728453Y111546I1956J-1260D01*
G01X728452Y111531D01*
G03X728438Y111279I2278J-253D01*
G01Y110104D01*
G02X728376Y109960I-200J1D01*
G01X728272Y109942D01*
G03X726340Y107649I395J-2293D01*
G03X726823Y106231I2327J1D01*
G01Y106230D01*
X726843Y106204D01*
X726864Y106143D01*
Y105788D01*
G02X726823Y105667I-200J0D01*
G03X726340Y104249I1844J-1419D01*
G03X728667Y101922I2327J0D01*
G03X730312Y102604I-1J2327D01*
G01X730732Y103024D01*
G02X730874Y103082I141J-142D01*
G01X731096D01*
G03X732741Y103764I-1J2327D01*
G01X733983Y105006D01*
G03X734664Y106651I-1646J1645D01*
G01Y141263D01*
G03X734601Y141803I-2326J2D01*
G02X734596Y141837I195J46D01*
G03X733928Y143322I-2288J-136D01*
G01X732696Y144554D01*
X731735Y145514D01*
G02X731714Y145539I142J141D01*
G01Y146144D01*
X731715Y146145D01*
X731734Y146171D01*
X731767Y146196D01*
X731957Y146291D01*
X731959D01*
X732104Y146362D01*
G02X732184Y146382I88J-180D01*
G01X732223Y146383D01*
X732296Y146355D01*
X732319Y146338D01*
G03X733233Y146030I914J1202D01*
G03Y149050I0J1510D01*
G03X732316Y148739I1J-1510D01*
G01X732315Y148738D01*
X732313Y148737D01*
G02X732105Y148717I-120J160D01*
G01X732093Y148723D01*
X731998Y148770D01*
X731996D01*
X731787Y148873D01*
G02X731714Y148937I91J178D01*
G01Y149996D01*
G03X731032Y151641I-2327J-1D01*
G01X717453Y165221D01*
G03X717414Y165259I-1643J-1647D01*
G02X717410Y165263I139J143D01*
G01X711400Y171273D01*
G02X711358Y171335I142J141D01*
G01X710334Y173692D01*
G02X710318Y173765I184J79D01*
G01X709719Y191269D01*
G03X709709Y191423I-2325J-74D01*
G01X709707Y191440D01*
X712324Y235077D01*
G03X712328Y235216I-2322J136D01*
G03X712300Y235576I-2326J0D01*
G01X710835Y244923D01*
G03X710182Y246208I-2298J-360D01*
G01X656397Y299993D01*
G02X656338Y300135I141J142D01*
G01Y302765D01*
G02X656339Y302784I200J-1D01*
G01Y302785D01*
G02X656378Y302883I199J-22D01*
G02X656396Y302904I160J-119D01*
G01X658672Y305180D01*
G02X658792Y305238I142J-141D01*
G01X658803Y305239D01*
X716652D01*
G02X716822Y305143I-1J-200D01*
G01X716843Y305108D01*
X716849Y305066D01*
G03X718338Y303769I1489J206D01*
G03X719830Y305087I0J1503D01*
G01Y305093D01*
X719838Y305142D01*
X719892Y305190D01*
G02X720024Y305239I131J-151D01*
G01X731058D01*
X731102Y305236D01*
X754422Y295575D01*
G02X754456Y295558I-72J-187D01*
G02X754488Y295531I-113J-166D01*
G01X808306Y241713D01*
G02X808363Y241592I-142J-141D01*
G01X808970Y235711D01*
G02X808971Y235679I-199J-22D01*
G01X806762Y198851D01*
G03X806758Y198713I2322J-136D01*
G01Y198711D01*
G03X806759Y198629I2326J-13D01*
G01X807838Y168383D01*
G03X807887Y167983I2325J82D01*
G02X807891Y167955I-196J-42D01*
G01Y167954D01*
G03X807893Y167929I2286J170D01*
G01X807919Y167201D01*
G03X807978Y167066I200J7D01*
G01X808499Y166545D01*
G02X808503Y166541I-139J-143D01*
G03X808558Y166484I1677J1563D01*
G01X824696Y150346D01*
X824711Y150304D01*
G03X824934Y149848I2189J788D01*
G02X824965Y149741I-169J-107D01*
G01Y149457D01*
G03X825024Y149315I200J0D01*
G01X825557Y148782D01*
G03X825580Y148757I1699J1540D01*
G03X825657Y148679I1670J1572D01*
G02X825659Y148677I-140J-142D01*
G01X826866Y147471D01*
G03X826924Y147415I1621J1621D01*
G02X826928Y147411I-139J-143D01*
G01X827479Y146860D01*
G03X827621Y146801I142J141D01*
G01X827988D01*
G02X828130Y146742I0J-200D01*
G01X828132Y146740D01*
Y146290D01*
G03X828191Y146148I200J0D01*
G01X828795Y145544D01*
G03X828803Y145536I1624J1616D01*
G01X830034Y144305D01*
G03X830043Y144296I1625J1616D01*
G01X830646Y143693D01*
G03X830788Y143634I142J141D01*
G01X831193D01*
X831274Y143595D01*
X831298Y143565D01*
Y141748D01*
G02X831268Y141643I-200J0D01*
G03X830914Y140410I1972J-1234D01*
G01Y139392D01*
G02X830855Y139250I-200J0D01*
G01X830830Y139225D01*
X830800Y139152D01*
Y138490D01*
G02X830799Y138467I-200J-3D01*
G01Y137936D01*
X830800Y137925D01*
Y135640D01*
G03X830859Y135498I200J0D01*
G01X830884Y135473D01*
X830914Y135400D01*
Y134914D01*
G02X830855Y134772I-200J0D01*
G01X830830Y134747D01*
X830800Y134674D01*
Y131162D01*
G03X830859Y131020I200J0D01*
G01X830885Y130994D01*
X830915Y130917D01*
X830914Y130876D01*
Y130436D01*
G02X830855Y130294I-200J0D01*
G01X830830Y130269D01*
X830800Y130196D01*
Y126684D01*
G03X830859Y126542I200J0D01*
G01X830882Y126519D01*
G02X830938Y126348I-142J-141D01*
G03X830914Y126009I2302J-333D01*
G01Y125958D01*
G02X830855Y125816I-200J0D01*
G01X830830Y125791D01*
X830800Y125718D01*
Y122206D01*
G03X830859Y122064I200J0D01*
G01X830936Y121987D01*
G02X830988Y121795I-141J-141D01*
G03X830929Y121473I2253J-579D01*
G01X830925Y121439D01*
X830896Y121379D01*
X830859Y121342D01*
G03X830800Y121200I141J-142D01*
G01Y117728D01*
G03X830859Y117586I200J0D01*
G01X831014Y117431D01*
G02X831060Y117221I-142J-141D01*
G01Y117220D01*
G03X831001Y117042I2177J-820D01*
G01X830994Y117017D01*
X830969Y116974D01*
X830859Y116864D01*
G03X830800Y116722I141J-142D01*
G01Y113250D01*
G03X830859Y113108I200J0D01*
G01X831191Y112776D01*
Y112718D01*
X830859Y112386D01*
G03X830800Y112244I141J-142D01*
G01Y110104D01*
G02X830798Y110073I-200J-3D01*
G02X830737Y109958I-198J31D01*
G03X830635Y109943I288J-2310D01*
G01X830602Y109940D01*
X830163D01*
G03X830021Y109881I0J-200D01*
G01X829711Y109571D01*
G02X829685Y109549I-142J141D01*
G03X829129Y108993I1344J-1900D01*
G02X829107Y108967I-163J116D01*
G01X828797Y108657D01*
G03X828738Y108515I141J-142D01*
G01Y108076D01*
X828735Y108043D01*
G03X828702Y107649I2294J-391D01*
G03X828735Y107255I2327J-3D01*
G01X828738Y107222D01*
Y106783D01*
G03X828797Y106641I200J0D01*
G01X829107Y106331D01*
G02X829129Y106305I-141J-142D01*
G03X829224Y106179I1905J1337D01*
G01X829226Y106177D01*
Y105788D01*
G02X829185Y105667I-200J0D01*
G03X828702Y104249I1844J-1419D01*
G03X831029Y101922I2327J0D01*
G03X832674Y102604I-1J2327D01*
G01X833085Y103015D01*
G02X833227Y103074I142J-141D01*
G01X833401D01*
G03X835046Y103755I0J2327D01*
G01X836445Y105154D01*
G03X837126Y106799I-1646J1645D01*
G01Y145399D01*
G03X836445Y147044I-2327J0D01*
G01X813605Y169884D01*
G02X813546Y170019I141J142D01*
G01X812539Y198267D01*
G02X812540Y198287I200J0D01*
G01X813957Y221927D01*
X814801Y236008D01*
X814802Y236010D01*
Y236022D01*
X814803Y236032D01*
Y236044D01*
X814804Y236056D01*
Y236068D01*
G03X814805Y236089I-2288J119D01*
G01Y236104D01*
G03X814806Y236147I-2290J75D01*
G01Y236149D01*
G03X814802Y236277I-2292J-8D01*
G03X814801Y236292I-2287J-145D01*
G03X814794Y236373I-2286J-157D01*
G01Y236375D01*
X814793Y236387D01*
X814089Y243214D01*
G03X813896Y243927I-2279J-234D01*
G01X813885Y243958D01*
G03X813280Y245010I-2250J-594D01*
G01X785193Y273097D01*
G02X785134Y273239I141J142D01*
G01Y276661D01*
G02X785135Y276680I200J-1D01*
G01Y276681D01*
G02X785174Y276779I199J-22D01*
G02X785192Y276800I160J-119D01*
G01X786649Y278257D01*
G02X786769Y278315I142J-141D01*
G01X786780Y278316D01*
X848618D01*
G02X848702Y278297I-1J-200D01*
G01X848815Y278245D01*
X848843Y278214D01*
X848844Y278213D01*
G03X851094I1125J995D01*
G01X851095Y278214D01*
X851123Y278245D01*
X851236Y278297D01*
G02X851320Y278316I85J-181D01*
G01X905609D01*
G02X905791Y278198I0J-200D01*
G01X905941Y277865D01*
G02X905959Y277783I-182J-83D01*
G01X905909Y277651D01*
G03X909497Y270006I3451J-3045D01*
G02X909509I6J-200D01*
G03X913130Y277624I146J4600D01*
G01X913126Y277628D01*
X913106Y277652D01*
X913078Y277726D01*
G03X913077Y277728I-179J-88D01*
G01X913063Y277765D01*
Y277803D01*
G02X913081Y277883I200J-3D01*
G01X913224Y278198D01*
G02X913226Y278203I187J-72D01*
G03X913228Y278205I-133J135D01*
G02X913406Y278316I179J-89D01*
G01X920096D01*
X920207Y278224D01*
X920220Y278153D01*
G03X923335Y275571I3115J588D01*
G03X926217Y277422I0J3169D01*
G02X926221Y277430I181J-85D01*
G03X926474Y278155I-2590J1310D01*
G01Y278158D01*
G02X926544Y278272I196J-42D01*
G01X926570Y278293D01*
X926634Y278316D01*
X940332D01*
G02X940419Y278289I-14J-200D01*
G01X940502Y278239D01*
G02X940537Y278213I-101J-172D01*
G01X940556Y278195D01*
X940569Y278173D01*
G03X943121I1276J795D01*
G01X943134Y278195D01*
X943153Y278213D01*
G02X943188Y278239I136J-146D01*
G01X943269Y278288D01*
G02X943358Y278316I103J-172D01*
G01X998244D01*
G02X998424Y278197I-3J-200D01*
G01X998427Y278189D01*
G03X1001225Y278188I1399J544D01*
G01Y278190D01*
G02X1001299Y278282I186J-74D01*
G01X1001323Y278299D01*
X1001380Y278316D01*
X1063714D01*
G03X1063856Y278375I0J200D01*
G01X1077889Y292408D01*
X1077923Y292423D01*
G03X1078687Y293187I-609J1373D01*
G01X1078702Y293221D01*
X1081401Y295919D01*
G02X1081469Y295964I142J-141D01*
G01X1223687D01*
G02X1223755Y295919I-74J-186D01*
G01X1224511Y295163D01*
G03X1224653Y295104I142J141D01*
G01X1250236D01*
G03X1250378Y295163I0J200D01*
G01X1260395Y305180D01*
G02X1260515Y305238I142J-141D01*
G01X1260526Y305239D01*
X1264121D01*
G02X1264140Y305238I-1J-200D01*
G01X1264141D01*
G02X1264239Y305199I-22J-199D01*
G02X1264260Y305181I-119J-160D01*
G01X1265525Y303916D01*
G02X1265583Y303796I-141J-142D01*
G01X1265584Y303785D01*
Y302828D01*
G02X1265582Y302800I-200J0D01*
G01X1265572Y302747D01*
X1265567Y302727D01*
X1265563Y302718D01*
X1265561Y302714D01*
Y302713D01*
G03X1265460Y302182I1402J-542D01*
G01Y302141D01*
G03X1265781Y301239I1502J26D01*
G01X1265802Y301212D01*
X1265813Y301181D01*
G02X1265824Y301116I-189J-65D01*
G01Y301017D01*
G03X1265834Y300956I200J1D01*
G01X1265853Y300895D01*
G02X1265863Y300827I-190J-63D01*
G01X1265861Y300776D01*
G02X1265858Y300748I-200J7D01*
G01X1236346Y271236D01*
G02X1236281Y271193I-141J142D01*
G01X1220927Y264832D01*
G02X1220859Y264872I65J189D01*
G02X1220852Y264878I127J155D01*
G01X1220732Y264995D01*
X1220700Y265027D01*
G02X1220639Y265168I139J144D01*
G01Y265221D01*
X1220658Y265271D01*
X1220671Y265306D01*
G03X1220781Y265895I-1527J590D01*
G01Y265897D01*
G03X1219144Y267534I-1637J0D01*
G03X1218109Y267166I0J-1639D01*
G01X1218083Y267145D01*
X1217985Y267108D01*
G02X1217919Y267097I-65J189D01*
G01X1217869D01*
G02X1217803Y267108I-1J200D01*
G01X1217705Y267145D01*
X1217679Y267166D01*
G03X1216645Y267534I-1034J-1269D01*
G01X1216644D01*
G03X1215007Y265897I0J-1637D01*
G03X1215653Y264594I1637J0D01*
G01X1215670Y264581D01*
X1215690Y264557D01*
G02X1215724Y264381I-159J-122D01*
G01X1215598Y264007D01*
G02X1215543Y263926I-188J68D01*
G01X1195463D01*
G02X1195407Y264006I131J151D01*
G01X1195342Y264179D01*
Y264181D01*
X1195275Y264353D01*
G02X1195263Y264420I188J68D01*
G01Y264425D01*
G02X1195303Y264545I200J0D01*
G01X1195315Y264561D01*
X1195330Y264575D01*
G03X1195837Y265700I-995J1125D01*
G01Y265748D01*
X1195835Y265775D01*
Y265777D01*
G03X1194335Y267203I-1500J-76D01*
G03X1192843Y265877I0J-1502D01*
G01X1192837Y265820D01*
G03X1192832Y265701I1498J-123D01*
G01Y265621D01*
X1192837Y265574D01*
G03X1193340Y264575I1497J127D01*
G01X1193363Y264555D01*
X1193395Y264503D01*
X1193402Y264473D01*
G02X1193395Y264357I-195J-46D01*
G01X1193337Y264203D01*
Y264201D01*
X1193262Y264005D01*
G02X1193207Y263926I-187J71D01*
G01X1181226D01*
X1181225Y263927D01*
X1181213Y263937D01*
X1181182Y263967D01*
X1181178Y263971D01*
X1181156Y263992D01*
G02X1181095Y264136I139J144D01*
G01Y264148D01*
G03X1181096Y264179I-1635J68D01*
G01Y264181D01*
G03X1179459Y265817I-1637J-1D01*
G03X1178334Y265370I0J-1639D01*
G01X1178330Y265366D01*
X1178276Y265316D01*
G02X1178147Y265268I-130J152D01*
G01X1178090D01*
G02X1178055Y265271I0J200D01*
G01X1178004Y265280D01*
X1177968Y265293D01*
X1177940Y265317D01*
G03X1176959Y265682I-981J-1136D01*
G03X1175459Y264256I0J-1502D01*
G01X1175457Y264217D01*
X1175441Y264183D01*
G02X1175397Y264122I-181J84D01*
G01X1175222Y263955D01*
X1175220Y263953D01*
X1175193Y263929D01*
G02X1175190Y263926I-143J140D01*
G01X1093101D01*
G02X1093045Y264006I131J151D01*
G01X1092980Y264179D01*
Y264181D01*
X1092913Y264353D01*
G02X1092901Y264420I188J68D01*
G01Y264425D01*
G02X1092941Y264545I200J0D01*
G01X1092953Y264561D01*
X1092968Y264575D01*
G03X1093475Y265700I-995J1125D01*
G01Y265748D01*
X1093473Y265775D01*
Y265777D01*
G03X1091973Y267203I-1500J-76D01*
G03X1090481Y265877I0J-1502D01*
G01X1090475Y265820D01*
G03X1090470Y265701I1498J-123D01*
G01Y265621D01*
X1090475Y265574D01*
G03X1090978Y264575I1497J127D01*
G01X1091001Y264555D01*
X1091033Y264503D01*
X1091040Y264473D01*
G02X1091033Y264357I-195J-46D01*
G01X1090975Y264203D01*
Y264201D01*
X1090900Y264005D01*
G02X1090845Y263926I-187J71D01*
G01X1089300D01*
G03X1087655Y263245I0J-2327D01*
G01X1061255Y236845D01*
G03X1060574Y235200I1646J-1645D01*
G01Y222309D01*
X1059283Y200782D01*
X1059282Y200778D01*
G03X1059281Y200763I2285J-160D01*
G01X1059280Y200739D01*
Y200734D01*
G03X1059278Y200681I2289J-113D01*
G01Y200628D01*
G03X1059331Y200158I2292J20D01*
G01X1060420Y195172D01*
G02X1060424Y195134I-196J-40D01*
G01Y187397D01*
G02X1060365Y187255I-200J0D01*
G01X1025508Y152398D01*
X1025454Y152369D01*
X1025424Y152364D01*
G03X1024193Y151720I414J-2289D01*
G01X1022813Y150340D01*
G03X1022169Y149110I1645J-1645D01*
G01X1022114Y149004D01*
X1022089Y148979D01*
G03X1020798Y148325I354J-2299D01*
G01X1019418Y146945D01*
G03X1018774Y145715I1645J-1645D01*
G01X1018719Y145609D01*
X1018694Y145584D01*
G03X1017403Y144930I354J-2299D01*
G01X1016023Y143550D01*
G03X1015379Y142320I1645J-1645D01*
G01X1015324Y142214D01*
X1015299Y142189D01*
G03X1014008Y141535I354J-2299D01*
G01X1012628Y140155D01*
G03X1011984Y138925I1645J-1645D01*
G01X1011929Y138819D01*
X1011904Y138794D01*
G03X1010613Y138140I354J-2299D01*
G01X1009233Y136760D01*
G03X1008589Y135529I1645J-1645D01*
G01X1008584Y135499D01*
X1008555Y135445D01*
X1007855Y134745D01*
G03X1007174Y133100I1646J-1645D01*
G01Y131072D01*
X1007154Y130985D01*
G03X1006924Y129985I2064J-1001D01*
G01Y128545D01*
G03X1007153Y127546I2294J0D01*
G01X1007163Y127526D01*
X1007174Y127481D01*
Y126512D01*
X1007154Y126425D01*
G03X1007142Y126399I2075J-973D01*
G03X1007052Y126177I2076J-971D01*
G01X1007048Y126165D01*
X1007039Y126137D01*
X1007036Y126132D01*
G03X1007026Y126099I186J-74D01*
G03X1007025Y126096I188J-64D01*
G01X1007024Y126088D01*
X1007012Y126047D01*
X1007006Y126029D01*
X1006996Y125990D01*
X1006995Y125985D01*
X1006988Y125956D01*
G03X1006962Y125832I2229J-532D01*
G01Y125831D01*
X1006959Y125815D01*
G03X1006936Y125633I2261J-378D01*
G03X1006933Y125595I2283J-199D01*
G01Y125581D01*
G03X1006928Y125431I2286J-151D01*
G01Y123684D01*
G03X1007154Y122697I2291J5D01*
G01Y122696D01*
G03X1007165Y122674I2055J1014D01*
G01X1007174Y122656D01*
Y122247D01*
G02X1007115Y122105I-200J0D01*
G01X1006732Y121722D01*
G02X1006582Y121713I-86J181D01*
G01X1006530Y121732D01*
G03X1006338Y121677I534J-2228D01*
G03X1005841Y121441I727J-2173D01*
G03X1005444Y121123I1225J-1936D01*
G01X1004213Y119892D01*
G03X1004108Y119781I1611J-1629D01*
G01X1004101Y119773D01*
X1004099Y119771D01*
X1004096Y119767D01*
X1004089Y119759D01*
G03X1003905Y119512I1742J-1490D01*
G01X1003883Y119478D01*
X1003876Y119465D01*
X1003873Y119460D01*
G03X1003788Y119308I1956J-1194D01*
G01X1003782Y119296D01*
X1003763Y119257D01*
X1003758Y119243D01*
X1003755Y119237D01*
X1003750Y119228D01*
G03X1003745Y119218I2045J-1029D01*
G01X1003736Y119197D01*
G03X1003718Y119153I2111J-889D01*
G02X1003716Y119151I-142J140D01*
G03X1003706Y119126I2123J-864D01*
G02X1003611Y119022I-186J74D01*
G01X1003578Y119005D01*
X1003507Y118997D01*
X1003442Y119014D01*
X1003434Y119016D01*
G03X1003071Y119059I-357J-1459D01*
G01X1003046D01*
G03X1002945Y119054I24J-1502D01*
G01X1002937Y119053D01*
X1002936D01*
G03X1002866Y119045I136J-1496D01*
G01X1002853Y119043D01*
X1002852D01*
X1002803Y119036D01*
X1002723Y119059D01*
X1002691Y119085D01*
G03X1002675Y119097I-125J-150D01*
G01X1002663Y119104D01*
X1002630Y119132D01*
X1002452Y119284D01*
G02X1002386Y119397I130J152D01*
G02X1002382Y119436I196J40D01*
G01Y121735D01*
G03X998778I-1802J0D01*
G01Y120091D01*
X998777Y118335D01*
G03X1000569Y116532I1803J0D01*
G01X1000591D01*
G02X1000760Y116439I0J-200D01*
G02X1000775Y116410I-170J-106D01*
G01X1000902Y116108D01*
G02X1000907Y116094I-186J-74D01*
G01X1000932Y116020D01*
G02X1000915Y115906I-198J-29D01*
G01X1000540Y115530D01*
X1000506Y115516D01*
X1000494Y115514D01*
X1000464Y115510D01*
G03X999218Y114899I339J-2268D01*
G03X999161Y114842I1592J-1649D01*
G02X999159Y114840I-142J140D01*
G01X997951Y113632D01*
G03X997438Y112846I1622J-1619D01*
G03X997344Y112550I2132J-840D01*
G01Y112549D01*
X997331Y112498D01*
G02X997285Y112426I-188J69D01*
G01X995599D01*
G03X994634Y112216I1J-2326D01*
G02X994624Y112212I-79J184D01*
G03X993834Y111699I826J-2137D01*
G01X993830Y111695D01*
X993822Y111688D01*
G02X993725Y111634I-142J141D01*
G01X993698Y111628D01*
X993645Y111631D01*
X993557Y111661D01*
X993533Y111678D01*
G03X993516Y111690I-875J-1221D01*
G03X993494Y111705I-857J-1234D01*
G01X993491Y111707D01*
X993329Y111817D01*
X993282Y111849D01*
X992069Y112673D01*
X992067D01*
X992047Y112687D01*
X992014Y112723D01*
X992003Y112744D01*
G02X991980Y112838I177J93D01*
G01Y114623D01*
G03X988376I-1802J0D01*
G01Y111221D01*
G03X988432Y110776I1802J1D01*
G01X988443Y110733D01*
X988435Y110692D01*
G02X988405Y110617I-197J35D01*
G01X988242Y110372D01*
G02X988139Y110293I-167J111D01*
G01X988104Y110282D01*
X988088Y110279D01*
X988085D01*
G03X986822Y109635I358J-2263D01*
G01X986026Y108839D01*
G02X986016Y108830I-139J144D01*
G01X983221D01*
G02X983079Y108889I0J200D01*
G01X982674Y109294D01*
G03X981029Y109976I-1646J-1645D01*
G03X978702Y107649I0J-2327D01*
G03X979185Y106231I2327J1D01*
G01Y106230D01*
X979205Y106204D01*
X979226Y106143D01*
Y105788D01*
G02X979185Y105667I-200J0D01*
G03X978702Y104249I1844J-1419D01*
G03X981029Y101922I2327J0D01*
G03X982674Y102604I-1J2327D01*
G01X983079Y103009D01*
G02X983221Y103068I142J-141D01*
G01X987565D01*
G03X988831Y103443I0J2326D01*
G01X988870Y103468D01*
X988961Y103479D01*
X989082Y103437D01*
X989088Y103435D01*
G02X989145Y103401I-73J-186D01*
G01X989206Y103343D01*
G02X989237Y103305I-138J-144D01*
G01X989250Y103285D01*
X989258Y103262D01*
G03X990833Y102124I1575J521D01*
G03X992492Y103783I0J1659D01*
G03X992413Y104283I-1658J-6D01*
G01X992403Y104315D01*
X992404Y104348D01*
Y104380D01*
X992414Y104410D01*
G02X992446Y104470I190J-63D01*
G01X992454Y104480D01*
X992518Y104561D01*
G02X992520Y104564I167J-109D01*
G01X993960D01*
G03X995605Y105245I0J2327D01*
G01X995962Y105602D01*
G02X996137Y105658I142J-141D01*
G01X996155Y105655D01*
X996255Y105638D01*
G02X996265Y105636I-34J-197D01*
G02X996318Y105616I-43J-195D01*
G02X996363Y105582I-97J-175D01*
G01X996417Y105528D01*
X996424Y105514D01*
X996432Y105499D01*
G03X997768Y104684I1336J688D01*
G03X999270Y106186I0J1502D01*
G01Y106190D01*
G03X999246Y106457I-1502J0D01*
G01X999244Y106467D01*
X999236Y106512D01*
X999255Y106592D01*
X999280Y106625D01*
X999289Y106640D01*
G02X999411Y106730I171J-104D01*
G01X999412D01*
G03X1000505Y107345I-552J2260D01*
G01X1012255Y119095D01*
G03X1012703Y119724I-1645J1645D01*
G02X1012716Y119747I180J-87D01*
G03X1013091Y121003I-1918J1257D01*
G01Y121004D01*
G03X1013090Y121056I-2293J-18D01*
G01Y131653D01*
G02X1013094Y131691I200J-2D01*
G02X1013147Y131793I196J-37D01*
G01X1065416Y184062D01*
G03X1065762Y184504I-1618J1623D01*
G01X1065781Y184531D01*
G03X1066336Y186038I-1771J1508D01*
G01Y223801D01*
X1066472Y226063D01*
X1066744Y230598D01*
X1066967Y234313D01*
G02X1067024Y234429I198J-26D01*
G01X1090698Y258103D01*
G02X1090840Y258162I142J-141D01*
G01X1096084D01*
G02X1096272Y258030I0J-200D01*
G01X1096399Y257678D01*
G02X1096411Y257610I-188J-68D01*
G01X1096339Y257456D01*
G03X1095799Y256303I961J-1153D01*
G03X1098803I1502J0D01*
G03X1098263Y257456I-1501J0D01*
G01X1098191Y257610D01*
G02X1098203Y257678I200J0D01*
G01X1098330Y258030D01*
G02X1098518Y258162I188J-68D01*
G01X1175268D01*
G02X1175275Y258156I-127J-155D01*
G01X1175296Y258136D01*
X1175473Y257968D01*
G02X1175517Y257907I-137J-145D01*
G01X1175533Y257873D01*
X1175535Y257831D01*
G03X1177035Y256417I1500J89D01*
G03X1178535Y257834I0J1502D01*
G01X1178536Y257850D01*
X1178537Y257873D01*
X1178553Y257907D01*
G02X1178598Y257970I182J-82D01*
G01X1178773Y258135D01*
X1178795Y258157D01*
G02X1178800Y258162I144J-139D01*
G01X1198446D01*
G02X1198634Y258030I0J-200D01*
G01X1198783Y257618D01*
X1198750Y257497D01*
X1198728Y257479D01*
G03X1198161Y256313I935J-1176D01*
G01Y256302D01*
G03X1198245Y255808I1502J1D01*
G02X1198256Y255742I-189J-65D01*
G01Y255713D01*
X1198245Y255679D01*
G02X1198222Y255630I-191J60D01*
G01X1198195Y255592D01*
X1198029Y255360D01*
G02X1197998Y255326I-162J117D01*
G01X1186030D01*
G03X1184385Y254645I0J-2327D01*
G01X1174533Y244793D01*
G02X1174468Y244750I-141J142D01*
G01X1168771Y242397D01*
G03X1167781Y241610I876J-2118D01*
G01X1164137Y236502D01*
G03X1163715Y235308I1865J-1331D01*
G01X1163635Y233966D01*
G02X1163576Y233836I-200J12D01*
G01X1163555Y233815D01*
G03X1162874Y232170I1646J-1645D01*
G01Y221282D01*
X1160735Y185631D01*
G02X1160732Y185607I-200J13D01*
G02X1160724Y185576I-197J34D01*
G01X1160470Y184850D01*
X1159825Y183013D01*
X1158964Y180557D01*
X1158707Y179825D01*
G02X1158660Y179750I-189J66D01*
G01X1127803Y148893D01*
X1127749Y148864D01*
X1127719Y148859D01*
G03X1126488Y148215I414J-2289D01*
G01X1125108Y146835D01*
G03X1124464Y145605I1645J-1645D01*
G01X1124409Y145499D01*
X1124384Y145474D01*
G03X1123093Y144820I354J-2299D01*
G01X1121713Y143440D01*
G03X1121069Y142210I1645J-1645D01*
G01X1121014Y142104D01*
X1120989Y142079D01*
G03X1119698Y141425I354J-2299D01*
G01X1118318Y140045D01*
G03X1117674Y138815I1645J-1645D01*
G01X1117619Y138709D01*
X1117594Y138684D01*
G03X1116303Y138030I354J-2299D01*
G01X1114923Y136650D01*
G03X1114279Y135419I1645J-1645D01*
G01X1114274Y135389D01*
X1114245Y135335D01*
X1113545Y134635D01*
G03X1112864Y132990I1646J-1645D01*
G01Y123675D01*
G02X1112788Y123628I-141J142D01*
G01X1112751Y123619D01*
G03X1111659Y123009I529J-2229D01*
G01X1110428Y121778D01*
G03X1109796Y120584I1619J-1621D01*
G01X1109789Y120549D01*
X1109208Y119968D01*
X1109186Y119964D01*
G03X1107956Y119308I413J-2255D01*
G02X1107954Y119306I-142J140D01*
G01X1106746Y118098D01*
G03X1106113Y116896I1621J-1621D01*
G01X1106107Y116867D01*
X1104740Y115500D01*
X1104718Y115496D01*
G03X1103488Y114840I413J-2255D01*
G02X1103486Y114838I-142J140D01*
G01X1102278Y113630D01*
G03X1101765Y112844I1622J-1619D01*
G03X1101678Y112577I2132J-842D01*
G01X1101656Y112492D01*
G02X1101614Y112426I-186J72D01*
G01X1098497D01*
G03X1096995Y111875I1J-2327D01*
G01X1096990Y111871D01*
G03X1096791Y111693I1426J-1794D01*
G01X1096012Y110915D01*
X1095182Y110085D01*
G02X1095040Y110026I-142J141D01*
G01X1094351D01*
X1094334Y110053D01*
X1094281Y110136D01*
X1094209Y110249D01*
G02X1094177Y110357I168J108D01*
G01Y110465D01*
X1094194Y110503D01*
G03X1094209Y110540I-1663J696D01*
G01Y110541D01*
G03X1094218Y110563I-1664J693D01*
G01X1094223Y110576D01*
G03X1094234Y110605I-1680J654D01*
G01Y110606D01*
G03X1094236Y110611I-1672J672D01*
G01X1094248Y110644D01*
X1094253Y110662D01*
X1094255Y110667D01*
G03X1094262Y110689I-1714J557D01*
G01Y110690D01*
X1094270Y110717D01*
G03X1094342Y111220I-1730J504D01*
G01Y114623D01*
G03X1090738I-1802J0D01*
G01Y111223D01*
G03X1090750Y111011I1802J-4D01*
G03X1090760Y110938I1790J208D01*
G03X1090793Y110778I1780J284D01*
G03X1090820Y110681I1749J435D01*
G01X1090833Y110640D01*
X1090834Y110636D01*
G03X1090840Y110618I193J54D01*
G03X1090842Y110614I180J87D01*
G02X1090850Y110595I-180J-87D01*
G03X1090854Y110584I1696J611D01*
G01X1090855D01*
X1090865Y110556D01*
X1090866Y110553D01*
G03X1090871Y110540I1685J641D01*
G01X1090876Y110528D01*
X1090879Y110521D01*
X1090880Y110519D01*
G03X1090882Y110514I1671J666D01*
G01X1090887Y110500D01*
X1090888Y110498D01*
X1090903Y110462D01*
Y110357D01*
G02X1090871Y110249I-200J0D01*
G01X1090787Y110118D01*
G02X1090619Y110026I-168J108D01*
G01X1090397D01*
G03X1089282Y109740I2J-2326D01*
G02X1089262Y109731I-92J178D01*
G03X1088510Y109230I870J-2120D01*
G01X1088500Y109220D01*
X1088120Y108839D01*
G02X1088110Y108830I-139J144D01*
G01X1085583D01*
G02X1085441Y108889I0J200D01*
G01X1085036Y109294D01*
G03X1083391Y109976I-1646J-1645D01*
G03X1081064Y107649I0J-2327D01*
G03X1081547Y106231I2327J1D01*
G01Y106230D01*
X1081567Y106204D01*
X1081588Y106143D01*
Y105788D01*
G02X1081547Y105667I-200J0D01*
G03X1081064Y104249I1844J-1419D01*
G03X1083391Y101922I2327J0D01*
G03X1085036Y102604I-1J2327D01*
G01X1085441Y103009D01*
G02X1085583Y103068I142J-141D01*
G01X1089664D01*
G03X1091309Y103749I0J2327D01*
G01X1091357Y103797D01*
G02X1091639I141J-142D01*
G01X1091665Y103771D01*
X1091695Y103706D01*
X1091697Y103670D01*
G03X1092002Y102870I1498J113D01*
G03X1094697Y103782I1193J913D01*
G01Y103817D01*
X1094695Y103860D01*
X1094707Y103895D01*
G02X1094752Y103969I189J-64D01*
G01X1094852Y104074D01*
X1094853Y104075D01*
X1094891Y104114D01*
X1094892Y104115D01*
X1094957Y104181D01*
X1094964Y104187D01*
G02X1095097Y104238I133J-149D01*
G01X1096398D01*
G03X1096822Y104278I-2J2292D01*
G02X1096836Y104280I35J-197D01*
G03X1098205Y104945I-276J2310D01*
G01X1098518Y105258D01*
G02X1098668Y105316I141J-142D01*
G01X1098803Y105310D01*
X1098804D01*
X1098860Y105308D01*
X1098899Y105288D01*
X1098939Y105269D01*
X1098968Y105234D01*
G03X1100130Y104684I1162J952D01*
G03X1101632Y106186I0J1502D01*
G03X1101629Y106276I-1502J-5D01*
G01Y106280D01*
X1101627Y106316D01*
X1101640Y106353D01*
G02X1101680Y106421I189J-65D01*
G01X1101720Y106466D01*
G02X1101723Y106469I143J-140D01*
G01X1101869Y106624D01*
X1101882Y106638D01*
G02X1101911Y106664I147J-135D01*
G01X1103090D01*
G03X1104735Y107345I0J2327D01*
G01X1109468Y112078D01*
G02X1109539Y112091I71J-187D01*
G01X1109571D01*
X1109874Y111995D01*
X1109875D01*
X1109881Y111993D01*
X1109885Y111992D01*
G03X1109893Y111990I53J193D01*
G03X1109903Y111988I44J195D01*
G01X1109935Y111982D01*
X1109960Y111969D01*
G02X1110010Y111933I-90J-178D01*
G01X1110020Y111923D01*
G02X1110056Y111873I-142J-141D01*
G01X1110069Y111846D01*
X1110074Y111818D01*
G03X1111553Y110581I1479J266D01*
G03X1113055Y112083I0J1502D01*
G03X1111816Y113562I-1502J0D01*
G01X1111789Y113567D01*
X1111740Y113591D01*
X1111719Y113609D01*
G02X1111660Y113699I132J151D01*
G01X1111552Y114044D01*
G02X1111557Y114166I193J53D01*
G01X1117945Y120555D01*
G03X1118626Y122200I-1646J1645D01*
G01Y131530D01*
G02X1118645Y131552I160J-119D01*
G01X1163146Y176053D01*
G03X1163352Y176289I-1619J1621D01*
G01X1163359Y176299D01*
X1167955Y180895D01*
G03X1168636Y182540I-1646J1645D01*
G01Y222767D01*
X1168959Y228144D01*
X1169141Y231180D01*
G02X1169200Y231310I200J-12D01*
G01X1187395Y249505D01*
G02X1187537Y249564I142J-141D01*
G01X1205772D01*
G02X1205797Y249538I-131J-151D01*
G01X1205846Y249475D01*
Y249473D01*
X1205883Y249427D01*
G02X1205910Y249382I-156J-124D01*
G02X1205914Y249374I-176J-93D01*
G01X1205918Y249362D01*
G02X1205925Y249270I-191J-61D01*
G01X1205921Y249242D01*
X1205917Y249228D01*
G03X1205850Y248766I1570J-464D01*
G01Y248765D01*
G03X1207487Y247128I1637J0D01*
G03X1208522Y247496I0J1639D01*
G01X1208548Y247517D01*
X1208646Y247554D01*
G02X1208712Y247565I65J-189D01*
G01X1208762D01*
G02X1208828Y247554I1J-200D01*
G01X1208926Y247517D01*
X1208952Y247496D01*
G03X1209986Y247128I1034J1269D01*
G01X1209987D01*
G03X1211112Y247575I0J1639D01*
G01X1211116Y247579D01*
X1211170Y247629D01*
G02X1211299Y247677I130J-152D01*
G01X1211356D01*
G02X1211391Y247674I0J-200D01*
G01X1211441Y247665D01*
X1211442D01*
X1211478Y247652D01*
X1211506Y247628D01*
G03X1212487Y247263I981J1136D01*
G03X1213989Y248751I0J1502D01*
G01Y248766D01*
G03X1213840Y249417I-1502J-1D01*
G02X1213826Y249458I181J85D01*
G01X1213810Y249526D01*
G02X1213820Y249587I200J-1D01*
G01X1213858Y249690D01*
Y249692D01*
X1213929Y249879D01*
G02X1214002Y249965I183J-81D01*
G01X1214017Y249974D01*
G02X1214028Y249979I88J-180D01*
G01X1245035Y262824D01*
G03X1245278Y262942I-878J2117D01*
G01X1245283Y262944D01*
G03X1246038Y263448I-889J2150D01*
G01X1254998Y272408D01*
G02X1255095Y272355I-44J-195D01*
G01X1257145Y270305D01*
X1257350Y270101D01*
G03X1258970Y269430I1620J1620D01*
G01X1260581D01*
X1260588Y269429D01*
X1260603D01*
G03X1260673Y269428I68J2291D01*
G01X1260686D01*
G03X1261231Y269495I-5J2291D01*
G03X1261818Y269730I-550J2224D01*
G03X1262303Y270100I-1135J1991D01*
G01X1263120Y270917D01*
X1264659Y272457D01*
G03X1265330Y274076I-1620J1620D01*
G01X1265331Y275790D01*
Y275791D01*
G03X1264660Y277411I-2291J0D01*
G01X1264456Y277616D01*
X1262406Y279666D01*
G02X1262353Y279763I142J141D01*
G01X1278763Y296173D01*
G02X1278905Y296232I142J-141D01*
G01X1317633D01*
G02X1317833Y296032I0J-200D01*
G01Y267885D01*
G02X1317811Y267794I-200J0D01*
G02X1317775Y267744I-178J90D01*
G01X1312676Y262645D01*
G02X1312614Y262603I-141J142D01*
G01X1312582Y262589D01*
X1312542Y262587D01*
G03X1310999Y261917I77J-2290D01*
G01X1309787Y260705D01*
G03X1309116Y259085I1620J-1620D01*
G01Y255536D01*
G02X1308916Y255336I-200J0D01*
G01X1303841D01*
G02X1303721Y255376I0J200D01*
G01X1303690Y255407D01*
G02X1303670Y255430I141J142D01*
G01X1303500Y255662D01*
G02X1303463Y255749I160J120D01*
G01X1303456Y255794D01*
X1303471Y255841D01*
G03X1303543Y256303I-1446J462D01*
G03X1300507I-1518J0D01*
G03X1300579Y255841I1518J0D01*
G01Y255840D01*
G02X1300586Y255747I-190J-61D01*
G01X1300579Y255702D01*
X1300466Y255547D01*
X1300371Y255418D01*
X1300370Y255417D01*
X1300347Y255383D01*
X1300302Y255359D01*
G02X1300223Y255337I-92J177D01*
G02X1300209Y255336I-21J198D01*
G01X1280159D01*
G03X1279339Y255184I1J-2291D01*
G02X1279313Y255176I-72J187D01*
G03X1278195Y254555I527J-2266D01*
G01X1265145Y241505D01*
G03X1264464Y239860I1646J-1645D01*
G01Y208426D01*
X1264229Y204511D01*
X1264144Y203098D01*
G02X1264126Y203037I-198J25D01*
G01X1263176Y201339D01*
X1262932Y200905D01*
G02X1262924Y200892I-174J98D01*
G01X1255872Y190337D01*
G02X1255847Y190307I-165J112D01*
G01X1226996Y161456D01*
G02X1226796Y161406I-142J141D01*
G01X1226729Y161426D01*
X1226722Y161428D01*
X1226706Y161434D01*
G02X1226622Y161492I68J188D01*
G01X1226588Y161532D01*
X1226586Y161545D01*
X1226578Y161585D01*
G03X1225102Y162808I-1476J-279D01*
G03X1223600Y161306I0J-1502D01*
G03X1224821Y159830I1503J0D01*
G01X1224872Y159820D01*
X1224898Y159798D01*
X1224912Y159787D01*
G02X1224970Y159710I-126J-155D01*
G01X1224979Y159689D01*
X1224982Y159679D01*
X1224990Y159653D01*
X1225002Y159612D01*
G02X1224952Y159412I-191J-58D01*
G01X1223976Y158436D01*
G02X1223835Y158378I-141J142D01*
G01X1223513Y158377D01*
X1223440Y158408D01*
X1223412Y158436D01*
G03X1223237Y158584I-1055J-1070D01*
G01Y158587D01*
G03X1223176Y158629I-884J-1218D01*
G01X1223172Y158632D01*
G03X1222354Y158874I-818J-1263D01*
G01X1222353D01*
G03X1220849Y157370I0J-1504D01*
G03X1221406Y156201I1505J0D01*
G01X1221414Y156195D01*
X1221415Y156194D01*
X1221419Y156191D01*
G02X1221468Y156130I-129J-153D01*
G01X1221490Y156083D01*
G02X1221506Y156018I-183J-80D01*
G01X1221509Y155969D01*
X1218612Y153072D01*
G02X1218433Y153016I-142J141D01*
G01X1218393Y153024D01*
G02X1218303Y153066I37J196D01*
G01X1218282Y153083D01*
X1218253Y153122D01*
X1218243Y153145D01*
Y153146D01*
G03X1217074Y154049I-1385J-584D01*
G03X1215596Y153378I-216J-1487D01*
G01X1215595Y153377D01*
X1215591Y153371D01*
X1215588Y153367D01*
X1215576Y153347D01*
X1215556Y153327D01*
G02X1215523Y153300I-143J141D01*
G01X1215485Y153277D01*
X1215483Y153275D01*
X1215403Y153227D01*
X1215354Y153224D01*
X1215076Y153206D01*
X1215073D01*
X1215022Y153203D01*
X1214977Y153225D01*
G02X1214902Y153286I85J181D01*
G01X1214894Y153297D01*
X1214893Y153298D01*
X1214882Y153312D01*
G03X1213709Y153875I-1173J-941D01*
G01X1213708D01*
G03Y150871I0J-1502D01*
G03X1214967Y151552I0J1504D01*
G02X1214994Y151585I167J-109D01*
G01X1215026Y151616D01*
G02X1215059Y151642I139J-143D01*
G01X1215119Y151681D01*
G02X1215213Y151711I106J-170D01*
G01X1215483Y151729D01*
X1215502D01*
G02X1215605Y151700I-1J-200D01*
G01X1215613Y151696D01*
G02X1215643Y151671I-113J-166D01*
G01X1215659Y151655D01*
X1215668Y151643D01*
G03X1216295Y151169I1188J920D01*
G01X1216323Y151157D01*
X1216385Y151080D01*
X1216388Y151064D01*
X1216403Y150989D01*
G02X1216348Y150808I-196J-39D01*
G01X1215645Y150105D01*
G03X1214964Y148540I1644J-1646D01*
G01X1214961Y148511D01*
G03X1214924Y148103I2255J-410D01*
G01Y145418D01*
G02X1214919Y145374I-200J0D01*
G02X1214872Y145283I-195J43D01*
G01X1214848Y145258D01*
X1214716Y145120D01*
G02X1214581Y145058I-145J138D01*
G01X1214576D01*
G03X1213069Y143518I33J-1540D01*
G03X1214574Y141979I1539J0D01*
G01X1214613Y141978D01*
X1214650Y141963D01*
G02X1214717Y141916I-79J-184D01*
G01X1214869Y141755D01*
G02X1214924Y141617I-145J-138D01*
G01Y140990D01*
G02X1214892Y140882I-200J0D01*
G01Y140881D01*
G03X1214514Y139610I1948J-1271D01*
G01Y137660D01*
G03X1214892Y136390I2326J1D01*
G01Y136388D01*
X1214908Y136363D01*
X1214924Y136310D01*
Y136190D01*
G02X1214892Y136082I-200J0D01*
G01Y136081D01*
G03X1214514Y134810I1948J-1271D01*
G01Y132860D01*
G03X1214892Y131590I2326J1D01*
G01Y131588D01*
X1214908Y131563D01*
X1214924Y131510D01*
Y131390D01*
G02X1214892Y131282I-200J0D01*
G01Y131281D01*
G03X1214514Y130010I1948J-1271D01*
G01Y128060D01*
G03X1214892Y126790I2326J1D01*
G01Y126788D01*
X1214908Y126763D01*
X1214924Y126710D01*
Y126590D01*
G02X1214892Y126482I-200J0D01*
G01Y126481D01*
G03X1214514Y125210I1948J-1271D01*
G01Y123260D01*
G03X1214892Y121990I2326J1D01*
G01Y121988D01*
X1214908Y121963D01*
X1214924Y121910D01*
Y121867D01*
G02X1214865Y121725I-200J0D01*
G01X1213896Y120756D01*
X1213871Y120751D01*
G03X1212740Y120182I425J-2254D01*
G03X1212648Y120092I1557J-1684D01*
G01X1212644Y120088D01*
X1211655Y119098D01*
G03X1211029Y117936I1620J-1623D01*
G02X1210974Y117834I-196J40D01*
G01X1210264Y117124D01*
X1210220Y117115D01*
G03X1209024Y116466I446J-2249D01*
G02X1209022Y116464I-142J140D01*
G01X1207812Y115254D01*
G03X1207228Y114255I1623J-1619D01*
G01Y114253D01*
X1207217Y114216D01*
X1207111Y114136D01*
X1206600D01*
X1206580Y114148D01*
G03X1205377Y114490I-1205J-1950D01*
G01X1203633D01*
G03X1202457Y114165I1J-2292D01*
G01X1202434Y114151D01*
X1202382Y114136D01*
X1201609D01*
G03X1200159Y113629I0J-2326D01*
G01X1200144Y113618D01*
G03X1199776Y113319I1253J-1918D01*
G01X1198774Y112318D01*
X1198293Y111837D01*
G02X1198275Y111821I-142J141D01*
G02X1198122Y111781I-123J158D01*
G01X1198063Y111794D01*
X1198049Y111800D01*
X1198041Y111804D01*
G03X1197401Y111947I-640J-1360D01*
G01X1197400D01*
G03X1197171Y111931I-10J-1503D01*
G01X1197160Y111929D01*
X1197062Y111926D01*
G02X1196886Y112033I1J200D01*
G01X1196869Y112068D01*
G03X1196819Y112133I-180J-87D01*
G01X1196774Y112172D01*
G02X1196705Y112308I130J152D01*
G02X1196704Y112324I199J20D01*
G01Y114623D01*
G03X1193100I-1802J0D01*
G01Y111220D01*
G03X1193363Y110284I1802J1D01*
G01X1193377Y110261D01*
X1193396Y110194D01*
X1193403Y110168D01*
X1193404Y110116D01*
X1193386Y110043D01*
Y110041D01*
X1193329Y109820D01*
G02X1193328Y109816I-194J46D01*
G01X1193247Y109775D01*
G03X1192655Y109345I1054J-2074D01*
G01X1192202Y108892D01*
G02X1192154Y108905I28J198D01*
G01X1192080Y108948D01*
G02X1192078Y108950I140J142D01*
G03X1191955Y109019I-1182J-1964D01*
G01X1191953D01*
X1191911Y109041D01*
G03X1191842Y109074I-1023J-2051D01*
G01X1191804Y109091D01*
G03X1191085Y109273I-914J-2101D01*
G01X1191011Y109277D01*
G03X1190896Y109280I-117J-2289D01*
G01X1189133D01*
G03X1187964Y108948I19J-2292D01*
G01X1187950Y108940D01*
X1187916Y108926D01*
G02X1187895Y108919I-74J186D01*
G01X1187875Y108913D01*
G02X1187783Y108909I-54J193D01*
G01X1187398Y109294D01*
G03X1185753Y109976I-1646J-1645D01*
G03X1183426Y107649I0J-2327D01*
G03X1183909Y106231I2327J1D01*
G01X1183945Y106184D01*
G02X1183950Y106139I-195J-44D01*
G01Y105788D01*
G02X1183909Y105667I-200J0D01*
G03X1183426Y104249I1844J-1419D01*
G03X1185753Y101922I2327J0D01*
G03X1187398Y102604I-1J2327D01*
G01X1187803Y103009D01*
G02X1187945Y103068I142J-141D01*
G01X1193564D01*
G03X1194037Y103116I3J2326D01*
G01X1194073Y103124D01*
X1194146Y103112D01*
X1194183Y103090D01*
X1194217Y103070D01*
X1194253Y103035D01*
X1194267Y103012D01*
Y103011D01*
G03X1195557Y102281I1290J775D01*
G03X1197059Y103783I0J1502D01*
G01Y103787D01*
G03X1197054Y103908I-1502J-1D01*
G01X1197051Y103950D01*
X1197064Y103988D01*
G02X1197106Y104061I190J-61D01*
G01X1197233Y104199D01*
G02X1197380Y104264I148J-135D01*
G01X1197960D01*
G03X1199605Y104945I0J2327D01*
G01X1200543Y105882D01*
G02X1200732Y105935I142J-141D01*
G01X1200737Y105934D01*
X1200905Y105893D01*
X1200924Y105886D01*
X1200950Y105877D01*
X1200976Y105856D01*
G02X1201019Y105811I-121J-159D01*
G01X1201028Y105797D01*
X1201053Y105754D01*
X1201058Y105739D01*
X1201060Y105732D01*
G03X1202492Y104684I1432J454D01*
G03X1203994Y106186I0J1502D01*
G03X1203022Y107591I-1501J0D01*
G01X1203018Y107593D01*
X1202990Y107604D01*
X1202925Y107681D01*
X1202846Y108058D01*
G02X1202901Y108241I196J41D01*
G01X1202929Y108269D01*
G02X1203071Y108328I142J-141D01*
G01X1208654D01*
G03X1210088Y108833I-1J2291D01*
G01X1210094Y108837D01*
G03X1210345Y109055I-1396J1861D01*
G01X1212344Y111054D01*
G02X1212432Y111075I89J-179D01*
G01X1212614Y111076D01*
X1212712D01*
G02X1212788Y111061I0J-200D01*
G01X1212829Y111044D01*
X1212857Y111016D01*
G03X1213914Y110581I1057J1067D01*
G01X1213916D01*
G03X1213979Y110582I8J1502D01*
G01X1214002Y110583D01*
G03X1215191Y111290I-87J1500D01*
G03X1215416Y112019I-1278J794D01*
G01Y112024D01*
G03X1215417Y112082I-1501J55D01*
G01Y112084D01*
G03X1215398Y112324I-1502J2D01*
G03X1214872Y113243I-1485J-240D01*
G01X1214865Y113249D01*
X1214857Y113257D01*
G02X1214858Y113538I143J140D01*
G01X1214923Y113603D01*
Y113633D01*
X1220045Y118755D01*
G03X1220726Y120400I-1646J1645D01*
G01Y146755D01*
G02X1220785Y146897I200J0D01*
G01X1262357Y188469D01*
G03X1262736Y188969I-1619J1621D01*
G01X1267143Y196831D01*
G02X1267151Y196844I174J-98D01*
G01X1269834Y200860D01*
G03X1270226Y202152I-1934J1292D01*
G01Y209902D01*
X1271785Y235868D01*
X1271786Y235893D01*
X1271973Y236495D01*
X1273579Y241666D01*
G02X1273626Y241742I189J-64D01*
G01X1279910Y248026D01*
X1281298Y249415D01*
G02X1281440Y249474I142J-141D01*
G01X1307836D01*
G02X1307988Y249404I0J-200D01*
G01X1308214Y249140D01*
X1308238Y249057D01*
X1308232Y249020D01*
G03X1308212Y248767I1617J-255D01*
G01Y248765D01*
G03X1309849Y247128I1637J0D01*
G03X1310884Y247496I0J1639D01*
G01X1310910Y247517D01*
X1311008Y247554D01*
G02X1311074Y247565I65J-189D01*
G01X1311124D01*
G02X1311190Y247554I1J-200D01*
G01X1311288Y247517D01*
X1311314Y247496D01*
G03X1312348Y247128I1034J1269D01*
G01X1312349D01*
G03X1313474Y247575I0J1639D01*
G01X1313478Y247579D01*
X1313532Y247629D01*
G02X1313661Y247677I130J-152D01*
G01X1313718D01*
G02X1313753Y247674I0J-200D01*
G01X1313803Y247665D01*
X1313804D01*
X1313840Y247652D01*
X1313868Y247628D01*
G03X1314849Y247263I981J1136D01*
G03X1316351Y248755I0J1502D01*
G01Y248771D01*
G03X1316332Y249010I-1503J1D01*
G01X1316325Y249054D01*
X1316348Y249138D01*
X1316574Y249404D01*
G02X1316726Y249474I152J-130D01*
G01X1321003D01*
G03X1321908Y249658I-2J2326D01*
G02X1321986Y249674I78J-184D01*
G01X1337394D01*
G02X1337432Y249670I-2J-200D01*
G02X1337534Y249617I-37J-196D01*
G01X1342057Y245094D01*
G02X1342099Y245031I-142J-140D01*
G01X1342115Y244994D01*
Y237978D01*
G03X1342174Y237836I200J0D01*
G01X1352344Y227666D01*
G02X1352386Y227603I-142J-140D01*
G01X1352402Y227566D01*
Y170905D01*
G02X1352388Y170830I-200J-1D01*
G01X1352373Y170794D01*
X1341353Y159773D01*
G03X1340707Y158490I1620J-1620D01*
G01Y158486D01*
G03X1340674Y158100I2293J-390D01*
G01Y149386D01*
G02X1340667Y149366I-192J56D01*
G01X1340652Y149330D01*
X1340624Y149301D01*
X1340493Y149168D01*
X1340490Y149165D01*
X1340416Y149093D01*
G02X1340291Y149042I-134J149D01*
G01X1340286D01*
G03X1340147Y149032I38J-1502D01*
G03X1339011Y148277I173J-1492D01*
G03X1338923Y148094I1310J-742D01*
G01X1338920Y148084D01*
X1338914Y148070D01*
G03X1338818Y147537I1406J-528D01*
G01Y147509D01*
G03X1339600Y146220I1505J31D01*
G01X1339601D01*
G02X1339693Y146110I-97J-175D01*
G02X1339698Y146094I-188J-67D01*
G01X1339740Y145931D01*
X1339757Y145865D01*
Y145863D01*
X1339782Y145769D01*
X1339781Y145763D01*
X1339401Y145194D01*
G02X1339307Y145119I-166J112D01*
G03X1338227Y144248I854J-2164D01*
G01X1337143Y142626D01*
G03X1336750Y141335I1934J-1294D01*
G01Y141331D01*
G03X1336751Y141294I2326J44D01*
G01Y141293D01*
G02X1336717Y141179I-200J-2D01*
G01X1336322Y140587D01*
G02X1336297Y140557I-165J112D01*
G01X1335123Y139383D01*
X1335069Y139354D01*
X1335039Y139349D01*
G03X1333808Y138705I414J-2289D01*
G01X1332428Y137325D01*
G03X1331784Y136095I1645J-1645D01*
G01X1331729Y135989D01*
X1331704Y135964D01*
G03X1330413Y135310I354J-2299D01*
G01X1329033Y133930D01*
G03X1328440Y132920I1645J-1645D01*
G02X1328330Y132792I-193J54D01*
G03X1327766Y132427I950J-2086D01*
G02X1327715Y132395I-131J152D01*
G03X1327018Y131915I949J-2124D01*
G01X1325638Y130535D01*
G03X1325162Y129847I1644J-1646D01*
G01X1325116Y129783D01*
G03X1325041Y129709I1572J-1668D01*
G02X1325039Y129707I-142J140D01*
G03X1325029Y129697I1616J-1626D01*
G01X1324341Y129009D01*
X1324308Y128994D01*
G03X1323623Y128520I960J-2119D01*
G01X1322243Y127140D01*
G03X1321769Y126455I1645J-1645D01*
G01X1321754Y126422D01*
X1321431Y126099D01*
G03X1321131Y125728I1623J-1619D01*
G02X1321035Y125650I-168J109D01*
G03X1320228Y125125I838J-2170D01*
G01X1318848Y123745D01*
G03X1318220Y122597I1645J-1645D01*
G01X1318204Y122523D01*
X1318184Y122503D01*
X1318111Y122458D01*
X1318091Y122451D01*
G03X1317920Y122381I782J-2155D01*
G02X1317915Y122379I-77J185D01*
G03X1317910Y122377I72J-187D01*
G01X1317895Y122370D01*
G03X1317760Y122301I975J-2075D01*
G02X1317727Y122286I-99J174D01*
G03X1316833Y121730I750J-2202D01*
G01X1315453Y120350D01*
G03X1314954Y119607I1646J-1644D01*
G02X1314889Y119525I-184J79D01*
G03X1314618Y119286I1376J-1833D01*
G02X1314616Y119284I-142J140D01*
G01X1314156Y118824D01*
X1314123Y118809D01*
G03X1313438Y118335I960J-2119D01*
G01X1312058Y116955D01*
G03X1311584Y116270I1645J-1645D01*
G01X1311569Y116237D01*
X1311019Y115687D01*
G03X1310844Y115491I1620J-1622D01*
G01X1310767Y115432D01*
G03X1310043Y114940I922J-2136D01*
G01X1308663Y113560D01*
G03X1308140Y112759I1645J-1645D01*
G01X1308121Y112722D01*
G03X1308041Y112589I1923J-1247D01*
G01X1308038Y112584D01*
X1308033Y112575D01*
X1307976Y112530D01*
X1307642Y112427D01*
X1307568Y112432D01*
X1307534Y112449D01*
G03X1306533Y112676I-1002J-2099D01*
G01X1304579D01*
G03X1303255Y112262I1J-2326D01*
G01X1303141Y112226D01*
X1302099D01*
G03X1300702Y111760I0J-2326D01*
G01X1300617Y111723D01*
X1300608Y111721D01*
X1300513Y111746D01*
X1300491Y111758D01*
G03X1299784Y111947I-730J-1313D01*
G01X1299757D01*
G03X1299533Y111931I-5J-1503D01*
G01X1299522Y111929D01*
X1299424Y111926D01*
G02X1299248Y112033I1J200D01*
G01X1299231Y112068D01*
G03X1299181Y112133I-180J-87D01*
G01X1299136Y112172D01*
G02X1299067Y112308I130J152D01*
G02X1299066Y112324I199J20D01*
G01Y114623D01*
G03X1295462I-1802J0D01*
G01Y111223D01*
G03X1295499Y110857I1802J-3D01*
G03X1295565Y110620I1765J364D01*
G03X1295624Y110475I1697J606D01*
G03X1295743Y110254I1643J742D01*
G02X1295774Y110147I-169J-107D01*
G01Y110108D01*
X1295730Y109930D01*
X1295623Y109797D01*
G03X1294985Y109345I1007J-2097D01*
G01X1294557Y108917D01*
X1294541Y108922D01*
X1294513Y108934D01*
X1294452Y108968D01*
G02X1294450Y108970I140J142D01*
G03X1293299Y109280I-1151J-1983D01*
G01X1291555D01*
G03X1290325Y108922I0J-2293D01*
G01X1290311Y108913D01*
X1290279Y108899D01*
G02X1290167Y108888I-75J186D01*
G01X1289761Y109295D01*
G03X1288117Y109976I-1645J-1646D01*
G01X1288115D01*
G03X1285788Y107649I0J-2327D01*
G01Y107647D01*
G03X1286310Y106179I2327J1D01*
G01X1286312Y106177D01*
Y105788D01*
G02X1286271Y105667I-200J0D01*
G03X1285788Y104249I1844J-1419D01*
G03X1288115Y101922I2327J0D01*
G03X1289760Y102604I-1J2327D01*
G01X1290165Y103009D01*
G02X1290307Y103068I142J-141D01*
G01X1295894D01*
G03X1296392Y103121I4J2326D01*
G01X1296462Y103137D01*
G02X1296489Y103125I-67J-188D01*
G01X1296548Y103092D01*
X1296551Y103090D01*
G02X1296614Y103034I-98J-174D01*
G01X1296634Y103004D01*
G03X1297919Y102281I1285J780D01*
G03X1299421Y103782I0J1502D01*
G01Y103783D01*
G03X1299417Y103891I-1502J-2D01*
G01Y103901D01*
X1299414Y103943D01*
X1299427Y103980D01*
G02X1299469Y104049I188J-67D01*
G01X1299493Y104075D01*
X1299509Y104093D01*
X1299608Y104200D01*
G02X1299754Y104264I147J-136D01*
G01X1300360D01*
G03X1302005Y104945I0J2327D01*
G01X1302880Y105820D01*
G02X1303066Y105874I142J-141D01*
G01X1303144Y105856D01*
X1303146D01*
X1303299Y105820D01*
G02X1303414Y105735I-53J-193D01*
G01X1303433Y105699D01*
G02X1303434Y105695I-193J-50D01*
G01X1303435Y105693D01*
Y105692D01*
G03X1304854Y104684I1419J495D01*
G03X1306355Y106123I0J1502D01*
G01Y106124D01*
X1306357Y106162D01*
X1306388Y106233D01*
X1306416Y106260D01*
X1306548Y106388D01*
X1306616Y106454D01*
G02X1306627Y106464I140J-143D01*
G01X1309392D01*
G03X1310745Y106898I0J2327D01*
G01X1310749Y106902D01*
G03X1311088Y107181I-1280J1900D01*
G01X1312841Y108933D01*
X1314871Y110963D01*
G02X1314991Y111021I142J-141D01*
G01X1315002Y111022D01*
X1315097D01*
G02X1315149Y111015I0J-200D01*
G02X1315164Y111010I-56J-192D01*
G01X1315266Y110971D01*
X1315292Y110948D01*
G03X1316274Y110581I984J1135D01*
G01X1316926D01*
G03X1317125Y110760I0J200D01*
G01X1317129Y110800D01*
X1317148Y110835D01*
G02X1317198Y110896I177J-94D01*
G01X1317212Y110907D01*
G03X1317779Y112081I-935J1176D01*
G01Y112113D01*
G03X1317365Y113119I-1502J-30D01*
G01X1317338Y113147D01*
X1317303Y113235D01*
G02X1317328Y113415I189J66D01*
G01X1317336Y113427D01*
G02X1317349Y113441I153J-129D01*
G01X1319932Y116024D01*
G02X1320097Y116081I141J-141D01*
G02X1320135Y116073I-22J-199D01*
G01X1320200Y116052D01*
X1320225Y116034D01*
G03X1321091Y115759I866J1227D01*
G01X1321092D01*
G03X1322584Y117085I0J1502D01*
G01X1322590Y117141D01*
G03X1322347Y118087I-1498J119D01*
G01X1322325Y118120D01*
X1322292Y118169D01*
G02X1322288Y118176I172J103D01*
G01X1322285Y118183D01*
G02X1322265Y118299I178J90D01*
G01X1322270Y118330D01*
X1322295Y118384D01*
X1322314Y118405D01*
X1322318Y118409D01*
G03X1322321Y118412I-139J142D01*
G01X1322327Y118419D01*
X1340312Y136404D01*
X1340316Y136407D01*
G03X1340512Y136620I-1586J1656D01*
G01X1340516Y136625D01*
G03X1340519Y136629I-1832J1377D01*
G01X1340625Y136735D01*
G03X1340914Y137087I-1645J1645D01*
G01X1342819Y139937D01*
X1342882Y139980D01*
X1342906Y139985D01*
X1342942Y139993D01*
G02X1342946Y139994I50J-193D01*
G01X1343110Y140026D01*
X1343190D01*
X1343226Y140018D01*
X1343259Y139996D01*
G03X1344092Y139744I833J1251D01*
G01X1344109D01*
X1344145Y139746D01*
X1344153D01*
G03X1345584Y141071I-61J1501D01*
G01X1345589Y141114D01*
G03X1345590Y141372I-1497J135D01*
G01X1345589Y141379D01*
G03X1344948Y142482I-1496J-132D01*
G01X1344942Y142486D01*
X1344912Y142511D01*
X1344897Y142526D01*
G02X1344842Y142629I141J142D01*
G01X1344792Y142880D01*
G03X1344790Y142888I-195J-44D01*
G01X1346044Y144764D01*
G03X1346436Y146056I-1934J1292D01*
G01Y156593D01*
G02X1346495Y156735I200J0D01*
G01X1357555Y167795D01*
G03X1358236Y169440I-1646J1645D01*
G01Y296453D01*
G02X1358295Y296595I200J0D01*
G01X1367541Y305841D01*
G02X1367683Y305900I142J-141D01*
G01X1378150D01*
X1378164Y305898D01*
G03X1378500Y305874I333J2302D01*
G01X1388343D01*
G02X1388485Y305815I0J-200D01*
G01X1417505Y276795D01*
G02X1417564Y276653I-141J-142D01*
G01Y165251D01*
G03X1417573Y165038I2291J-10D01*
G01X1417574Y165026D01*
G03X1418255Y163455I2325J75D01*
G01X1431777Y149933D01*
X1431806Y149879D01*
X1431811Y149849D01*
G03X1432455Y148618I2289J414D01*
G01X1433835Y147238D01*
G03X1435065Y146594I1645J1645D01*
G01X1435171Y146539D01*
X1435196Y146514D01*
G03X1435850Y145223I2299J354D01*
G01X1437230Y143843D01*
G03X1438404Y143210I1645J1645D01*
G01X1438484Y143193D01*
X1438543Y143157D01*
X1438564Y143131D01*
Y141850D01*
X1438528Y141736D01*
G03X1438114Y140412I1912J-1325D01*
G01Y138460D01*
G03X1438116Y138356I2326J-7D01*
G02X1438115Y138334I-200J-2D01*
G03X1438113Y138302I2286J-159D01*
G01Y138288D01*
G03X1438108Y138138I2286J-151D01*
G01Y136391D01*
G03X1438139Y136019I2291J4D01*
G01Y135957D01*
G03X1438114Y135611I2301J-340D01*
G01Y133827D01*
G03X1438113Y133815I2283J-196D01*
G01Y133814D01*
G03X1438108Y133663I2286J-151D01*
G01Y131915D01*
G03X1438167Y131399I2291J1D01*
G01X1438172Y131353D01*
X1438168Y131311D01*
G03X1438114Y130815I2272J-498D01*
G01Y129349D01*
G03X1438113Y129337I2283J-196D01*
G01Y129336D01*
G03X1438108Y129185I2286J-151D01*
G01Y127438D01*
G03X1438205Y126779I2291J1D01*
G01X1438214Y126748D01*
Y126690D01*
X1438206Y126662D01*
G03X1438114Y126011I2234J-648D01*
G01Y124871D01*
G03X1438113Y124859I2283J-196D01*
G01Y124858D01*
G03X1438108Y124707I2286J-151D01*
G01Y122960D01*
G03X1438205Y122301I2291J1D01*
G01X1438225Y122235D01*
Y122234D01*
G03X1438230Y122220I191J60D01*
G01X1438231Y122217D01*
X1438233Y122212D01*
G03X1438247Y122173I2164J755D01*
G03X1438255Y122152I2145J805D01*
G02X1438256Y122012I-187J-71D01*
G03X1438114Y121212I2184J-800D01*
G01Y120393D01*
G03X1438113Y120381I2283J-196D01*
G01Y120380D01*
G03X1438108Y120229I2286J-151D01*
G01Y118482D01*
G03X1438205Y117823I2291J1D01*
G01X1438225Y117757D01*
Y117756D01*
G03X1438230Y117742I191J60D01*
G01X1438231Y117739D01*
X1438233Y117734D01*
G03X1438247Y117695I2164J755D01*
G03X1438322Y117516I2149J795D01*
G03X1438356Y117446I2078J966D01*
G03X1438114Y116415I2084J-1033D01*
G01Y115915D01*
G03X1438113Y115903I2283J-196D01*
G01Y115902D01*
G03X1438108Y115751I2286J-151D01*
G01Y114004D01*
G03X1438205Y113345I2291J1D01*
G01X1438225Y113279D01*
Y113278D01*
G03X1438230Y113264I191J60D01*
G01X1438231Y113261D01*
X1438233Y113256D01*
G03X1438247Y113217I2164J755D01*
G03X1438322Y113038I2149J795D01*
G03X1438390Y112903I2080J963D01*
G01X1438415Y112807D01*
X1438391Y112713D01*
G03X1438114Y111613I2049J-1101D01*
G01Y111437D01*
G03X1438113Y111425I2283J-196D01*
G01Y111424D01*
G03X1438108Y111273I2286J-151D01*
G01Y110207D01*
G02X1438057Y110074I-200J0D01*
G01X1437985Y109992D01*
X1437979Y109987D01*
X1437975Y109983D01*
G02X1437962Y109971I-142J141D01*
G01X1437889Y109964D01*
G03X1435790Y107649I227J-2315D01*
G01Y107647D01*
G03X1436272Y106230I2326J1D01*
G01X1436292Y106204D01*
X1436314Y106142D01*
Y105764D01*
G02X1436307Y105712I-200J0D01*
G01X1436272Y105668D01*
G03X1435790Y104251I1844J-1418D01*
G01Y104249D01*
G03X1438116Y101922I2327J0D01*
G03X1439761Y102604I-1J2327D01*
G01X1440166Y103009D01*
G02X1440308Y103068I142J-141D01*
G01X1440593D01*
G03X1442238Y103749I0J2327D01*
G01X1443645Y105156D01*
G03X1444326Y106801I-1646J1645D01*
G01Y144571D01*
G03X1443832Y146004I-2327J-1D01*
G01X1443828Y146009D01*
G03X1443768Y146087I-1846J-1358D01*
G01X1443747Y146113D01*
X1443716Y146202D01*
X1443703Y146239D01*
X1443708Y146367D01*
G02X1443724Y146440I200J-6D01*
G01X1443739Y146473D01*
X1443766Y146500D01*
G03X1444184Y147540I-1085J1040D01*
G03X1442682Y149042I-1502J0D01*
G01X1442681D01*
G03X1441710Y148686I0J-1503D01*
G01X1441709Y148685D01*
X1441680Y148661D01*
X1441647Y148649D01*
G02X1441571Y148638I-66J189D01*
G01X1441448Y148643D01*
X1441446D01*
X1441301Y148649D01*
G02X1441168Y148707I8J200D01*
G01X1432463Y157411D01*
X1423395Y166479D01*
G02X1423336Y166621I141J142D01*
G01Y278160D01*
G03X1423235Y278841I-2326J3D01*
G01X1423226Y278869D01*
Y293243D01*
G02X1423285Y293385I200J0D01*
G01X1424841Y294941D01*
G02X1424983Y295000I142J-141D01*
G01X1434827D01*
G02X1434969Y294941I0J-200D01*
G01X1435255Y294655D01*
G03X1436900Y293974I1645J1646D01*
G01X1476053D01*
G02X1476195Y293915I0J-200D01*
G01X1517105Y253005D01*
G02X1517164Y252863I-141J-142D01*
G01Y214037D01*
X1516455Y202232D01*
X1516454Y202224D01*
Y202218D01*
X1516359Y201684D01*
X1516319Y201460D01*
X1516317Y201448D01*
X1516316Y201444D01*
G03X1516314Y201433I2253J-415D01*
G01Y201429D01*
X1516310Y201398D01*
G03X1516284Y201057I2264J-344D01*
G01Y201056D01*
G03X1516285Y200978I2291J-10D01*
G01X1516381Y198139D01*
X1516525Y193895D01*
X1517164Y175067D01*
Y172670D01*
G03X1517341Y171780I2326J0D01*
G01X1520685Y163706D01*
G03X1521189Y162951I2150J889D01*
G01X1533987Y150153D01*
X1534016Y150099D01*
X1534021Y150069D01*
G03X1534665Y148838I2289J414D01*
G01X1536045Y147458D01*
G03X1536818Y146946I1645J1645D01*
G01X1536923Y146847D01*
G03X1537295Y146294I2068J990D01*
G03X1537392Y146194I1693J1546D01*
G02X1537394Y146192I-140J-142D01*
G01X1537734Y145852D01*
X1537745Y145834D01*
G03X1538060Y145443I1959J1256D01*
G01X1539440Y144063D01*
G03X1540731Y143409I1645J1645D01*
G01X1540744Y143396D01*
X1540774Y143323D01*
Y141650D01*
X1540738Y141536D01*
G03X1540324Y140212I1912J-1325D01*
G01Y138375D01*
G03X1540322Y138364I2254J-415D01*
G01X1540320Y138356D01*
X1540319Y138348D01*
X1540318Y138341D01*
Y138338D01*
X1540315Y138322D01*
G03X1540294Y138156I2261J-370D01*
G03X1540291Y138118I2283J-199D01*
G01Y138104D01*
G03X1540286Y137954I2286J-151D01*
G01Y136208D01*
G03X1540335Y135737I2292J0D01*
G01X1540339Y135696D01*
X1540338Y135674D01*
G03X1540324Y135411I2312J-255D01*
G01Y133893D01*
G03X1540322Y133882I2253J-415D01*
G01X1540320Y133873D01*
G03X1540286Y133481I2258J-393D01*
G01Y131731D01*
G03X1540363Y131143I2291J1D01*
G02X1540366Y131054I-193J-51D01*
G03X1540324Y130611I2284J-440D01*
G01Y129415D01*
G03X1540322Y129404I2253J-415D01*
G01X1540320Y129395D01*
G03X1540286Y129003I2257J-393D01*
G01Y127254D01*
G03X1540383Y126595I2291J1D01*
G01X1540403Y126530D01*
Y126528D01*
X1540411Y126501D01*
X1540412Y126447D01*
X1540404Y126419D01*
G03X1540324Y125811I2246J-605D01*
G01Y124937D01*
G03X1540322Y124926I2253J-415D01*
G01X1540320Y124917D01*
G03X1540286Y124525I2257J-393D01*
G01Y122776D01*
G03X1540383Y122117I2291J1D01*
G01X1540403Y122051D01*
Y122050D01*
G03X1540408Y122036I191J60D01*
G01X1540409Y122033D01*
X1540411Y122028D01*
G03X1540425Y121989I2164J755D01*
G03X1540451Y121922I2149J795D01*
G02X1540455Y121780I-185J-76D01*
G03X1540324Y121013I2195J-770D01*
G01Y120459D01*
G03X1540322Y120448I2253J-415D01*
G01X1540320Y120439D01*
G03X1540286Y120047I2257J-393D01*
G01Y118298D01*
G03X1540383Y117639I2291J1D01*
G01X1540403Y117573D01*
Y117572D01*
G03X1540408Y117558I191J60D01*
G01X1540409Y117555D01*
X1540411Y117550D01*
G03X1540425Y117511I2164J755D01*
G03X1540500Y117332I2149J795D01*
G03X1540513Y117304I2085J951D01*
G01X1540533Y117218D01*
X1540516Y117138D01*
G03X1540324Y116213I2134J-925D01*
G01Y115981D01*
G03X1540322Y115970I2253J-415D01*
G01X1540320Y115961D01*
G03X1540286Y115569I2257J-393D01*
G01Y113820D01*
G03X1540383Y113161I2291J1D01*
G01X1540403Y113095D01*
Y113094D01*
G03X1540408Y113080I191J60D01*
G01X1540409Y113077D01*
X1540411Y113072D01*
G03X1540425Y113033I2164J755D01*
G03X1540500Y112854I2149J795D01*
G03X1540587Y112685I2079J963D01*
G01X1540614Y112585D01*
X1540591Y112493D01*
G03X1540327Y111527I2059J-1082D01*
G02X1540324Y111501I-200J10D01*
G03X1540286Y111088I2253J-416D01*
G01Y110109D01*
G02X1540238Y109979I-200J0D01*
G01X1540223Y109961D01*
G03X1538152Y107649I255J-2312D01*
G01Y107647D01*
G03X1538634Y106230I2326J1D01*
G01X1538654Y106204D01*
X1538676Y106142D01*
Y105764D01*
G02X1538669Y105712I-200J0D01*
G01X1538634Y105668D01*
G03X1538152Y104251I1844J-1418D01*
G01Y104249D01*
G03X1540478Y101922I2327J0D01*
G03X1542123Y102604I-1J2327D01*
G01X1542528Y103009D01*
G02X1542670Y103068I142J-141D01*
G01X1543003D01*
G03X1544648Y103749I0J2327D01*
G01X1545855Y104956D01*
G03X1546536Y106601I-1646J1645D01*
G01Y144792D01*
G03X1546064Y146196I-2326J-1D01*
G01X1546055Y146233D01*
X1546065Y146322D01*
Y146324D01*
X1546073Y146391D01*
G02X1546086Y146435I197J-34D01*
G01X1546104Y146475D01*
X1546128Y146500D01*
G03X1546546Y147540I-1085J1040D01*
G03X1545044Y149042I-1502J0D01*
G03X1543983Y148603I0J-1502D01*
G01X1543982Y148602D01*
G02X1543700Y148603I-140J142D01*
G01X1525857Y166446D01*
G02X1525815Y166508I142J141D01*
G01X1525527Y167171D01*
X1525259Y167788D01*
X1524738Y168989D01*
X1524659Y169173D01*
G02X1524657Y169175I130J132D01*
G01X1522941Y173317D01*
G02X1522926Y173394I185J76D01*
G01Y215507D01*
X1523479Y224717D01*
X1524215Y236992D01*
Y237005D01*
X1524216Y237016D01*
Y237020D01*
X1524217Y237028D01*
G03X1524218Y237047I-2287J130D01*
G01Y237055D01*
G03X1524220Y237138I-2289J97D01*
G01Y252985D01*
G03X1523548Y254605I-2292J-1D01*
G01X1522608Y255545D01*
X1522596Y255566D01*
G03X1522245Y256015I-1995J-1198D01*
G01X1486752Y291508D01*
G02X1486693Y291650I141J142D01*
G01Y297466D01*
G02X1486694Y297485I200J-1D01*
G01Y297486D01*
G02X1486733Y297584I199J-22D01*
G02X1486751Y297605I160J-119D01*
G01X1487261Y298115D01*
G02X1487403Y298174I142J-141D01*
G01X1570553D01*
G02X1570695Y298115I0J-200D01*
G01X1612396Y256414D01*
G02X1612439Y256349I-142J-141D01*
G01X1615671Y248547D01*
G02X1615673Y248541I-189J-66D01*
G01X1617403Y243984D01*
X1619751Y237798D01*
G02X1619764Y237727I-187J-71D01*
G01Y217996D01*
X1619494Y213501D01*
X1619194Y208498D01*
X1619026Y205696D01*
X1618713Y200479D01*
Y200466D01*
X1618712Y200458D01*
Y200454D01*
X1618711Y200445D01*
G03X1618710Y200424I2288J-119D01*
G01Y200418D01*
G03X1618708Y200334I2290J-97D01*
G01Y200332D01*
G03X1618786Y199742I2292J3D01*
G01X1619757Y196100D01*
G02X1619764Y196049I-193J-52D01*
G01Y167710D01*
G03X1620445Y166065I2327J0D01*
G01X1636187Y150323D01*
X1636216Y150269D01*
X1636221Y150239D01*
G03X1636865Y149008I2289J414D01*
G01X1638245Y147628D01*
G03X1639475Y146984I1645J1645D01*
G01X1639581Y146929D01*
X1639606Y146904D01*
G03X1640260Y145613I2299J354D01*
G01X1641640Y144233D01*
G03X1642141Y143853I1643J1646D01*
G02X1642157Y143843I-98J-175D01*
G03X1642597Y143604I1307J1882D01*
G03X1642829Y143523I870J2120D01*
G01X1642893Y143505D01*
X1642974Y143398D01*
Y141593D01*
X1642938Y141479D01*
G03X1642524Y140155I1912J-1325D01*
G01Y138204D01*
G03X1642603Y137600I2326J-3D01*
G01X1642610Y137575D01*
Y136173D01*
G03X1642614Y136038I2291J0D01*
G02X1642607Y135973I-200J-11D01*
G03X1642524Y135354I2243J-616D01*
G01Y133404D01*
G03X1642603Y132800I2326J-3D01*
G01X1642610Y132775D01*
Y131696D01*
G03X1642637Y131343I2292J-2D01*
G02X1642631Y131252I-197J-33D01*
G03X1642524Y130555I2219J-697D01*
G01Y128604D01*
G03X1642603Y128000I2326J-3D01*
G01X1642610Y127975D01*
Y127218D01*
G03X1642675Y126677I2291J1D01*
G02X1642668Y126561I-195J-46D01*
G03X1642524Y125756I2182J-806D01*
G01Y123804D01*
G03X1642603Y123200I2326J-3D01*
G01X1642610Y123175D01*
Y122740D01*
G03X1642724Y122026I2291J0D01*
G01X1642734Y121964D01*
X1642717Y121884D01*
G03X1642524Y120958I2133J-928D01*
G01Y119004D01*
G03X1642603Y118400I2326J-3D01*
G01X1642610Y118375D01*
Y118262D01*
G03X1642786Y117382I2291J1D01*
G02X1642780Y117214I-184J-78D01*
G03X1642524Y116155I2070J-1061D01*
G01Y114202D01*
G03X1642620Y113542I2326J1D01*
G01X1642627Y113509D01*
G03X1642814Y112839I2275J274D01*
G03X1642860Y112743I2089J942D01*
G01X1642882Y112651D01*
X1642854Y112549D01*
G03X1642524Y111355I1996J-1194D01*
G01Y110121D01*
G02X1642366Y109926I-200J1D01*
G01X1642364D01*
G03X1640514Y107649I476J-2277D01*
G01Y107647D01*
G03X1640996Y106230I2326J1D01*
G01X1641015Y106206D01*
X1641038Y106142D01*
Y105764D01*
G02X1641031Y105712I-200J0D01*
G01X1640996Y105668D01*
G03X1640514Y104251I1844J-1418D01*
G01Y104249D01*
G03X1642840Y101922I2327J0D01*
G03X1644485Y102604I-1J2327D01*
G01X1644890Y103009D01*
G02X1645032Y103068I142J-141D01*
G01X1645260D01*
G03X1646905Y103749I0J2327D01*
G01X1648055Y104899D01*
G03X1648567Y105672I-1645J1645D01*
G01X1648570Y105680D01*
G03X1648772Y106620I-2089J941D01*
G01Y144944D01*
G03X1648403Y146190I-2291J-1D01*
G02X1648434Y146445I168J109D01*
G03X1648908Y147540I-1028J1095D01*
G03X1647406Y149042I-1502J0D01*
G03X1646345Y148603I0J-1502D01*
G01X1646344Y148602D01*
X1646145D01*
G02X1646003Y148661I0J200D01*
G01X1631587Y163077D01*
X1625585Y169080D01*
G02X1625526Y169222I141J142D01*
G01Y219478D01*
X1626484Y235451D01*
G03X1626488Y235586I-2287J135D01*
G01Y235588D01*
G03X1626339Y236401I-2291J0D01*
G01X1625539Y238509D01*
G02X1625526Y238580I187J71D01*
G01Y239350D01*
G03X1625349Y240240I-2326J0D01*
G01X1619765Y253722D01*
G02X1619763Y253728I189J66D01*
G01X1617773Y258970D01*
G03X1617251Y259777I-2142J-813D01*
G01X1577301Y299728D01*
G02X1577282Y299750I141J141D01*
G02X1577242Y299870I160J120D01*
G01Y305158D01*
G02X1577243Y305177I200J-1D01*
G01Y305178D01*
G02X1577282Y305276I199J-22D01*
G02X1577300Y305297I160J-119D01*
G01X1580696Y308693D01*
G02X1580816Y308751I142J-141D01*
G01X1580827Y308752D01*
X1611508D01*
G03X1611659Y308820I0J202D01*
G02X1611665Y308827I155J-127D01*
G01X1611680Y308842D01*
X1611754Y308874D01*
X1666353D01*
G02X1666495Y308815I0J-200D01*
G01X1710369Y264941D01*
X1710398Y264887D01*
X1710403Y264857D01*
G03X1711047Y263627I2289J415D01*
G01X1712427Y262247D01*
G03X1713657Y261603I1645J1645D01*
G01X1713687Y261598D01*
X1713741Y261569D01*
X1715815Y259495D01*
G02X1715858Y259430I-142J-141D01*
G01X1716900Y256916D01*
X1716905Y256855D01*
X1716898Y256825D01*
G03X1716846Y256332I2274J-489D01*
G03X1717022Y255442I2326J-2D01*
G01X1717768Y253640D01*
G03X1718659Y252574I2149J891D01*
G01X1718736Y252481D01*
X1718749Y252450D01*
G03X1718682Y251897I2260J-554D01*
G03X1718859Y251007I2326J0D01*
G01X1719605Y249205D01*
G03X1720478Y248150I2150J890D01*
G01X1720479D01*
G02X1720554Y248057I-111J-166D01*
G01X1720598Y247947D01*
X1720750Y247562D01*
G02X1720764Y247489I-186J-74D01*
G01Y247089D01*
G02X1720728Y246976I-200J1D01*
G01Y246975D01*
G03X1720314Y245650I1913J-1325D01*
G01Y243699D01*
G03X1720728Y242375I2326J1D01*
G01X1720764Y242261D01*
Y242225D01*
G03X1720314Y240850I1876J-1375D01*
G01Y238899D01*
G03X1720728Y237575I2326J1D01*
G01X1720764Y237461D01*
Y170110D01*
G03X1721445Y168465I2327J0D01*
G01X1721459Y168451D01*
G03X1721562Y168341I1724J1511D01*
G01X1728040Y161863D01*
X1728069Y161809D01*
X1728074Y161779D01*
G03X1728717Y160556I2288J422D01*
G01X1730097Y159176D01*
G03X1731319Y158533I1646J1645D01*
G01X1731424Y158478D01*
X1731459Y158443D01*
G03X1732112Y157161I2298J363D01*
G01X1733492Y155781D01*
G03X1734714Y155138I1646J1645D01*
G01X1734819Y155083D01*
X1734854Y155048D01*
G03X1735507Y153766I2298J363D01*
G01X1736887Y152386D01*
G03X1738109Y151743I1646J1645D01*
G01X1738214Y151688D01*
X1738249Y151653D01*
G03X1738902Y150371I2298J363D01*
G01X1739093Y150180D01*
X1739103Y150163D01*
G03X1739352Y149845I1924J1250D01*
G03X1739429Y149767I1670J1572D01*
G02X1739431Y149765I-140J-142D01*
G01X1740638Y148559D01*
G03X1741614Y147979I1623J1620D01*
G01X1741746Y147853D01*
G03X1742252Y147023I2196J769D01*
G02X1742274Y146995I-146J-137D01*
G03X1742575Y146624I1920J1250D01*
G01X1743807Y145392D01*
G03X1744269Y145034I1623J1618D01*
G03X1744769Y144816I1159J1977D01*
G03X1745081Y144746I657J2196D01*
G01X1745082D01*
X1745100Y144743D01*
X1745102D01*
X1745117Y144740D01*
G02X1745209Y144693I-42J-196D01*
G01X1745214Y144688D01*
G03X1745222Y144680I145J137D01*
G01X1745229Y144675D01*
X1745296Y144608D01*
G02X1745353Y144490I-142J-141D01*
G01X1745357Y144458D01*
X1745342Y144391D01*
X1745323Y144361D01*
G03X1744972Y143149I1941J-1219D01*
G01Y141401D01*
G03X1745341Y140155I2292J1D01*
G01X1745356Y140132D01*
X1745372Y140077D01*
Y139244D01*
X1745356Y139189D01*
X1745341Y139166D01*
G03X1744970Y137916I1923J-1251D01*
G01Y136176D01*
G03X1745341Y134928I2293J3D01*
G01Y134927D01*
X1745345Y134922D01*
X1745362Y134895D01*
X1745372Y134849D01*
Y134804D01*
G02X1745366Y134757I-200J2D01*
G01X1745354Y134706D01*
X1745336Y134678D01*
G03X1744972Y133440I1928J-1239D01*
G01Y131696D01*
G03X1745334Y130462I2291J2D01*
G01X1745350Y130437D01*
X1745363Y130391D01*
G02X1745369Y130362I-192J-55D01*
G01X1745372Y130333D01*
Y130302D01*
X1745349Y130223D01*
X1745334Y130198D01*
X1745333Y130196D01*
Y130195D01*
G03X1745329Y130190I1778J-1426D01*
G01X1745328Y130189D01*
G03X1744972Y128963I1937J-1227D01*
G01Y127217D01*
G03X1745051Y126621I2293J1D01*
G02X1745048Y126504I-193J-54D01*
G03X1744924Y125755I2202J-749D01*
G01Y123804D01*
G03X1744968Y123350I2326J-4D01*
G01X1744972Y123331D01*
Y122737D01*
G03X1745101Y121980I2293J1D01*
G01X1745113Y121913D01*
X1745098Y121838D01*
G03X1744924Y120957I2152J-883D01*
G01Y119004D01*
G03X1744968Y118550I2326J-4D01*
G01X1744972Y118531D01*
Y118261D01*
G03X1745164Y117345I2292J2D01*
G01X1745181Y117265D01*
X1745160Y117177D01*
G03X1744924Y116157I2090J-1021D01*
G01Y114202D01*
G03X1744970Y113746I2326J4D01*
G01X1744973Y113713D01*
G03X1745239Y112711I2291J72D01*
G02X1745236Y112517I-177J-94D01*
G03X1744924Y111354I2015J-1164D01*
G01Y109973D01*
X1744916Y109963D01*
X1744910Y109957D01*
G03X1742876Y107649I292J-2308D01*
G01Y107647D01*
G03X1743358Y106230I2326J1D01*
G01X1743378Y106204D01*
X1743400Y106142D01*
Y105756D01*
X1743377Y105692D01*
X1743358Y105668D01*
G03X1742876Y104251I1844J-1418D01*
G01Y104249D01*
G03X1745202Y101922I2327J0D01*
G03X1746847Y102604I-1J2327D01*
G01X1747252Y103009D01*
G02X1747394Y103068I142J-141D01*
G01X1747660D01*
G03X1749305Y103749I0J2327D01*
G01X1750455Y104899D01*
G03X1751136Y106544I-1646J1645D01*
G01Y145960D01*
G03X1750455Y147605I-2327J0D01*
G01X1726613Y171447D01*
G02X1726554Y171589I141J142D01*
G01Y197273D01*
X1728902Y236352D01*
Y236366D01*
G03X1728907Y236490I-2288J154D01*
G01Y236534D01*
X1729061Y241446D01*
G03X1729062Y241517I-2290J68D01*
G01Y241520D01*
G03Y241545I-2291J12D01*
G01Y241579D01*
G03X1729059Y241650I-2291J-61D01*
G03X1729053Y241728I-2287J-137D01*
G03X1729048Y241777I-2282J-208D01*
G03X1729026Y241927I-2277J-257D01*
G03X1728902Y242362I-2255J-408D01*
G01X1726527Y248360D01*
G03X1726351Y249162I-2327J-90D01*
G01X1723085Y257047D01*
X1721161Y261909D01*
G03X1720926Y262352I-2130J-846D01*
G03X1720904Y262384I-1899J-1282D01*
G03X1720819Y262497I-1873J-1320D01*
G02X1720814Y262504I160J120D01*
G03X1720329Y263131I-2058J-1090D01*
G01X1693516Y289944D01*
G02X1693457Y290086I141J142D01*
G01Y293322D01*
G02X1693458Y293341I200J-1D01*
G01Y293342D01*
G02X1693497Y293440I199J-22D01*
G02X1693515Y293461I160J-119D01*
G01X1693966Y293912D01*
G02X1693987Y293930I140J-142D01*
G01X1699088D01*
G02X1699139Y293873I-121J-159D01*
G02X1699155Y293840I-171J-103D01*
G01X1699287Y293490D01*
G02X1699294Y293370I-187J-71D01*
G01X1699287Y293342D01*
X1699256Y293291D01*
X1699232Y293270D01*
X1699229Y293267D01*
X1699225Y293264D01*
G03X1698721Y292141I999J-1123D01*
G03X1701725I1502J0D01*
G03X1701221Y293264I-1503J0D01*
G01X1701217Y293267D01*
X1701205Y293279D01*
G02X1701160Y293491I142J141D01*
G01X1701248Y293724D01*
Y293726D01*
X1701291Y293840D01*
G02X1701311Y293879I187J-71D01*
G02X1701358Y293930I168J-108D01*
G01X1780760D01*
G02X1780902Y293871I0J-200D01*
G01X1802857Y271915D01*
G02X1802916Y271773I-141J-142D01*
G01Y141052D01*
G02X1802857Y140910I-200J0D01*
G01X1781489Y119542D01*
G03X1780814Y117912I1631J-1630D01*
G01Y101878D01*
G03X1781489Y100248I2306J0D01*
G01X1785724Y96013D01*
G02X1785725Y95966I-198J-28D01*
G01X1785717Y95878D01*
Y95876D01*
X1785702Y95723D01*
G02X1785673Y95636I-199J18D01*
G01X1785651Y95600D01*
X1785613Y95575D01*
G03X1784914Y94279I852J-1296D01*
G03X1785937Y92820I1552J0D01*
G01X1785976Y92806D01*
G02X1786052Y92756I-69J-188D01*
G01X1786068Y92740D01*
Y87411D01*
G02X1786033Y87375I-160J120D01*
G01X1786010Y87356D01*
X1785942Y87330D01*
X1785940D01*
G03X1785895Y87312I535J-1403D01*
G01X1785893D01*
G03X1784965Y85861I572J-1388D01*
G03X1785958Y84509I1501J62D01*
G01X1785988Y84495D01*
X1786035Y84469D01*
G02X1786068Y84435I-126J-155D01*
G01Y74197D01*
G03X1786744Y72566I2307J1D01*
G01X1789033Y70277D01*
G03X1790663Y69602I1630J1631D01*
G01X1790664D01*
G03X1792970Y71908I0J2306D01*
G01Y71909D01*
G03X1792295Y73539I-2306J0D01*
G01X1791315Y74519D01*
X1791307Y74558D01*
X1791403Y74890D01*
G02X1791425Y74939I192J-57D01*
G01X1791440Y74963D01*
X1791469Y74989D01*
X1791490Y75009D01*
X1791538Y75034D01*
X1791565Y75039D01*
G03X1792719Y75665I-477J2257D01*
G01X1794631Y77577D01*
G03X1795040Y78132I-1631J1631D01*
G02X1795046Y78142I175J-98D01*
G03X1795370Y79310I-1943J1168D01*
G01Y95460D01*
G03X1795046Y96628I-2267J0D01*
G02X1795040Y96638I169J108D01*
G03X1794631Y97193I-2040J-1076D01*
G01X1787295Y104528D01*
G02X1787236Y104670I141J142D01*
G01Y116123D01*
G02X1787295Y116265I200J0D01*
G01X1808665Y137634D01*
G03X1809276Y138724I-1631J1631D01*
G01X1809280Y138736D01*
G03X1809384Y139421I-2203J685D01*
G01Y273405D01*
G03X1809277Y274099I-2307J0D01*
G01X1809273Y274111D01*
G03X1808664Y275192I-2240J-550D01*
G01X1784179Y299677D01*
G03X1782549Y300352I-1630J-1631D01*
G01X1692344D01*
G02X1692202Y300411I0J200D01*
G01X1670174Y322440D01*
G03X1669713Y322796I-1629J-1633D01*
G01X1669691Y322809D01*
X1668470Y324031D01*
G03X1668156Y324294I-1632J-1630D01*
G01X1668141Y324304D01*
X1667359Y325086D01*
G03X1665756Y325750I-1603J-1603D01*
G01X1633264D01*
G02X1633173Y325772I0J200D01*
G02X1633123Y325808I90J178D01*
G01X1631607Y327324D01*
G02X1631571Y327374I142J140D01*
G02X1631549Y327465I178J91D01*
G01Y327884D01*
X1631562Y327933D01*
X1631574Y327955D01*
G03X1631860Y329067I-2021J1113D01*
G03X1631490Y330320I-2307J0D01*
G01X1631458Y330428D01*
X1631487Y330532D01*
G03X1631820Y331725I-1973J1194D01*
G01Y331727D01*
G03X1631090Y333411I-2307J0D01*
G01X1631033Y333465D01*
G02X1631022Y333576I186J74D01*
G01X1631027Y333601D01*
X1631045Y333641D01*
G03X1631204Y334399I-1743J761D01*
G01Y334439D01*
G03X1630647Y335747I-1902J-37D01*
G01X1611766Y354627D01*
G02X1611730Y354677I142J140D01*
G02X1611708Y354768I178J91D01*
G01Y366296D01*
G02X1611788Y366456I200J0D01*
G01X1639537D01*
G03X1640459Y366838I-1J1306D01*
G01X1646609Y372988D01*
G03X1646992Y373912I-923J924D01*
G01Y380754D01*
X1647006Y380782D01*
G03X1647187Y381498I-1323J715D01*
G01Y381500D01*
G03X1645685Y383002I-1502J0D01*
G01X1645682D01*
G03X1645433Y382981I1J-1502D01*
G01X1645427Y382980D01*
X1645418Y382979D01*
G02X1645271Y383020I-24J198D01*
G01X1645219Y383062D01*
G02X1645217Y383064I140J142D01*
G01X1645126Y383139D01*
X1645123Y383142D01*
G03X1645110Y383153I-135J-147D01*
G01X1645041Y383203D01*
X1645022Y383216D01*
X1645002Y383231D01*
X1644998Y383239D01*
Y384733D01*
G02X1645057Y384875I200J0D01*
G01X1649234Y389051D01*
X1649260Y389059D01*
G03X1650337Y390500I-426J1441D01*
G03X1648835Y392002I-1502J0D01*
G03X1647394Y390925I0J-1503D01*
G01X1647386Y390899D01*
X1642768Y386281D01*
G03X1642386Y385359I924J-923D01*
G01Y382574D01*
G02X1642262Y382389I-200J0D01*
G01X1642206Y382365D01*
X1642088Y382389D01*
X1640602Y383875D01*
G03X1638972Y384550I-1630J-1631D01*
G01X1635861D01*
G03X1634231Y383875I0J-2306D01*
G01X1631522Y381165D01*
G02X1631380Y381106I-142J141D01*
G01X1599246D01*
G03X1598366Y380931I1J-2306D01*
G01X1598119Y380829D01*
G02X1597902Y380872I-76J185D01*
G01X1589779Y388995D01*
G03X1589637Y389054I-142J-141D01*
G01X1585813D01*
G02X1585782Y389056I-3J200D01*
G02X1585658Y389128I32J198D01*
G01X1585634Y389160D01*
X1585495Y389502D01*
G02X1585492Y389646I185J76D01*
G01X1585496Y389656D01*
X1585514Y389699D01*
G02X1585552Y389758I184J-77D01*
G01X1585561Y389768D01*
X1585563Y389771D01*
X1585564D01*
G03X1586037Y390856I-1324J1223D01*
G03X1586042Y390965I-1797J137D01*
G01Y394395D01*
G03X1582438I-1802J0D01*
G01Y390962D01*
G03X1582919Y389768I1802J32D01*
G01X1582928Y389758D01*
G02X1582967Y389697I-146J-136D01*
G01X1582982Y389660D01*
G02X1582989Y389642I-183J-81D01*
G01X1582992Y389632D01*
G02X1582986Y389501I-192J-57D01*
G01X1582983Y389494D01*
X1582864Y389206D01*
G02X1582862Y389201I-187J72D01*
G01X1582859Y389196D01*
X1582842Y389163D01*
Y389162D01*
G02X1582676Y389054I-178J92D01*
G01X1543982D01*
G02X1543948Y389057I1J200D01*
G02X1543914Y389066I34J197D01*
G01X1543881Y389079D01*
X1543868Y389083D01*
G03X1543816Y389090I-52J-193D01*
G01X1534565D01*
G02X1534474Y389112I0J200D01*
G02X1534424Y389148I90J178D01*
G01X1533138Y390434D01*
G02X1533102Y390484I142J140D01*
G02X1533080Y390575I178J91D01*
G01Y494331D01*
G02X1533081Y494350I200J-1D01*
G01Y494351D01*
G02X1533120Y494449I199J-22D01*
G02X1533138Y494470I160J-119D01*
G01X1535241Y496573D01*
G02X1535361Y496631I142J-141D01*
G01X1535372Y496632D01*
X1549107D01*
G02X1549126Y496631I-1J-200D01*
G01X1549127D01*
G02X1549225Y496592I-22J-199D01*
G02X1549246Y496574I-119J-160D01*
G01X1550735Y495085D01*
G03X1550877Y495026I142J141D01*
G01X1551648D01*
G02X1551676Y495024I0J-200D01*
G01X1552059Y494641D01*
G03X1552983Y494258I924J923D01*
G01X1559796D01*
G03X1560720Y494641I0J1306D01*
G01X1563020Y496941D01*
G02X1563162Y497000I142J-141D01*
G01X1638868D01*
G02X1639010Y496941I0J-200D01*
G01X1646239Y489713D01*
G02X1646298Y489571I-141J-142D01*
G01Y468112D01*
X1646291Y468099D01*
G03X1646102Y467369I1315J-730D01*
G01Y467367D01*
G03X1647604Y465865I1502J0D01*
G03X1649106Y467354I0J1502D01*
G01Y467371D01*
G03X1648934Y468067I-1502J-2D01*
G01X1648915Y468101D01*
X1648910Y468111D01*
Y490197D01*
G03X1648528Y491119I-1306J-1D01*
G01X1640416Y499231D01*
G03X1640114Y499456I-923J-924D01*
G02X1640009Y499632I95J176D01*
G01Y499751D01*
G02X1640028Y499773I161J-119D01*
G01X1640029D01*
G02X1640170Y499832I142J-141D01*
G01X1640708D01*
G03X1640994Y499864I3J1266D01*
G01X1640996D01*
X1641002Y499866D01*
X1641062Y499880D01*
X1641105Y499895D01*
X1641106D01*
X1641119Y499900D01*
X1641120D01*
X1641125Y499902D01*
X1641132Y499904D01*
G03X1641138Y499906I-397J1202D01*
G03X1641142Y499908I-87J178D01*
G03X1641552Y500153I-433J1190D01*
G01X1641560Y500161D01*
G02X1641567Y500166I120J-160D01*
G01X1641568Y500167D01*
G03X1641603Y500201I-865J926D01*
G01X1646016Y504615D01*
G02X1646038Y504634I141J-141D01*
G01X1657425D01*
G02X1657567Y504575I0J-200D01*
G01X1662118Y500023D01*
G03X1663042Y499640I924J923D01*
G01X1756272D01*
G02X1756414Y499581I0J-200D01*
G01X1768572Y487423D01*
G03X1769496Y487040I924J923D01*
G01X1774301D01*
G03X1775225Y487423I0J1306D01*
G01X1776502Y488701D01*
G02X1776644Y488760I142J-141D01*
G01X1784602D01*
G02X1784744Y488701I0J-200D01*
G01X1801815Y471629D01*
G02X1801874Y471487I-141J-142D01*
G01Y464479D01*
G02X1801815Y464337I-200J0D01*
G01X1800535Y463057D01*
X1800509Y463049D01*
G03X1799431Y461607I425J-1442D01*
G03X1800933Y460105I1502J0D01*
G03X1802374Y461182I0J1503D01*
G01X1802382Y461208D01*
X1802876Y461702D01*
G02X1802968Y461694I29J-198D01*
G01X1803134Y461639D01*
X1803136Y461638D01*
X1803269Y461591D01*
G02X1803341Y461539I-78J-184D01*
G01X1803357Y461520D01*
X1803406Y461461D01*
Y461460D01*
X1803433Y461433D01*
X1803448Y461368D01*
X1803450Y461361D01*
G03X1804933Y460105I1483J248D01*
G03X1806435Y461583I0J1502D01*
G01Y461612D01*
G03X1806320Y462185I-1502J-3D01*
G01X1806313Y462202D01*
X1806303Y462249D01*
G02X1806327Y462394I196J42D01*
G01X1806338Y462412D01*
X1806394Y462503D01*
G02X1806438Y462548I163J-116D01*
G01X1806666D01*
G02X1806808Y462489I0J-200D01*
G01X1810793Y458505D01*
G02X1810852Y458363I-141J-142D01*
G01Y454000D01*
G02X1810781Y453941I-160J120D01*
G01X1810463Y453782D01*
G02X1810374Y453761I-89J179D01*
G01X1810368D01*
G02X1810256Y453796I1J200D01*
G01X1810249Y453801D01*
G03X1809346Y454103I-904J-1201D01*
G03Y451099I0J-1502D01*
G03X1810251Y451402I0J1503D01*
G01X1810371Y451442D01*
G02X1810403Y451439I-3J-200D01*
G01X1810405D01*
X1810435Y451434D01*
X1810781Y451261D01*
G02X1810852Y451202I-89J-179D01*
G01Y448513D01*
G02X1810779Y448453I-160J120D01*
G01X1810750Y448439D01*
X1810474Y448302D01*
G02X1810363Y448282I-90J179D01*
G01X1810335Y448286D01*
X1810250Y448315D01*
X1810225Y448333D01*
G03X1809338Y448623I-887J-1211D01*
G03Y445619I0J-1502D01*
G01Y445618D01*
G03X1810224Y445907I0J1503D01*
G01X1810250Y445927D01*
X1810319Y445950D01*
G02X1810434Y445954I64J-189D01*
G02X1810450Y445949I-52J-193D01*
G01X1810468Y445943D01*
X1810784Y445787D01*
G02X1810852Y445730I-91J-178D01*
G01Y443521D01*
G02X1810781Y443462I-160J120D01*
G01X1810461Y443303D01*
G02X1810442Y443295I-87J180D01*
G02X1810266Y443313I-70J188D01*
G01X1810248Y443324D01*
X1810241Y443329D01*
G03X1809590Y443598I-883J-1215D01*
G03X1809373Y443616I-232J-1484D01*
G01X1809363D01*
G03X1809353I-5J-1502D01*
G01X1809351D01*
G03X1807856Y442114I7J-1502D01*
G03X1809358Y440612I1502J0D01*
G03X1810253Y440908I0J1501D01*
G01X1810276Y440925D01*
X1810328Y440944D01*
X1810355Y440947D01*
G02X1810461Y440926I16J-200D01*
G01X1810782Y440765D01*
G02X1810852Y440706I-90J-178D01*
G01Y436272D01*
G02X1810769Y436208I-159J121D01*
G01X1810432Y436076D01*
G02X1810295Y436080I-63J190D01*
G01X1810199Y436120D01*
X1810171Y436149D01*
G03X1809095Y436603I-1076J-1048D01*
G03Y433599I0J-1502D01*
G03X1810171Y434053I0J1502D01*
G01X1810199Y434082D01*
X1810295Y434122D01*
G02X1810432Y434126I74J-186D01*
G01X1810769Y433994D01*
G02X1810852Y433930I-76J-185D01*
G01Y405207D01*
G02X1810793Y405065I-200J0D01*
G01X1780331Y374603D01*
G02X1780189Y374544I-142J141D01*
G01X1754657D01*
G03X1753735Y374162I1J-1306D01*
G01X1752098Y372525D01*
X1752072Y372517D01*
G03X1750995Y371076I426J-1441D01*
G03X1752497Y369574I1502J0D01*
G03X1753938Y370651I0J1503D01*
G01X1753946Y370677D01*
X1755141Y371873D01*
G02X1755283Y371932I142J-141D01*
G01X1780815D01*
G03X1781737Y372314I-1J1306D01*
G01X1813082Y403659D01*
G03X1813464Y404581I-924J923D01*
G01Y458989D01*
G03X1813082Y459911I-1306J-1D01*
G01X1808214Y464779D01*
G03X1807290Y465162I-924J-923D01*
G01X1804529D01*
G02X1804488Y465203I119J160D01*
G01Y472111D01*
G03X1804105Y473035I-1306J0D01*
G01X1786150Y490990D01*
G03X1785228Y491372I-923J-924D01*
G01X1776018D01*
G03X1775096Y490990I1J-1306D01*
G01X1773819Y489713D01*
G02X1773677Y489654I-142J141D01*
G01X1771732D01*
G02X1771664Y489744I119J161D01*
G01X1771626Y489865D01*
Y489868D01*
X1771568Y489953D01*
G02X1771533Y490062I165J113D01*
G01Y490160D01*
X1771545Y490193D01*
G03X1771637Y490672I-1410J519D01*
G01Y490722D01*
G03X1770560Y492152I-1502J-11D01*
G01X1770534Y492160D01*
X1757302Y505392D01*
G03X1756380Y505774I-923J-924D01*
G01X1662592D01*
G02X1662450Y505833I0J200D01*
G01X1659696Y508588D01*
G03X1658774Y508970I-923J-924D01*
G01X1643149D01*
G03X1642227Y508588I1J-1306D01*
G01X1637913Y504273D01*
G02X1637771Y504214I-142J141D01*
G01X1624370D01*
G02X1624290Y504374I120J160D01*
G01Y539486D01*
G02X1624292Y539514I200J0D01*
G01X1624661Y539883D01*
G02X1624803Y539942I142J-141D01*
G01X1688156D01*
G02X1688178Y539923I-119J-160D01*
G01X1688182Y539919D01*
X1688334Y539744D01*
X1688384Y539687D01*
G02X1688433Y539556I-151J-131D01*
G01Y539535D01*
X1688432Y539528D01*
Y539527D01*
X1688431Y539519D01*
X1688430Y539510D01*
G03X1688429Y539501I1492J-170D01*
G01Y539493D01*
X1688426Y539477D01*
G03X1688425Y539466I199J-24D01*
G01Y539460D01*
X1688424Y539454D01*
Y539449D01*
G03X1688421Y539417I1494J-156D01*
G01Y539409D01*
G03X1688420Y539400I1491J-170D01*
G01Y539397D01*
G03X1688418Y539342I1500J-82D01*
G01Y539311D01*
G03X1689920Y537813I1502J4D01*
G03X1691422Y539315I0J1502D01*
G01Y539374D01*
G03X1691081Y540268I-1502J-61D01*
G01X1691058Y540296D01*
X1691036Y540361D01*
Y540400D01*
X1691040Y540532D01*
G02X1691041Y540542I199J-15D01*
G01X1693849Y543350D01*
G02X1693877Y543352I28J-198D01*
G01X1746178D01*
G02X1746207Y543350I1J-200D01*
G01X1749248Y540309D01*
G03X1750878Y539634I1630J1631D01*
G01X1750879D01*
G03X1753020Y541082I0J2307D01*
G01X1753042Y541138D01*
X1753057Y541148D01*
X1753105Y541181D01*
G02X1753170Y541210I113J-165D01*
G01X1753209Y541220D01*
X1753248Y541214D01*
G03X1753445Y541197I227J1485D01*
G01X1753477D01*
G03X1754196Y541380I0J1503D01*
G01X1754232Y541400D01*
X1754278Y541413D01*
G02X1754361Y541418I53J-193D01*
G01X1754458Y541321D01*
G03X1756088Y540646I1630J1631D01*
G01X1756089D01*
G03X1757970Y541617I0J2307D01*
G01Y541619D01*
X1758006Y541668D01*
G02X1758059Y541690I102J-172D01*
G01X1758060D01*
X1758113Y541703D01*
X1758115D01*
X1758149Y541711D01*
G02X1758245Y541707I40J-196D01*
G01X1758270Y541699D01*
X1758281Y541694D01*
G03X1758956Y541533I677J1342D01*
G01X1758957D01*
G03X1760459Y542972I0J1503D01*
G01X1760462Y542998D01*
G02X1760504Y543090I197J-34D01*
G02X1760521Y543108I154J-128D01*
G01X1760597Y543180D01*
X1760717Y543295D01*
G02X1760736Y543311I138J-145D01*
G01X1760737Y543312D01*
G02X1760857Y543352I120J-160D01*
G01X1811144D01*
G02X1811182Y543348I-2J-200D01*
G02X1811284Y543295I-37J-196D01*
G01X1814771Y539808D01*
G02X1814824Y539706I-143J-139D01*
G02X1814828Y539668I-196J-40D01*
G01Y297490D01*
G03X1814887Y297348I200J0D01*
G01X1829949Y282286D01*
G02X1830002Y282184I-143J-139D01*
G02X1830006Y282146I-196J-40D01*
G01Y9389D01*
G02X1829947Y9247I-200J0D01*
G01X1827159Y6459D01*
G02X1827017Y6400I-142J141D01*
G37*
G36*
G01X1081725Y1645992D02*
X1833071D01*
G02X1838945Y1640118I0J-5874D01*
G01Y1249999D01*
X1836948D01*
Y1640118D01*
G03X1833073Y1643994I-3876J0D01*
G01X1633526D01*
Y1644873D01*
X1578560D01*
Y1643994D01*
X1285912D01*
Y1644677D01*
X1232543D01*
Y1643994D01*
X1081724D01*
G03X1078854Y1642722I1J-3877D01*
G02X1070058Y1638822I-8797J7971D01*
G01X800966D01*
G02X792169Y1642722I0J11872D01*
G03X789299Y1643994I-2871J-2603D01*
G01X608951D01*
Y1644464D01*
X555228D01*
Y1643994D01*
X262776D01*
Y1644377D01*
X208818D01*
Y1643994D01*
X7874D01*
G03X3998Y1640118I0J-3876D01*
G01Y1244645D01*
X2000D01*
Y1640118D01*
G02X7874Y1645992I5874J0D01*
G01X789298D01*
G02X793649Y1644063I-1J-5873D01*
G03X800966Y1640819I7317J6631D01*
G01X1070058D01*
G03X1077374Y1644063I-1J9873D01*
G02X1081725Y1645992I4352J-3945D01*
G37*
G36*
G01X43028Y1096342D02*
X74410D01*
G02X74552Y1096283I0J-200D01*
G01X75858Y1094977D01*
X75873Y1094938D01*
G03X76319Y1094261I1860J740D01*
G01X77471Y1093108D01*
G02X77530Y1092967I-141J-142D01*
G01Y961798D01*
G03X77589Y961656I200J0D01*
G01X83713Y955532D01*
G03X83855Y955473I142J141D01*
G01X368786D01*
G02X368971Y955348I0J-200D01*
G01X369133Y954945D01*
X369107Y954827D01*
X369062Y954784D01*
G03X368599Y953699I1040J-1085D01*
G03X371603I1502J0D01*
G03X371140Y954784I-1503J0D01*
G01X371095Y954827D01*
X371069Y954945D01*
X371231Y955348D01*
G02X371416Y955473I185J-75D01*
G01X378235D01*
G02X378354Y955434I0J-200D01*
G03X379245Y955141I891J1208D01*
G03X379865Y955275I0J1501D01*
G01X379923Y955301D01*
X380044Y955279D01*
X382322Y953001D01*
G02X382381Y952859I-141J-142D01*
G01Y944927D01*
G02X382322Y944785I-200J0D01*
G01X373895Y936358D01*
X373753Y936344D01*
X373693Y936384D01*
G03X373219Y936594I-836J-1248D01*
G01X373183Y936603D01*
X373124Y936643D01*
X372931Y936919D01*
X372913Y936988D01*
X372917Y937025D01*
G03X372926Y937185I-1493J164D01*
G03X371424Y938687I-1502J0D01*
G03X370699Y938501I-1J-1502D01*
G01X370667Y938483D01*
X370595Y938473D01*
X370264Y938547D01*
X370204Y938587D01*
X370182Y938617D01*
G03X368964Y939240I-1218J-879D01*
G03Y936236I0J-1502D01*
G03X369689Y936422I1J1502D01*
G01X369721Y936440D01*
X369793Y936450D01*
X370124Y936376D01*
X370184Y936336D01*
X370206Y936306D01*
G03X371063Y935727I1218J879D01*
G01X371099Y935718D01*
X371158Y935678D01*
X371351Y935402D01*
X371369Y935333D01*
X371365Y935296D01*
G03X371356Y935136I1493J-164D01*
G01Y935085D01*
X371326Y935011D01*
X371098Y934781D01*
G02X370956Y934722I-142J141D01*
G01X368351D01*
X368242Y934809D01*
X368227Y934878D01*
G03X365295I-1466J-328D01*
G01X365280Y934809D01*
X365171Y934722D01*
X280111D01*
G02X279927Y934844I0J200D01*
G01X279759Y935237D01*
X279781Y935356D01*
X279823Y935399D01*
G03X280241Y936439I-1085J1040D01*
G03X277237I-1502J0D01*
G03X277655Y935399I1503J0D01*
G01X277697Y935356D01*
X277719Y935237D01*
X277551Y934844D01*
G02X277367Y934722I-184J78D01*
G01X70528D01*
G02X70386Y934781I0J200D01*
G01X64768Y940399D01*
G02X64709Y940541I141J142D01*
G01Y1083944D01*
G03X64650Y1084086I-200J0D01*
G01X63491Y1085245D01*
X63476Y1085278D01*
G03X62731Y1086023I-1367J-622D01*
G01X62698Y1086038D01*
X62237Y1086499D01*
G03X62095Y1086558I-142J-141D01*
G01X56906D01*
G02X56765Y1086616I0J200D01*
G01X56537Y1086842D01*
X56506Y1086913D01*
Y1086954D01*
G03X53502I-1502J-17D01*
G01Y1086913D01*
X53471Y1086842D01*
X53243Y1086616D01*
G02X53102Y1086558I-141J142D01*
G01X52268D01*
G02X52126Y1086617I0J200D01*
G01X51897Y1086849D01*
X51867Y1086922D01*
X51868Y1086963D01*
Y1086981D01*
G03X48864I-1502J0D01*
G01Y1086963D01*
X48865Y1086922D01*
X48835Y1086849D01*
X48606Y1086617D01*
G02X48464Y1086558I-142J141D01*
G01X45959D01*
X45849Y1086647D01*
X45834Y1086716D01*
G03X44365Y1087906I-1469J-312D01*
G03X44041Y1087871I-2J-1502D01*
G01X43991Y1087860D01*
X43893Y1087888D01*
X41908Y1089873D01*
G02X41849Y1090015I141J142D01*
G01Y1095163D01*
G02X41908Y1095305I200J0D01*
G01X42886Y1096283D01*
G02X43028Y1096342I142J-141D01*
G37*
G36*
G01X137657Y54588D02*
X166656D01*
X166715D01*
X166891Y54412D01*
Y52762D01*
X166720Y52591D01*
X166656D01*
X137657D01*
G03X131720Y46654I0J-5937D01*
G01Y7874D01*
G02X125846Y2000I-5874J0D01*
G01X78602D01*
G02X72728Y7874I0J5874D01*
G01Y45195D01*
X73413Y45880D01*
X74726D01*
Y7874D01*
G03X78602Y3998I3876J0D01*
G01X125846D01*
G03X129722Y7874I0J3876D01*
G01Y46654D01*
G02X137657Y54588I7935J-1D01*
G37*
G36*
G01X147061Y1012003D02*
X370908D01*
G02X371050Y1011944I0J-200D01*
G01X379717Y1003277D01*
X379747Y1003195D01*
X379743Y1003150D01*
G03X379736Y1003008I1634J-152D01*
G03X379739Y1002924I1640J17D01*
G01X379741Y1002875D01*
X379701Y1002787D01*
X379366Y1002524D01*
X379271Y1002507D01*
X379224Y1002521D01*
G03X378790Y1002585I-434J-1438D01*
G03X380292Y1001085I0J-1502D01*
G01Y1001135D01*
X380336Y1001220D01*
X380684Y1001466D01*
X380779Y1001479D01*
X380826Y1001463D01*
G03X381377Y1001368I550J1545D01*
G03X381519Y1001374I2J1640D01*
G01X381564Y1001378D01*
X381646Y1001348D01*
X381651Y1001343D01*
X381724Y1001313D01*
X394372D01*
G02X394514Y1001254I0J-200D01*
G01X420527Y975241D01*
G02X420586Y975099I-141J-142D01*
G01Y962346D01*
G02X420527Y962204I-200J0D01*
G01X419035Y960712D01*
G02X418893Y960653I-142J141D01*
G01X400162D01*
G02X400046Y960690I0J200D01*
G03X398300I-873J-1221D01*
G02X398184Y960653I-116J163D01*
G01X391564D01*
G02X391397Y960742I-1J200D01*
G03X388903I-1247J-837D01*
G02X388736Y960653I-166J111D01*
G01X386910D01*
G02X386740Y960747I0J200D01*
G03X384194I-1273J-797D01*
G02X384024Y960653I-170J106D01*
G01X380596D01*
G02X380427Y960746I0J200D01*
G01X380219Y961075D01*
X380212Y961176D01*
X380234Y961223D01*
G03X380377Y961862I-1359J640D01*
G03X377373I-1502J0D01*
G03X377516Y961223I1502J1D01*
G01X377538Y961176D01*
X377531Y961075D01*
X377323Y960746D01*
G02X377154Y960653I-169J107D01*
G01X371561D01*
G02X371402Y960731I-1J200D01*
G03X369026I-1188J-919D01*
G02X368867Y960653I-158J122D01*
G01X97525D01*
G02X97383Y960712I0J200D01*
G01X87349Y970746D01*
G02X87290Y970888I141J142D01*
G01Y1005282D01*
G02X87349Y1005424I200J0D01*
G01X87968Y1006043D01*
X88012Y1006069D01*
X88037Y1006076D01*
G03X89078Y1007117I-405J1446D01*
G01X89085Y1007142D01*
X89111Y1007186D01*
X93869Y1011944D01*
G02X94011Y1012003I142J-141D01*
G01X109380D01*
G02X109515Y1011950I-1J-200D01*
G01X109742Y1011741D01*
X109775Y1011674D01*
X109778Y1011636D01*
G03X112772I1497J126D01*
G01X112775Y1011674D01*
X112808Y1011741D01*
X113035Y1011950D01*
G02X113170Y1012003I136J-147D01*
G01X134981D01*
X135084Y1011929D01*
X135105Y1011868D01*
G03X135621Y1011156I1421J487D01*
G01X135658Y1011127D01*
X135699Y1011046D01*
X135705Y1010637D01*
X135666Y1010554D01*
X135630Y1010525D01*
G03X135069Y1009354I942J-1171D01*
G03X138073I1502J0D01*
G03X137476Y1010552I-1502J-1D01*
G01X137439Y1010581D01*
X137398Y1010662D01*
X137392Y1011071D01*
X137431Y1011154D01*
X137467Y1011183D01*
G03X137947Y1011868I-941J1170D01*
G01X137968Y1011929D01*
X138071Y1012003D01*
X140481D01*
X140584Y1011929D01*
X140605Y1011868D01*
G03X143447I1421J486D01*
G01X143468Y1011929D01*
X143571Y1012003D01*
X143971D01*
X144074Y1011929D01*
X144095Y1011868D01*
G03X146937I1421J486D01*
G01X146958Y1011929D01*
X147061Y1012003D01*
G37*
G36*
G01X184350Y1145591D02*
G03Y1143187I0J-1202D01*
G03X184673Y1143232I-3J1202D01*
G01X184675D01*
G02X184848Y1143199I53J-193D01*
G01X185103Y1143006D01*
G02X185182Y1142847I-121J-159D01*
G01Y1142191D01*
G02X185103Y1142032I-200J0D01*
G01X184848Y1141839D01*
G02X184675Y1141806I-120J160D01*
G01X184674D01*
G03X184350Y1141851I-326J-1157D01*
G03Y1139447I0J-1202D01*
G03X184673Y1139492I-3J1202D01*
G01X184675D01*
G02X184848Y1139459I53J-193D01*
G01X185103Y1139266D01*
G02X185182Y1139107I-121J-159D01*
G01Y1138451D01*
G02X185103Y1138292I-200J0D01*
G01X184848Y1138099D01*
G02X184675Y1138066I-120J160D01*
G01X184674D01*
G03X184350Y1138111I-326J-1157D01*
G03Y1135707I0J-1202D01*
G03X184673Y1135752I-3J1202D01*
G01X184675D01*
G02X184848Y1135719I53J-193D01*
G01X185103Y1135526D01*
G02X185182Y1135367I-121J-159D01*
G01Y1134711D01*
G02X185103Y1134552I-200J0D01*
G01X184848Y1134359D01*
G02X184675Y1134326I-120J160D01*
G01X184674D01*
G03X184350Y1134371I-326J-1157D01*
G03Y1131967I0J-1202D01*
G03X184673Y1132012I-3J1202D01*
G01X184675D01*
G02X184848Y1131979I53J-193D01*
G01X185103Y1131786D01*
G02X185182Y1131627I-121J-159D01*
G01Y1130971D01*
G02X185103Y1130812I-200J0D01*
G01X184848Y1130619D01*
G02X184675Y1130586I-120J160D01*
G01X184674D01*
G03X184350Y1130631I-326J-1157D01*
G03Y1128227I0J-1202D01*
G03X184673Y1128272I-3J1202D01*
G01X184675D01*
G02X184848Y1128239I53J-193D01*
G01X185103Y1128046D01*
G02X185182Y1127887I-121J-159D01*
G01Y1127230D01*
G02X185103Y1127071I-200J0D01*
G01X184848Y1126878D01*
G02X184675Y1126845I-120J160D01*
G01X184674D01*
G03X184350Y1126890I-326J-1157D01*
G03Y1124486I0J-1202D01*
G03X184673Y1124531I-3J1202D01*
G01X184675D01*
G02X184848Y1124498I53J-193D01*
G01X185103Y1124305D01*
G02X185182Y1124146I-121J-159D01*
G01Y1123490D01*
G02X185103Y1123331I-200J0D01*
G01X184848Y1123138D01*
G02X184675Y1123105I-120J160D01*
G01X184674D01*
G03X184350Y1123150I-326J-1157D01*
G03Y1120746I0J-1202D01*
G03X184892Y1120875I0J1203D01*
G01X184913Y1120886D01*
X184958Y1120897D01*
X184982D01*
G02X185182Y1120697I0J-200D01*
G01Y1120498D01*
G02X185123Y1120356I-200J0D01*
G01X184185Y1119418D01*
X184135Y1119391D01*
X184106Y1119385D01*
G03X183430Y1118981I245J-1177D01*
G02X183276Y1118910I-153J129D01*
G01X181684D01*
G02X181530Y1118981I-1J200D01*
G03X179690I-920J-774D01*
G02X179536Y1118910I-153J129D01*
G01X177944D01*
G02X177790Y1118981I-1J200D01*
G03X175950I-920J-774D01*
G02X175796Y1118910I-153J129D01*
G01X162983D01*
G02X162829Y1118981I-1J200D01*
G03X160989I-920J-774D01*
G02X160835Y1118910I-153J129D01*
G01X159243D01*
G02X159089Y1118981I-1J200D01*
G03X157249I-920J-774D01*
G02X157095Y1118910I-153J129D01*
G01X155503D01*
G02X155349Y1118981I-1J200D01*
G03X153509I-920J-774D01*
G02X153355Y1118910I-153J129D01*
G01X151763D01*
G02X151609Y1118981I-1J200D01*
G03X149769I-920J-774D01*
G02X149615Y1118910I-153J129D01*
G01X148022D01*
G02X147868Y1118981I-1J200D01*
G03X146028I-920J-774D01*
G02X145874Y1118910I-153J129D01*
G01X144282D01*
G02X144128Y1118981I-1J200D01*
G03X142288I-920J-774D01*
G02X142134Y1118910I-153J129D01*
G01X134810D01*
G02X134700Y1118943I0J200D01*
G03X133907Y1119193I-831J-1252D01*
G02X133770Y1119252I5J200D01*
G01X131797Y1121225D01*
G03X131655Y1121284I-142J-141D01*
G01X126673D01*
G02X126531Y1121343I0J200D01*
G01X123800Y1124074D01*
G02X123741Y1124216I141J142D01*
G01Y1125558D01*
G02X123833Y1125726I200J0D01*
G01X124116Y1125909D01*
G02X124306Y1125923I108J-169D01*
G03X124925Y1125789I620J1368D01*
G03Y1128793I0J1502D01*
G03X124307Y1128659I2J-1502D01*
G01X124305D01*
X124259Y1128638D01*
X124159Y1128646D01*
X123833Y1128856D01*
G02X123741Y1129024I108J168D01*
G01Y1130940D01*
G02X123800Y1131082I200J0D01*
G01X123818Y1131100D01*
G02X124036Y1131144I142J-141D01*
G01X126862Y1129972D01*
G03X128360Y1129674I1500J3629D01*
G01X128887D01*
G02X129063Y1129570I1J-200D01*
G03X130380Y1128789I1317J720D01*
G03X131607Y1129424I0J1503D01*
G02X131912Y1129450I163J-115D01*
G01X133379Y1127983D01*
G03X136155Y1126832I2777J2775D01*
G01X140062D01*
G03X141446Y1127085I-3J3927D01*
G01X141481Y1127098D01*
X141964D01*
G02X142144Y1126984I-1J-200D01*
G01X142300Y1126657D01*
G02X142276Y1126446I-180J-86D01*
G01X142275Y1126445D01*
G03X142006Y1125688I933J-758D01*
G03X144410I1202J0D01*
G03X144141Y1126444I-1202J-2D01*
G02X144140Y1126446I175J89D01*
G02X144116Y1126657I156J125D01*
G01X144272Y1126984D01*
G02X144452Y1127098I181J-86D01*
G01X145704D01*
G02X145884Y1126984I-1J-200D01*
G01X146040Y1126657D01*
G02X146016Y1126446I-180J-86D01*
G01X146015Y1126445D01*
G03X145746Y1125688I933J-758D01*
G03X148150I1202J0D01*
G03X147881Y1126444I-1202J-2D01*
G02X147880Y1126446I175J89D01*
G02X147856Y1126657I156J125D01*
G01X148012Y1126984D01*
G02X148192Y1127098I181J-86D01*
G01X149445D01*
G02X149625Y1126984I-1J-200D01*
G01X149781Y1126657D01*
G02X149757Y1126446I-180J-86D01*
G01X149756Y1126445D01*
G03X149487Y1125688I933J-758D01*
G03X151891I1202J0D01*
G03X151297Y1126725I-1202J0D01*
G02X151198Y1126898I101J173D01*
G02X151398Y1127098I200J0D01*
G01X151847D01*
G03X154551Y1128218I-1J3826D01*
G01X154567Y1128235D01*
G03X155129Y1128452I-138J1194D01*
G02X155246Y1128490I117J-162D01*
G01X157352D01*
G02X157469Y1128453I1J-200D01*
G03X157798Y1128286I702J975D01*
G01X157821Y1128278D01*
X157861Y1128254D01*
X157896Y1128218D01*
G03X160600Y1127098I2705J2706D01*
G01X160665D01*
G02X160845Y1126984I-1J-200D01*
G01X161001Y1126657D01*
G02X160977Y1126446I-180J-86D01*
G01X160976Y1126445D01*
G03X160707Y1125688I933J-758D01*
G03X163111I1202J0D01*
G03X162517Y1126725I-1202J0D01*
G02X162418Y1126898I101J173D01*
G02X162618Y1127098I200J0D01*
G01X163067D01*
G03X165771Y1128218I-1J3826D01*
G01X165787Y1128235D01*
G03X166349Y1128452I-138J1194D01*
G02X166466Y1128490I117J-162D01*
G01X168570D01*
G02X168687Y1128452I0J-200D01*
G03X170091I702J977D01*
G02X170208Y1128490I117J-162D01*
G01X172310D01*
G02X172427Y1128452I0J-200D01*
G03X173129Y1128226I702J977D01*
G03X174291Y1129121I0J1202D01*
G01X174298Y1129147D01*
X174324Y1129192D01*
X176572Y1131440D01*
G03X176631Y1131582I-141J142D01*
G01Y1131613D01*
X176657Y1131681D01*
X176863Y1131908D01*
G02X176990Y1131973I149J-134D01*
G01X176991D01*
G03Y1134365I-121J1196D01*
G01X176990D01*
G02X176863Y1134430I22J199D01*
G01X176683Y1134629D01*
G02X176631Y1134763I148J134D01*
G01Y1135366D01*
X176647Y1135404D01*
G03X176763Y1135712I-3519J1501D01*
G03X176870Y1135707I110J1197D01*
G03Y1138111I0J1202D01*
G03X176763Y1138106I3J-1202D01*
G03X176647Y1138414I-3635J-1193D01*
G01X176631Y1138452D01*
Y1139055D01*
G02X176683Y1139189I200J0D01*
G01X176863Y1139388D01*
G02X176990Y1139453I149J-134D01*
G01X176991D01*
G03Y1141845I-121J1196D01*
G01X176990D01*
G02X176863Y1141910I22J199D01*
G01X176683Y1142109D01*
G02X176631Y1142243I148J134D01*
G01Y1142795D01*
G02X176683Y1142929I200J0D01*
G01X176863Y1143128D01*
G02X176990Y1143193I149J-134D01*
G01X176991D01*
G03Y1145585I-121J1196D01*
G01X176990D01*
G02X176863Y1145650I22J199D01*
G01X176683Y1145849D01*
G02X176631Y1145983I148J134D01*
G01Y1146535D01*
G02X176683Y1146669I200J0D01*
G01X176863Y1146868D01*
G02X176990Y1146933I149J-134D01*
G01X176991D01*
G03Y1149325I-121J1196D01*
G01X176990D01*
G02X176863Y1149390I22J199D01*
G01X176683Y1149589D01*
G02X176631Y1149723I148J134D01*
G01Y1150276D01*
G02X176683Y1150410I200J0D01*
G01X176863Y1150609D01*
G02X176990Y1150674I149J-134D01*
G01X176991D01*
G03X178072Y1151870I-121J1196D01*
G03X178015Y1152236I-1202J0D01*
G02X178044Y1152415I190J61D01*
G01X178234Y1152676D01*
G02X178396Y1152758I162J-118D01*
G01X179084D01*
G02X179246Y1152676I0J-200D01*
G01X179436Y1152415D01*
G02X179465Y1152236I-161J-118D01*
G03X179408Y1151870I1145J-366D01*
G03X181812I1202J0D01*
G03X181755Y1152236I-1202J0D01*
G02X181784Y1152415I190J61D01*
G01X181974Y1152676D01*
G02X182136Y1152758I162J-118D01*
G01X184545D01*
G02X184687Y1152699I0J-200D01*
G01X185123Y1152263D01*
G02X185182Y1152121I-141J-142D01*
G01Y1145931D01*
G02X185103Y1145772I-200J0D01*
G01X184848Y1145579D01*
G02X184675Y1145546I-120J160D01*
G01X184674D01*
G03X184350Y1145591I-326J-1157D01*
G37*
G36*
G01X189603Y1152796D02*
X190317D01*
G02X190480Y1152712I0J-200D01*
G01X190698Y1152406D01*
X190711Y1152311D01*
X190695Y1152264D01*
G03X190628Y1151869I1135J-396D01*
G03X191830Y1150667I1202J0D01*
G03X192126Y1150704I0J1202D01*
G01X192171Y1150716D01*
X192261Y1150697D01*
X192547Y1150474D01*
G02X192624Y1150316I-123J-158D01*
G01Y1149682D01*
G02X192547Y1149524I-200J0D01*
G01X192261Y1149301D01*
X192171Y1149282D01*
X192126Y1149294D01*
G03X191830Y1149331I-296J-1166D01*
G03Y1146927I0J-1202D01*
G03X192126Y1146964I0J1203D01*
G01X192171Y1146976D01*
X192261Y1146957D01*
X192547Y1146734D01*
G02X192624Y1146576I-123J-158D01*
G01Y1145942D01*
G02X192547Y1145784I-200J0D01*
G01X192261Y1145561D01*
X192171Y1145542D01*
X192126Y1145554D01*
G03X191830Y1145591I-296J-1166D01*
G03Y1143187I0J-1202D01*
G03X192126Y1143224I0J1202D01*
G01X192171Y1143236D01*
X192261Y1143217D01*
X192547Y1142994D01*
G02X192624Y1142836I-123J-158D01*
G01Y1142202D01*
G02X192547Y1142044I-200J0D01*
G01X192261Y1141821D01*
X192171Y1141802D01*
X192126Y1141814D01*
G03X191830Y1141851I-296J-1165D01*
G03Y1139447I0J-1202D01*
G03X192126Y1139484I0J1203D01*
G01X192171Y1139496D01*
X192261Y1139477D01*
X192547Y1139254D01*
G02X192624Y1139096I-123J-158D01*
G01Y1138462D01*
G02X192547Y1138304I-200J0D01*
G01X192261Y1138081D01*
X192171Y1138062D01*
X192126Y1138074D01*
G03X191830Y1138111I-296J-1165D01*
G03Y1135707I0J-1202D01*
G03X192126Y1135744I0J1202D01*
G01X192171Y1135756D01*
X192261Y1135737D01*
X192547Y1135514D01*
G02X192624Y1135356I-123J-158D01*
G01Y1134722D01*
G02X192547Y1134564I-200J0D01*
G01X192261Y1134341D01*
X192171Y1134322D01*
X192126Y1134334D01*
G03X191830Y1134371I-296J-1165D01*
G03Y1131967I0J-1202D01*
G03X192126Y1132004I0J1202D01*
G01X192171Y1132016D01*
X192261Y1131997D01*
X192547Y1131774D01*
G02X192624Y1131616I-123J-158D01*
G01Y1130982D01*
G02X192547Y1130824I-200J0D01*
G01X192261Y1130601D01*
X192171Y1130582D01*
X192126Y1130594D01*
G03X191830Y1130631I-296J-1166D01*
G03Y1128227I0J-1202D01*
G03X192126Y1128264I0J1202D01*
G01X192171Y1128276D01*
X192261Y1128257D01*
X192547Y1128034D01*
G02X192624Y1127876I-123J-158D01*
G01Y1127241D01*
G02X192547Y1127083I-200J0D01*
G01X192261Y1126860D01*
X192171Y1126841D01*
X192126Y1126853D01*
G03X191830Y1126890I-296J-1165D01*
G03Y1124486I0J-1202D01*
G03X192126Y1124523I0J1202D01*
G01X192171Y1124535D01*
X192261Y1124516D01*
X192547Y1124293D01*
G02X192624Y1124135I-123J-158D01*
G01Y1123501D01*
G02X192547Y1123343I-200J0D01*
G01X192261Y1123120D01*
X192171Y1123101D01*
X192126Y1123113D01*
G03X191830Y1123150I-296J-1165D01*
G03Y1120746I0J-1202D01*
G03X192126Y1120783I0J1203D01*
G01X192171Y1120795D01*
X192261Y1120776D01*
X192547Y1120553D01*
G02X192624Y1120395I-123J-158D01*
G01Y1119761D01*
G02X192547Y1119603I-200J0D01*
G01X192261Y1119380D01*
X192171Y1119361D01*
X192126Y1119373D01*
G03X191830Y1119410I-296J-1165D01*
G03Y1117006I0J-1202D01*
G03X192126Y1117043I0J1202D01*
G01X192171Y1117055D01*
X192261Y1117036D01*
X192547Y1116813D01*
G02X192624Y1116655I-123J-158D01*
G01Y1116021D01*
G02X192547Y1115863I-200J0D01*
G01X192261Y1115640D01*
X192171Y1115621D01*
X192126Y1115633D01*
G03X191830Y1115670I-296J-1166D01*
G03Y1113266I0J-1202D01*
G03X192126Y1113303I0J1202D01*
G01X192171Y1113315D01*
X192261Y1113296D01*
X192547Y1113073D01*
G02X192624Y1112915I-123J-158D01*
G01Y1110599D01*
G02X192566Y1110458I-200J0D01*
G01X191496Y1109388D01*
G02X191354Y1109329I-142J141D01*
G01X191135D01*
X191042Y1109384D01*
X191015Y1109433D01*
G03X188905I-1055J-574D01*
G01X188878Y1109384D01*
X188785Y1109329D01*
X187395D01*
X187302Y1109384D01*
X187275Y1109433D01*
G03X185165I-1055J-574D01*
G01X185138Y1109384D01*
X185045Y1109329D01*
X183655D01*
X183562Y1109384D01*
X183535Y1109433D01*
G03X181425I-1055J-574D01*
G01X181398Y1109384D01*
X181305Y1109329D01*
X179915D01*
X179822Y1109384D01*
X179795Y1109433D01*
G03X177685I-1055J-574D01*
G01X177658Y1109384D01*
X177565Y1109329D01*
X176174D01*
X176081Y1109384D01*
X176054Y1109433D01*
G03X174999Y1110060I-1055J-574D01*
G03X174777Y1110039I2J-1202D01*
G01X174728Y1110030D01*
X174635Y1110059D01*
X174330Y1110364D01*
X174301Y1110457D01*
X174310Y1110506D01*
G03X174331Y1110728I-1181J224D01*
G03X171927I-1202J0D01*
G03X172189Y1109978I1202J-1D01*
G01X172225Y1109933D01*
X172238Y1109819D01*
X172057Y1109442D01*
G02X171877Y1109329I-180J87D01*
G01X170641D01*
G02X170461Y1109442I0J200D01*
G01X170280Y1109819D01*
X170293Y1109933D01*
X170329Y1109978D01*
G03X170591Y1110728I-940J749D01*
G03X168187I-1202J0D01*
G03X168449Y1109978I1202J-1D01*
G01X168485Y1109933D01*
X168498Y1109819D01*
X168317Y1109442D01*
G02X168137Y1109329I-180J87D01*
G01X166901D01*
G02X166721Y1109442I0J200D01*
G01X166540Y1109819D01*
X166553Y1109933D01*
X166589Y1109978D01*
G03X166851Y1110728I-940J749D01*
G03X164447I-1202J0D01*
G03X164709Y1109978I1202J-1D01*
G01X164745Y1109933D01*
X164758Y1109819D01*
X164577Y1109442D01*
G02X164397Y1109329I-180J87D01*
G01X163161D01*
G02X162981Y1109442I0J200D01*
G01X162800Y1109819D01*
X162813Y1109933D01*
X162849Y1109978D01*
G03X163111Y1110728I-940J749D01*
G03X160707I-1202J0D01*
G03X160969Y1109978I1202J-1D01*
G01X161005Y1109933D01*
X161018Y1109819D01*
X160837Y1109442D01*
G02X160657Y1109329I-180J87D01*
G01X159421D01*
G02X159241Y1109442I0J200D01*
G01X159060Y1109819D01*
X159073Y1109933D01*
X159109Y1109978D01*
G03X159371Y1110728I-940J749D01*
G03X156967I-1202J0D01*
G03X157229Y1109978I1202J-1D01*
G01X157265Y1109933D01*
X157278Y1109819D01*
X157097Y1109442D01*
G02X156917Y1109329I-180J87D01*
G01X155681D01*
G02X155501Y1109442I0J200D01*
G01X155320Y1109819D01*
X155333Y1109933D01*
X155369Y1109978D01*
G03X155631Y1110728I-940J749D01*
G03X153227I-1202J0D01*
G03X153489Y1109978I1202J-1D01*
G01X153525Y1109933D01*
X153538Y1109819D01*
X153357Y1109442D01*
G02X153177Y1109329I-180J87D01*
G01X151941D01*
G02X151761Y1109442I0J200D01*
G01X151580Y1109819D01*
X151593Y1109933D01*
X151629Y1109978D01*
G03X151891Y1110728I-940J749D01*
G03X149487I-1202J0D01*
G03X149749Y1109978I1202J-1D01*
G01X149785Y1109933D01*
X149798Y1109819D01*
X149617Y1109442D01*
G02X149437Y1109329I-180J87D01*
G01X148200D01*
G02X148020Y1109442I0J200D01*
G01X147839Y1109819D01*
X147852Y1109933D01*
X147888Y1109978D01*
G03X148150Y1110728I-940J749D01*
G03X145746I-1202J0D01*
G03X146008Y1109978I1202J-1D01*
G01X146044Y1109933D01*
X146057Y1109819D01*
X145876Y1109442D01*
G02X145696Y1109329I-180J87D01*
G01X144460D01*
G02X144280Y1109442I0J200D01*
G01X144099Y1109819D01*
X144112Y1109933D01*
X144148Y1109978D01*
G03X144410Y1110728I-940J749D01*
G03X142006I-1202J0D01*
G03X142268Y1109978I1202J-1D01*
G01X142304Y1109933D01*
X142317Y1109819D01*
X142136Y1109442D01*
G02X141956Y1109329I-180J87D01*
G01X124774D01*
G02X124632Y1109388I0J200D01*
G01X123167Y1110853D01*
G02X123108Y1110995I141J142D01*
G01Y1113422D01*
G02X123237Y1113609I200J0D01*
G01X123644Y1113765D01*
X123764Y1113736D01*
X123806Y1113689D01*
G03X124925Y1113189I1119J1002D01*
G03Y1116193I0J1502D01*
G03X123806Y1115693I0J-1502D01*
G01X123764Y1115646D01*
X123644Y1115617D01*
X123237Y1115773D01*
G02X123108Y1115960I71J187D01*
G01Y1118114D01*
G02X123167Y1118256I200J0D01*
G01X123524Y1118613D01*
G02X123666Y1118672I142J-141D01*
G01X131497D01*
G02X131639Y1118613I0J-200D01*
G01X132343Y1117909D01*
X132374Y1117828D01*
X132371Y1117785D01*
G03X132368Y1117691I1499J-95D01*
G03X133870Y1116189I1502J0D01*
G03X135344Y1117402I0J1502D01*
G01X135358Y1117473D01*
X135468Y1117563D01*
X142089D01*
G02X142249Y1117484I1J-200D01*
G03X144167I959J723D01*
G02X144327Y1117563I159J-121D01*
G01X145829D01*
G02X145989Y1117484I1J-200D01*
G03X147907I959J723D01*
G02X148067Y1117563I159J-121D01*
G01X149570D01*
G02X149730Y1117484I1J-200D01*
G03X151648I959J723D01*
G02X151808Y1117563I159J-121D01*
G01X153310D01*
G02X153470Y1117484I1J-200D01*
G03X155388I959J723D01*
G02X155548Y1117563I159J-121D01*
G01X157050D01*
G02X157210Y1117484I1J-200D01*
G03X159128I959J723D01*
G02X159288Y1117563I159J-121D01*
G01X160790D01*
G02X160950Y1117484I1J-200D01*
G03X162868I959J723D01*
G02X163028Y1117563I159J-121D01*
G01X175751D01*
G02X175911Y1117484I1J-200D01*
G03X177829I959J723D01*
G02X177989Y1117563I159J-121D01*
G01X179491D01*
G02X179651Y1117484I1J-200D01*
G03X181569I959J723D01*
G02X181729Y1117563I159J-121D01*
G01X183231D01*
G02X183391Y1117484I1J-200D01*
G03X184350Y1117006I959J723D01*
G03X185552Y1118208I0J1202D01*
G03X185532Y1118425I-1202J-1D01*
G01X185523Y1118474D01*
X185552Y1118567D01*
X185598Y1118613D01*
G03X185657Y1118755I-141J142D01*
G01Y1119391D01*
G02X185716Y1119532I200J-1D01*
G01X186125Y1119942D01*
G03X186184Y1120083I-141J142D01*
G01Y1152596D01*
G02X186384Y1152796I200J0D01*
G01X186577D01*
G02X186740Y1152712I0J-200D01*
G01X186957Y1152406D01*
X186971Y1152311D01*
X186955Y1152265D01*
G03X186888Y1151870I1135J-396D01*
G03X189292I1202J0D01*
G03X189225Y1152265I-1202J-1D01*
G01X189209Y1152311D01*
X189223Y1152406D01*
X189440Y1152712D01*
G02X189603Y1152796I163J-116D01*
G37*
G36*
G01X240020Y54588D02*
X268877D01*
X269414Y54051D01*
Y53128D01*
X268877Y52591D01*
X240020D01*
G03X234083Y46654I0J-5937D01*
G01Y7874D01*
G02X228209Y2000I-5874J0D01*
G01X180965D01*
G02X175091Y7874I0J5874D01*
G01Y46443D01*
X177088D01*
Y7874D01*
G03X180963Y3998I3876J0D01*
G01X228209D01*
G03X232086Y7874I0J3877D01*
G01Y46654D01*
G02X240020Y54588I7934J0D01*
G37*
G36*
G01X425285Y1299758D02*
X450225D01*
G02X450258Y1299755I-2J-200D01*
G02X450365Y1299701I-32J-197D01*
G01X450947Y1299119D01*
G02X451001Y1298933I-141J-142D01*
G01X450915Y1298553D01*
X450848Y1298477D01*
X450799Y1298459D01*
G03X449802Y1297045I504J-1414D01*
G03X451304Y1295543I1502J0D01*
G03X452718Y1296540I0J1501D01*
G01X452736Y1296589D01*
X452812Y1296656D01*
X453191Y1296742D01*
G02X453353Y1296709I45J-195D01*
G01X453369Y1296697D01*
X461227Y1288839D01*
G02X461281Y1288656I-142J-141D01*
G01X461199Y1288277D01*
X461132Y1288200D01*
X461085Y1288182D01*
G03X460111Y1286776I528J-1406D01*
G03X461613Y1285274I1502J0D01*
G03X463094Y1286525I0J1502D01*
G01X463099Y1286557D01*
X463127Y1286611D01*
X463150Y1286633D01*
G02X463433I141J-141D01*
G01X463608Y1286458D01*
G02X463667Y1286316I-141J-142D01*
G01Y1256065D01*
G02X463607Y1255922I-200J0D01*
G01X463371Y1255693D01*
X463298Y1255664D01*
X463256Y1255665D01*
G03X463216Y1255666I-58J-1501D01*
G03Y1252662I0J-1502D01*
G03X463438Y1252678I3J1502D01*
G01X463452Y1252681D01*
X463467D01*
G02X463667Y1252481I0J-200D01*
G01Y1252443D01*
G02X463467Y1252243I-200J0D01*
G01X463452D01*
X463438Y1252246D01*
G03X463216Y1252262I-219J-1486D01*
G03Y1249258I0J-1502D01*
G03X463256Y1249259I-18J1502D01*
G01X463298Y1249260D01*
X463371Y1249231D01*
X463607Y1249002D01*
G02X463667Y1248859I-140J-143D01*
G01Y1245956D01*
G02X463607Y1245813I-200J0D01*
G01X463371Y1245584D01*
X463298Y1245555D01*
X463256Y1245556D01*
G03X463216Y1245557I-58J-1501D01*
G03Y1242553I0J-1502D01*
G03X463256Y1242554I-18J1502D01*
G01X463298Y1242555D01*
X463371Y1242526D01*
X463607Y1242297D01*
G02X463667Y1242154I-140J-143D01*
G01Y1158339D01*
X463637Y1158265D01*
X463608Y1158237D01*
X462806Y1157435D01*
G02X462664Y1157376I-142J141D01*
G01X458549D01*
G03X458497Y1157369I0J-200D01*
G01X458484Y1157365D01*
X458471Y1157360D01*
G02X458398Y1157346I-74J186D01*
G01X398532D01*
G03X398390Y1157287I0J-200D01*
G01X395977Y1154874D01*
X395949Y1154845D01*
X395875Y1154815D01*
X393144D01*
X393124Y1154819D01*
G03X390356Y1155094I-2768J-13795D01*
G01X390354D01*
G03X376284Y1141024I0J-14070D01*
G03X378373Y1133647I14070J0D01*
G01X378399Y1133605D01*
X378406Y1133508D01*
X378236Y1133116D01*
X378160Y1133055D01*
X378112Y1133045D01*
G03X376908Y1131573I298J-1472D01*
G03X378370Y1130072I1502J0D01*
G01X378409Y1130070D01*
X378479Y1130040D01*
X378729Y1129786D01*
X378759Y1129715D01*
Y1129676D01*
G03X380085Y1128200I1502J16D01*
G01X380105Y1128198D01*
X380106D01*
X380115Y1128197D01*
G03X380266Y1128190I145J1495D01*
G03X380461Y1128203I-2J1502D01*
G03X381701Y1129264I-200J1489D01*
G01X381715Y1129310D01*
X381781Y1129380D01*
X382117Y1129498D01*
G02X382243Y1129500I66J-189D01*
G01X382312Y1129478D01*
X382337Y1129461D01*
G03X390352Y1126954I8017J11564D01*
G01X390354D01*
G03X390673Y1126958I-17J14070D01*
G01X390714Y1126959D01*
X390788Y1126930D01*
X391022Y1126701D01*
G02X391082Y1126558I-140J-143D01*
G01Y1044388D01*
X391052Y1044314D01*
X391023Y1044286D01*
X390038Y1043301D01*
G02X389896Y1043242I-142J141D01*
G01X260848D01*
G03X260796Y1043235I0J-200D01*
G01X260783Y1043231D01*
X260770Y1043226D01*
G02X260697Y1043212I-74J186D01*
G01X202225D01*
X202151Y1043242D01*
X202123Y1043271D01*
X193678Y1051716D01*
G02X193619Y1051858I141J142D01*
G01Y1069053D01*
G03X193560Y1069195I-200J0D01*
G01X193531Y1069223D01*
X193501Y1069297D01*
Y1073711D01*
G02X193560Y1073853I200J0D01*
G01X193645Y1073938D01*
G02X193774Y1073996I141J-142D01*
G03Y1076396I-74J1200D01*
G02X193645Y1076454I12J200D01*
G01X193560Y1076539D01*
G02X193501Y1076681I141J142D01*
G01Y1077451D01*
G02X193560Y1077593I200J0D01*
G01X193645Y1077678D01*
G02X193774Y1077736I141J-142D01*
G03Y1080136I-74J1200D01*
G02X193645Y1080194I12J200D01*
G01X193560Y1080279D01*
G02X193501Y1080421I141J142D01*
G01Y1081107D01*
G02X193560Y1081248I200J-1D01*
G01X193645Y1081333D01*
G02X193775Y1081392I142J-141D01*
G03Y1083962I-74J1285D01*
G02X193645Y1084021I12J200D01*
G01X193560Y1084106D01*
G02X193501Y1084247I141J142D01*
G01Y1084847D01*
G02X193560Y1084988I200J-1D01*
G01X193645Y1085073D01*
G02X193775Y1085132I142J-141D01*
G03Y1087702I-74J1285D01*
G02X193645Y1087761I12J200D01*
G01X193560Y1087846D01*
G02X193501Y1087987I141J142D01*
G01Y1088672D01*
G02X193560Y1088814I200J0D01*
G01X193645Y1088899D01*
G02X193774Y1088957I141J-142D01*
G03Y1091357I-74J1200D01*
G02X193645Y1091415I12J200D01*
G01X193560Y1091500D01*
G02X193501Y1091642I141J142D01*
G01Y1092412D01*
G02X193560Y1092554I200J0D01*
G01X193645Y1092639D01*
G02X193774Y1092697I141J-142D01*
G03Y1095097I-74J1200D01*
G02X193645Y1095155I12J200D01*
G01X193560Y1095240D01*
G02X193501Y1095382I141J142D01*
G01Y1096152D01*
G02X193560Y1096294I200J0D01*
G01X193645Y1096379D01*
G02X193774Y1096437I141J-142D01*
G03Y1098837I-74J1200D01*
G02X193645Y1098895I12J200D01*
G01X193560Y1098980D01*
G02X193501Y1099122I141J142D01*
G01Y1099806D01*
G02X193560Y1099947I200J-1D01*
G01X193645Y1100032D01*
G02X193775Y1100091I142J-141D01*
G03Y1102661I-74J1285D01*
G02X193645Y1102720I12J200D01*
G01X193560Y1102805D01*
G02X193501Y1102946I141J142D01*
G01Y1103547D01*
G02X193560Y1103688I200J-1D01*
G01X193645Y1103773D01*
G02X193775Y1103832I142J-141D01*
G03Y1106402I-74J1285D01*
G02X193645Y1106461I12J200D01*
G01X193560Y1106546D01*
G02X193501Y1106687I141J142D01*
G01Y1107373D01*
G02X193560Y1107515I200J0D01*
G01X193645Y1107600D01*
G02X193774Y1107658I141J-142D01*
G03X194902Y1108858I-74J1200D01*
G03X193876Y1110047I-1202J0D01*
G02X193758Y1110110I30J198D01*
G01X193678Y1110197D01*
G02X193626Y1110332I148J135D01*
G01Y1152218D01*
G03X193570Y1152356I-200J-1D01*
G01X193568Y1152359D01*
X193552Y1152377D01*
G02X193501Y1152509I149J133D01*
G01Y1208357D01*
G02X193560Y1208499I200J0D01*
G01X193645Y1208584D01*
G02X193774Y1208642I141J-142D01*
G03X193922Y1208661I-79J1199D01*
G01X193971Y1208670D01*
X194064Y1208641D01*
X194369Y1208336D01*
X194398Y1208243D01*
X194389Y1208194D01*
G03X194368Y1207972I1181J-224D01*
G03X196772I1202J0D01*
G03X196751Y1208194I-1202J-2D01*
G01X196742Y1208243D01*
X196771Y1208336D01*
X197076Y1208641D01*
X197169Y1208670D01*
X197218Y1208661D01*
G03X197440Y1208640I224J1181D01*
G03X197663Y1208661I-1J1202D01*
G01X197711Y1208670D01*
X197806Y1208641D01*
X198110Y1208337D01*
X198139Y1208243D01*
X198130Y1208194D01*
G03X198109Y1207972I1181J-224D01*
G03X199311Y1209174I1202J0D01*
G03X199088Y1209153I1J-1202D01*
G01X199040Y1209144D01*
X198945Y1209173D01*
X198641Y1209477D01*
X198612Y1209571D01*
X198621Y1209620D01*
G03X198642Y1209842I-1181J224D01*
G03X196238I-1202J0D01*
G03X196259Y1209620I1202J2D01*
G01X196268Y1209571D01*
X196239Y1209478D01*
X195934Y1209173D01*
X195841Y1209144D01*
X195792Y1209153D01*
G03X195570Y1209174I-224J-1181D01*
G03X195348Y1209153I2J-1202D01*
G01X195299Y1209144D01*
X195206Y1209173D01*
X194901Y1209478D01*
X194872Y1209571D01*
X194881Y1209620D01*
G03X194902Y1209842I-1181J224D01*
G03X193774Y1211042I-1202J0D01*
G02X193645Y1211100I12J200D01*
G01X193560Y1211185D01*
G02X193501Y1211327I141J142D01*
G01Y1212097D01*
G02X193560Y1212239I200J0D01*
G01X193645Y1212324D01*
G02X193774Y1212382I141J-142D01*
G03X194902Y1213582I-74J1200D01*
G03X194881Y1213804I-1202J-2D01*
G01X194872Y1213853D01*
X194901Y1213946D01*
X195206Y1214251D01*
X195299Y1214280D01*
X195348Y1214271D01*
G03X195570Y1214250I224J1181D01*
G03X196772Y1215452I0J1202D01*
G03X196751Y1215674I-1202J-2D01*
G01X196742Y1215723D01*
X196771Y1215816D01*
X197076Y1216121D01*
X197169Y1216150D01*
X197218Y1216141D01*
G03X197440Y1216120I224J1181D01*
G03X196238Y1217322I0J1202D01*
G03X196259Y1217100I1202J2D01*
G01X196268Y1217051D01*
X196239Y1216958D01*
X195934Y1216653D01*
X195841Y1216624D01*
X195792Y1216633D01*
G03X195570Y1216654I-224J-1181D01*
G03X194368Y1215452I0J-1202D01*
G03X194389Y1215230I1202J2D01*
G01X194398Y1215181D01*
X194369Y1215088D01*
X194064Y1214783D01*
X193971Y1214754D01*
X193922Y1214763D01*
G03X193774Y1214782I-227J-1180D01*
G02X193645Y1214840I12J200D01*
G01X193560Y1214925D01*
G02X193501Y1215067I141J142D01*
G01Y1219577D01*
G02X193560Y1219719I200J0D01*
G01X193645Y1219804D01*
G02X193774Y1219862I141J-142D01*
G03X194373Y1220066I-74J1200D01*
G02X194484Y1220100I112J-166D01*
G01X196656D01*
G02X196767Y1220066I-1J-200D01*
G03X198113I673J996D01*
G02X198224Y1220100I112J-166D01*
G01X200397D01*
G02X200508Y1220066I-1J-200D01*
G03X201854I673J996D01*
G02X201965Y1220100I112J-166D01*
G01X204137D01*
G02X204248Y1220066I-1J-200D01*
G03X205594I673J996D01*
G02X205705Y1220100I112J-166D01*
G01X207877D01*
G02X207988Y1220066I-1J-200D01*
G03X209334I673J996D01*
G02X209445Y1220100I112J-166D01*
G01X211617D01*
G02X211728Y1220066I-1J-200D01*
G03X213074I673J996D01*
G02X213185Y1220100I112J-166D01*
G01X215357D01*
G02X215468Y1220066I-1J-200D01*
G03X216814I673J996D01*
G02X216925Y1220100I112J-166D01*
G01X219097D01*
G02X219208Y1220066I-1J-200D01*
G03X220554I673J996D01*
G02X220665Y1220100I112J-166D01*
G01X222838D01*
G02X222949Y1220066I-1J-200D01*
G03X224295I673J996D01*
G01X224320Y1220083D01*
X224376Y1220100D01*
X224517D01*
G03X224659Y1220159I0J200D01*
G01X224741Y1220241D01*
G03X224800Y1220383I-141J142D01*
G01Y1220822D01*
X224803Y1220841D01*
G03X224824Y1221033I-1180J226D01*
G02X224954Y1221216I200J-4D01*
G03X225560Y1221504I-1333J3587D01*
G01X225609Y1221532D01*
X225718Y1221531D01*
X226115Y1221288D01*
X226166Y1221191D01*
X226162Y1221135D01*
G03X226160Y1221062I1200J-69D01*
G03X227362Y1222264I1202J0D01*
G03X227290Y1222262I-3J-1202D01*
G01X227234Y1222258D01*
X227136Y1222309D01*
X226893Y1222706D01*
X226892Y1222815D01*
X226921Y1222864D01*
G03X227209Y1223471I-3300J1937D01*
G02X227392Y1223601I187J-70D01*
G03X228564Y1224803I-30J1202D01*
G03X227602Y1225981I-1202J0D01*
G02X227442Y1226165I40J196D01*
G03X227386Y1226637I-3820J-214D01*
G02Y1226709I197J36D01*
G03X227442Y1227181I-3764J686D01*
G02X227602Y1227365I200J-12D01*
G03X228564Y1228513I-240J1178D01*
G02X228694Y1228696I200J-4D01*
G03X229221Y1228938I-1329J3588D01*
G01X229268Y1228965D01*
X229375Y1228963D01*
X229765Y1228726D01*
X229816Y1228632D01*
X229815Y1228578D01*
G03X229814Y1228543I1286J-54D01*
G03X231102Y1229830I1287J0D01*
G01X231067D01*
X231013Y1229829D01*
X230919Y1229880D01*
X230682Y1230270D01*
X230680Y1230377D01*
X230707Y1230424D01*
G03X230949Y1230951I-3346J1856D01*
G02X231132Y1231081I187J-70D01*
G03X232304Y1232283I-30J1202D01*
G03X231342Y1233461I-1202J0D01*
G02X231182Y1233645I40J196D01*
G03X231126Y1234117I-3820J-214D01*
G02Y1234189I197J36D01*
G03X231182Y1234661I-3764J686D01*
G02X231342Y1234845I200J-12D01*
G03X232304Y1236023I-240J1178D01*
G03X231132Y1237225I-1202J0D01*
G02X230949Y1237355I4J200D01*
G03X230661Y1237961I-3587J-1333D01*
G01X230633Y1238010D01*
X230634Y1238119D01*
X230877Y1238516D01*
X230974Y1238567D01*
X231030Y1238563D01*
G03X231102Y1238561I69J1200D01*
G03X232304Y1239763I0J1202D01*
G03X231559Y1240875I-1202J0D01*
G01X231511Y1240894D01*
X231449Y1240970D01*
X231373Y1241347D01*
G02X231428Y1241528I196J39D01*
G01X232385Y1242485D01*
G03X232444Y1242627I-141J142D01*
G01Y1259634D01*
G02X232503Y1259776I200J0D01*
G01X234822Y1262095D01*
G02X234841Y1262112I143J-140D01*
G02X234879Y1262135I122J-158D01*
G01X235794Y1262568D01*
X235889Y1262613D01*
G03X236925Y1263327I-1661J3519D01*
G01X236928Y1263331D01*
X236938Y1263340D01*
G02X236988Y1263375I138J-145D01*
G01X237020Y1263390D01*
G03X238275Y1263742I-409J3870D01*
G01X239849Y1264486D01*
G03X241272Y1265632I-1661J3519D01*
G01X241286Y1265651D01*
X241323Y1265680D01*
X259892Y1274463D01*
G02X259901Y1274467I86J-181D01*
G01X273262Y1280001D01*
G03X273610Y1280166I-1506J3626D01*
G01X286378Y1286990D01*
G02X286387Y1286995I101J-172D01*
G01X313342Y1299744D01*
X383088D01*
G02X383288Y1299544I0J-200D01*
G01Y1297453D01*
G03X385086Y1295650I1803J0D01*
G01X385121Y1295651D01*
G03X385683Y1295750I-28J1802D01*
G01X385756Y1295776D01*
G03X385774Y1295783I-63J190D01*
G01X385847Y1295817D01*
G03X385982Y1295886I-752J1638D01*
G01X386015Y1295905D01*
X386053Y1295910D01*
G02X386127Y1295908I32J-197D01*
G01X386209Y1295889D01*
X386246Y1295881D01*
X386364Y1295802D01*
X386385Y1295774D01*
G03X387587Y1295173I1202J901D01*
G01X387648D01*
X387702Y1295177D01*
G03X389089Y1296675I-115J1498D01*
G03X387587Y1298177I-1502J0D01*
G03X387355Y1298159I0J-1502D01*
G01X387312Y1298152D01*
X387228Y1298176D01*
X386964Y1298401D01*
G02X386894Y1298553I130J152D01*
G01Y1299544D01*
G02X387094Y1299744I200J0D01*
G01X395093D01*
G03X395117Y1299746I-5J200D01*
G01X395128Y1299748D01*
X395175Y1299755D01*
G02X395208Y1299758I35J-197D01*
G01X411838D01*
X411939Y1299690D01*
X411962Y1299633D01*
G03X414746I1392J564D01*
G01X414769Y1299690D01*
X414870Y1299758D01*
X417021D01*
X417122Y1299690D01*
X417145Y1299633D01*
G03X419929I1392J564D01*
G01X419952Y1299690D01*
X420053Y1299758D01*
X422197D01*
X422301Y1299684D01*
X422322Y1299623D01*
G03X425160I1419J492D01*
G01X425181Y1299684D01*
X425285Y1299758D01*
G37*
G36*
G01X342382Y54588D02*
X370863D01*
X371080D01*
X371204Y54464D01*
Y52932D01*
X370863Y52591D01*
X342382D01*
G03X336445Y46654I0J-5937D01*
G01Y7874D01*
G02X330571Y2000I-5874J0D01*
G01X283327D01*
G02X277453Y7874I0J5874D01*
G01Y46654D01*
Y46655D01*
X279450D01*
Y7874D01*
G03X283325Y3998I3876J0D01*
G01X330571D01*
G03X334448Y7874I0J3877D01*
G01Y46654D01*
G02X342382Y54588I7934J0D01*
G37*
G36*
G01X338203Y1018294D02*
G03I-639J0D01*
G37*
G36*
G01X371892Y1642391D02*
X443837D01*
G02X443979Y1642332I0J-200D01*
G01X451970Y1634341D01*
G02X452029Y1634199I-141J-142D01*
G01Y1555260D01*
G02X451936Y1555091I-200J0D01*
G01X451921Y1555082D01*
X451876Y1555063D01*
X451836Y1555047D01*
G03X451724Y1555000I1450J-3612D01*
G01X451720Y1554998D01*
X450346Y1554430D01*
X450344Y1554427D01*
X450342Y1554426D01*
X450115Y1553877D01*
G02X450007Y1553769I-185J77D01*
G01X447703Y1552814D01*
X447702D01*
X447698Y1552812D01*
X447225Y1552614D01*
X447217Y1552611D01*
G03X447153Y1552577I60J-191D01*
G01X446776Y1552269D01*
X446774Y1552268D01*
G03X446733Y1552235I2419J-3048D01*
G01X446696Y1552205D01*
G02X446550Y1552162I-125J156D01*
G01X445961Y1552223D01*
X445958Y1552221D01*
X445955D01*
X444795Y1551274D01*
X444793Y1551272D01*
G03X444703Y1551200I2386J-3075D01*
G01X444701Y1551198D01*
X444606Y1551121D01*
X444605D01*
X443814Y1550475D01*
X443362Y1550106D01*
X443361D01*
G03X443338Y1550087I2466J-3009D01*
G01X443337Y1550085D01*
X442112Y1549086D01*
Y1549085D01*
X441309Y1548430D01*
X441308Y1548429D01*
G03X441271Y1548399I2433J-3038D01*
G01X441270Y1548398D01*
X441166Y1548314D01*
X441164D01*
X440245Y1547563D01*
X439921Y1547299D01*
G03X439900Y1547282I2438J-3033D01*
G01X439899Y1547281D01*
X438671Y1546279D01*
Y1546278D01*
X437837Y1545597D01*
X437832Y1545594D01*
G03X437828Y1545591I2332J-3114D01*
G01X437725Y1545507D01*
X437723D01*
X437124Y1545017D01*
X436580Y1544575D01*
Y1544573D01*
X436478Y1544490D01*
X436475Y1544488D01*
X435634Y1543801D01*
X435630D01*
X434388Y1542786D01*
X434385Y1542784D01*
X433094Y1541731D01*
X433092Y1541729D01*
G03X432988Y1541645I2393J-3069D01*
G01X432986Y1541643D01*
X431848Y1540716D01*
G03X431776Y1540580I127J-154D01*
G01X431725Y1540070D01*
G02X431652Y1539935I-199J20D01*
G01X429739Y1538376D01*
G03X429673Y1538321I2458J-3017D01*
G01X429671Y1538319D01*
X429315Y1538029D01*
G03X429275Y1537985I126J-155D01*
G01X429023Y1537611D01*
X429021Y1537608D01*
X429013Y1537595D01*
X429009Y1537590D01*
G03X428935Y1537481I3183J-2240D01*
G01X428934Y1537478D01*
X427662Y1535586D01*
X422418Y1527785D01*
Y1527781D01*
X422382Y1527729D01*
X422378Y1527722D01*
X422270Y1527557D01*
X422267Y1527558D01*
X422112Y1527328D01*
G03X422087Y1527275I167J-111D01*
G01X421955Y1526842D01*
X421954Y1526839D01*
X421946Y1526811D01*
X421945Y1526807D01*
G03X421926Y1526750I3682J-1259D01*
G01X419284Y1518106D01*
G02X418612Y1517949I-382J118D01*
G01X418594Y1517970D01*
X418589Y1517976D01*
X418586Y1517979D01*
G03X417153Y1518690I-1434J-1090D01*
G01X413753D01*
G03Y1515084I0J-1803D01*
G01X417153D01*
G03X417935Y1515263I-1J1803D01*
G01X417938Y1515264D01*
X417967Y1515277D01*
G02X418492Y1514821I133J-377D01*
G01X418382Y1514277D01*
X418354Y1514225D01*
X418333Y1514204D01*
X418322Y1514193D01*
Y1514012D01*
X418318Y1513972D01*
X418136Y1513067D01*
Y1513059D01*
X418131Y1513038D01*
G03X418115Y1512959I3807J-812D01*
G01Y1512956D01*
X418061Y1512693D01*
G03X418057Y1512651I196J-40D01*
G01X418058Y1512544D01*
X418056Y1512529D01*
X416607Y1501805D01*
Y1501803D01*
X416605Y1501789D01*
G03X416592Y1501685I3854J-535D01*
G01Y1501681D01*
X416566Y1501451D01*
G02X416029Y1501122I-397J46D01*
G01X415999Y1501134D01*
X415993Y1501137D01*
G03X415204Y1501320I-791J-1619D01*
G01X415203D01*
G03X413400Y1499518I0J-1803D01*
G01Y1496118D01*
G03X415202Y1494316I1802J0D01*
G01X415205D01*
G03X415289Y1494318I-1J1802D01*
G01X415332D01*
G02X415698Y1493874I-31J-399D01*
G01X413995Y1479003D01*
X413891Y1478904D01*
X413818Y1478899D01*
G03X412132Y1477100I117J-1799D01*
G03X412781Y1475715I1802J0D01*
G01X412783Y1475714D01*
X412806Y1475694D01*
X412833Y1475662D01*
X412844Y1475639D01*
X412880Y1475565D01*
G02X412900Y1475478I-180J-87D01*
G01Y1464671D01*
G02X412185Y1464425I-400J0D01*
G03X411000Y1465003I-1185J-926D01*
G03X409497Y1463500I0J-1503D01*
G03X410075Y1462315I1504J0D01*
G02Y1461685I-246J-315D01*
G03Y1459315I926J-1185D01*
G02Y1458685I-246J-315D01*
G03Y1456315I926J-1185D01*
G02Y1455685I-246J-315D01*
G03X409497Y1454500I926J-1185D01*
G03X411000Y1452997I1503J0D01*
G03X412185Y1453575I0J1504D01*
G02X412900Y1453329I315J-246D01*
G01Y1452171D01*
G02X412185Y1451925I-400J0D01*
G03X411000Y1452503I-1185J-926D01*
G03X409512Y1451213I0J-1503D01*
G02X408875Y1450951I-396J57D01*
G03X407970Y1451254I-905J-1200D01*
G03Y1448248I0J-1503D01*
G03X409458Y1449538I0J1503D01*
G02X410095Y1449800I396J-57D01*
G03X411000Y1449497I905J1200D01*
G03X412185Y1450075I0J1504D01*
G02X412900Y1449829I315J-246D01*
G01Y1449343D01*
X412870Y1449269D01*
X412841Y1449241D01*
X410345Y1446745D01*
G03X410288Y1446627I142J-141D01*
G01X407154Y1419254D01*
G02X407056Y1419104I-199J23D01*
G01X406737Y1418919D01*
X406643Y1418913D01*
X406599Y1418932D01*
G03X405889Y1419078I-711J-1657D01*
G01X402489D01*
G03Y1415472I0J-1803D01*
G01X405890D01*
G03X406205Y1415500I-2J1803D01*
G01X406207D01*
X406254Y1415508D01*
X406345Y1415481D01*
X406378Y1415449D01*
G03X406380Y1415447I142J140D01*
G01X406611Y1415230D01*
G02X406673Y1415061I-137J-146D01*
G01X405496Y1404778D01*
G03X405480Y1404603I3866J-442D01*
G01X404579Y1391566D01*
G03X404571Y1391383I3882J-261D01*
G01X404570Y1391322D01*
X404501Y1391222D01*
X404365Y1391169D01*
G02X404325Y1391158I-73J187D01*
G02X404220Y1391169I-32J198D01*
G02X404218Y1391170I88J179D01*
G01X404184Y1391184D01*
G02X404154Y1391199I74J186D01*
G01X404109Y1391226D01*
X404097Y1391237D01*
G03X403113Y1391605I-985J-1133D01*
G01X403111D01*
G03X401692Y1390595I0J-1502D01*
G01X401671Y1390534D01*
X401567Y1390460D01*
X397302D01*
G02X397233Y1390472I-1J200D01*
G01X397212Y1390480D01*
X397099Y1390546D01*
X397064Y1390580D01*
X397051Y1390602D01*
G03X394489I-1281J-785D01*
G01X394476Y1390580D01*
X394441Y1390546D01*
X394344Y1390489D01*
G02X394311Y1390474I-99J174D01*
G01X394274Y1390460D01*
X394086D01*
G02X393899Y1390590I0J200D01*
G01X393858Y1390700D01*
Y1390701D01*
X393832Y1390770D01*
X393831Y1390771D01*
X393816Y1390812D01*
G03X393665Y1391161I-3643J-1369D01*
G03X393436Y1391565I-3494J-1714D01*
G01X363183Y1438111D01*
X363182Y1438113D01*
X363156Y1438154D01*
X363154Y1438157D01*
X359676Y1443507D01*
X356788Y1447946D01*
X356786Y1447950D01*
X356772Y1447973D01*
G02X356743Y1448077I171J104D01*
G01Y1627242D01*
G02X356802Y1627384I200J0D01*
G01X371750Y1642332D01*
G02X371892Y1642391I142J-141D01*
G37*
G36*
G01X723487Y575341D02*
G03X723224Y575318I-1J-1502D01*
G01X723211Y575316D01*
X723188Y575314D01*
G02X723065Y575357I1J200D01*
G01X723039Y575380D01*
X722962Y575446D01*
G02X722892Y575586I130J152D01*
G01X722893Y575606D01*
G03X722894Y575673I-1801J60D01*
G01Y575675D01*
G03Y575684I-1802J5D01*
G01Y576913D01*
G02X722916Y577004I200J0D01*
G02X722952Y577054I178J-90D01*
G01X747457Y601559D01*
G02X747597Y601611I134J-148D01*
G01X747959Y601561D01*
G02X748024Y601531I-50J-194D01*
G01X748026Y601529D01*
X748058Y601494D01*
X748080Y601469D01*
X748091Y601449D01*
G03X749395Y600682I1310J736D01*
G01X749402D01*
G03X750905Y602185I0J1503D01*
G03X750118Y603507I-1504J0D01*
G01X750104Y603515D01*
X750056Y603563D01*
G02X750023Y603644I164J114D01*
G01X749991Y603866D01*
X749984Y603915D01*
X749975Y603977D01*
Y603982D01*
G02X749980Y604039I200J11D01*
G02X750002Y604094I195J-46D01*
G02X750033Y604135I174J-99D01*
G01X767226Y621328D01*
G02X767327Y621381I140J-143D01*
G01X767329D01*
G02X767366Y621385I40J-196D01*
G01X898704D01*
G02X898833Y621338I0J-200D01*
G01Y621337D01*
G02X898901Y621220I-129J-153D01*
G01Y621219D01*
G03X899078Y620702I1774J319D01*
G02X899088Y620680I-177J-94D01*
G02X899101Y620610I-187J-71D01*
G02X899095Y620562I-200J1D01*
G01X899075Y620480D01*
G02X899046Y620415I-194J48D01*
G01X898988Y620330D01*
X898960Y620310D01*
G03X898320Y619040I940J-1270D01*
G03X901478I1579J0D01*
G01Y619041D01*
G03X901461Y619273I-1579J1D01*
G01Y619274D01*
G02X901504Y619432I198J31D01*
G02X901507Y619435I143J-140D01*
G01X901704Y619664D01*
G02X901856Y619734I152J-130D01*
G01X902898D01*
G02X903050Y619664I0J-200D01*
G01X903248Y619434D01*
G02X903288Y619360I-152J-130D01*
G01X903300Y619319D01*
X903293Y619274D01*
G03X903276Y619041I1562J-231D01*
G01Y619040D01*
G03X904855Y617461I1579J0D01*
G03X906434Y619007I0J1579D01*
G01Y619044D01*
G03X906432Y619110I-1578J-15D01*
G01Y619116D01*
G03X905766Y620329I-1577J-76D01*
G01X905754Y620337D01*
G02X905689Y620438I128J154D01*
G01X905656Y620572D01*
G02X905665Y620685I196J41D01*
G01X905675Y620703D01*
G03X905810Y621044I-1600J831D01*
G01Y621046D01*
G03X905851Y621220I-1731J500D01*
G01Y621221D01*
G02X905919Y621337I196J-37D01*
G01Y621338D01*
G02X906048Y621385I129J-153D01*
G01X907553D01*
X907554D01*
G02X907746Y621238I-1J-200D01*
G01X907748Y621228D01*
G03X907910Y620782I1760J387D01*
G01X907923Y620750D01*
G02X907929Y620650I-190J-62D01*
G01X907907Y620560D01*
G02X907878Y620495I-194J48D01*
G01X907820Y620410D01*
X907792Y620390D01*
G03X907152Y619120I940J-1270D01*
G03X910310I1579J0D01*
G01Y619121D01*
G03X910293Y619353I-1579J1D01*
G01Y619354D01*
G02X910336Y619512I198J31D01*
G02X910339Y619515I143J-140D01*
G01X910536Y619744D01*
G02X910688Y619814I152J-130D01*
G01X911730D01*
G02X911882Y619744I0J-200D01*
G01X912080Y619514D01*
G02X912120Y619440I-152J-130D01*
G01X912132Y619399D01*
X912125Y619354D01*
G03X912108Y619121I1562J-231D01*
G01Y619120D01*
G03X913687Y617541I1579J0D01*
G03X915266Y619087I0J1579D01*
G01Y619124D01*
G03X915264Y619190I-1578J-15D01*
G01Y619196D01*
G03X914598Y620409I-1577J-76D01*
G01X914586Y620417D01*
G02X914521Y620517I128J154D01*
G01X914489Y620650D01*
G02X914484Y620693I195J44D01*
G01X914505Y620780D01*
X914516Y620801D01*
G03X914668Y621228I-1609J813D01*
G01X914670Y621238D01*
G02X914862Y621385I193J-53D01*
G01X940084D01*
G02X940213Y621337I-1J-200D01*
G01X940309Y621249D01*
G02X940336Y621216I-140J-142D01*
G02X940361Y621162I-167J-110D01*
G01X940365Y621132D01*
Y621131D01*
G03X941859Y619806I1494J180D01*
G03X943360Y621199I0J1505D01*
G01Y621200D01*
X943363Y621236D01*
G02X943420Y621332I194J-50D01*
G01X943448Y621358D01*
X943482Y621371D01*
G02X943555Y621385I73J-186D01*
G01X949137D01*
G02X949217Y621368I-1J-200D01*
G01X949242Y621356D01*
X949307Y621325D01*
G02X949349Y621294I-97J-175D01*
G01X949358Y621284D01*
G03X951600I1121J1000D01*
G01X951609Y621294D01*
G02X951651Y621325I139J-144D01*
G01X951716Y621356D01*
X951741Y621368D01*
G02X951821Y621385I81J-183D01*
G01X957166D01*
G02X957320Y621312I0J-200D01*
G01X957518Y621073D01*
G02X957557Y620996I-155J-127D01*
G01X957568Y620955D01*
X957559Y620909D01*
G03X957554Y620884I1274J-268D01*
G01Y620883D01*
X957551Y620866D01*
X957550Y620861D01*
Y620857D01*
G03X957545Y620825I1284J-217D01*
G01Y620823D01*
X957543Y620812D01*
Y620811D01*
X957542Y620803D01*
G03X957539Y620775I1293J-153D01*
G01Y620773D01*
G03X957538Y620760I1298J-106D01*
G03X957535Y620662I1299J-89D01*
G01Y620660D01*
G03X958111Y619580I1302J1D01*
G02X958158Y619523I-128J-154D01*
G01Y619521D01*
G02X958183Y619426I-175J-97D01*
G01Y619096D01*
G02X958158Y619001I-200J2D01*
G01Y618999D01*
G02X958111Y618942I-175J97D01*
G03X957535Y617861I726J-1081D01*
G03X960139I1302J0D01*
G03X960122Y618074I-1302J3D01*
G01Y618075D01*
X960120Y618085D01*
X960119Y618091D01*
G03X959563Y618942I-1282J-230D01*
G02X959516Y618999I128J154D01*
G01Y619001D01*
G02X959491Y619096I175J97D01*
G01Y619426D01*
G02X959516Y619521I200J-2D01*
G01Y619523D01*
G02X959563Y619580I175J-97D01*
G03X960139Y620661I-726J1081D01*
G03X960115Y620909I-1302J-1D01*
G01X960106Y620955D01*
X960117Y620996D01*
G02X960156Y621073I194J-50D01*
G01X960354Y621312D01*
G02X960508Y621385I154J-127D01*
G01X960709D01*
G02X960863Y621312I0J-200D01*
G01X961061Y621073D01*
G02X961100Y620996I-155J-127D01*
G01X961111Y620955D01*
X961102Y620909D01*
G03X961097Y620884I1274J-268D01*
G01Y620883D01*
X961094Y620866D01*
X961093Y620861D01*
Y620857D01*
G03X961088Y620825I1284J-217D01*
G01Y620823D01*
X961086Y620812D01*
Y620811D01*
X961085Y620803D01*
G03X961082Y620775I1293J-153D01*
G01Y620773D01*
G03X961081Y620760I1298J-106D01*
G03X961078Y620662I1299J-89D01*
G01Y620660D01*
G03X961654Y619580I1302J1D01*
G02X961701Y619523I-128J-154D01*
G01Y619521D01*
G02X961726Y619426I-175J-97D01*
G01Y619096D01*
G02X961701Y619001I-200J2D01*
G01Y618999D01*
G02X961654Y618942I-175J97D01*
G03X961078Y617861I726J-1081D01*
G03X963682I1302J0D01*
G03X963665Y618074I-1302J3D01*
G01Y618075D01*
X963663Y618085D01*
X963662Y618091D01*
G03X963106Y618942I-1282J-230D01*
G02X963059Y618999I128J154D01*
G01Y619001D01*
G02X963034Y619096I175J97D01*
G01Y619426D01*
G02X963059Y619521I200J-2D01*
G01Y619523D01*
G02X963106Y619580I175J-97D01*
G03X963682Y620661I-726J1081D01*
G03X963658Y620909I-1302J-1D01*
G01X963649Y620955D01*
X963660Y620996D01*
G02X963699Y621073I194J-50D01*
G01X963897Y621312D01*
G02X964051Y621385I154J-127D01*
G01X964252D01*
G02X964406Y621312I0J-200D01*
G01X964604Y621073D01*
G02X964643Y620996I-155J-127D01*
G01X964654Y620955D01*
X964645Y620909D01*
G03X964640Y620884I1274J-268D01*
G01Y620883D01*
X964637Y620866D01*
X964636Y620861D01*
Y620857D01*
G03X964631Y620825I1284J-217D01*
G01Y620823D01*
X964629Y620812D01*
Y620811D01*
X964628Y620803D01*
G03X964625Y620775I1293J-153D01*
G01Y620773D01*
G03X964624Y620760I1298J-106D01*
G03X964621Y620662I1299J-89D01*
G01Y620660D01*
G03X965197Y619580I1302J1D01*
G02X965244Y619523I-128J-154D01*
G01Y619521D01*
G02X965269Y619426I-175J-97D01*
G01Y619096D01*
G02X965244Y619001I-200J2D01*
G01Y618999D01*
G02X965197Y618942I-175J97D01*
G03X964621Y617861I726J-1081D01*
G03X967225I1302J0D01*
G03X967208Y618074I-1302J3D01*
G01Y618075D01*
X967206Y618085D01*
X967205Y618091D01*
G03X966649Y618942I-1282J-230D01*
G02X966602Y618999I128J154D01*
G01Y619001D01*
G02X966577Y619096I175J97D01*
G01Y619426D01*
G02X966602Y619521I200J-2D01*
G01Y619523D01*
G02X966649Y619580I175J-97D01*
G03X967225Y620661I-726J1081D01*
G03X967201Y620909I-1302J-1D01*
G01X967192Y620955D01*
X967203Y620996D01*
G02X967242Y621073I194J-50D01*
G01X967440Y621312D01*
G02X967594Y621385I154J-127D01*
G01X967796D01*
G02X967950Y621312I0J-200D01*
G01X968148Y621073D01*
G02X968187Y620996I-155J-127D01*
G01X968198Y620955D01*
X968189Y620909D01*
G03X968184Y620884I1274J-268D01*
G01Y620883D01*
X968181Y620866D01*
X968180Y620861D01*
Y620857D01*
G03X968175Y620825I1284J-217D01*
G01Y620823D01*
X968173Y620812D01*
Y620811D01*
X968172Y620803D01*
G03X968169Y620775I1293J-153D01*
G01Y620773D01*
G03X968168Y620760I1298J-106D01*
G03X968165Y620662I1299J-89D01*
G01Y620660D01*
G03X968741Y619580I1302J1D01*
G02X968788Y619523I-128J-154D01*
G01Y619521D01*
G02X968813Y619426I-175J-97D01*
G01Y619096D01*
G02X968788Y619001I-200J2D01*
G01Y618999D01*
G02X968741Y618942I-175J97D01*
G03X968165Y617861I726J-1081D01*
G03X970769I1302J0D01*
G03X970752Y618074I-1302J3D01*
G01Y618075D01*
X970750Y618085D01*
X970749Y618091D01*
G03X970193Y618942I-1282J-230D01*
G02X970146Y618999I128J154D01*
G01Y619001D01*
G02X970121Y619096I175J97D01*
G01Y619426D01*
G02X970146Y619521I200J-2D01*
G01Y619523D01*
G02X970193Y619580I175J-97D01*
G03X970769Y620661I-726J1081D01*
G03X970745Y620909I-1302J-1D01*
G01X970736Y620955D01*
X970747Y620996D01*
G02X970786Y621073I194J-50D01*
G01X970984Y621312D01*
G02X971138Y621385I154J-127D01*
G01X974155D01*
G02X974308Y621313I-1J-200D01*
G01X974380Y621227D01*
X974512Y621068D01*
G02X974545Y620998I-161J-119D01*
G02X974548Y620984I-194J-49D01*
G01Y620925D01*
X974545Y620909D01*
G03X974525Y620655I1483J-245D01*
G01Y620632D01*
G03X974982Y619573I1504J21D01*
G01X975011Y619545D01*
X975056Y619440D01*
Y619439D01*
X975066Y619417D01*
G02X975072Y619391I-191J-58D01*
G01Y619389D01*
G02X975075Y619358I-197J-35D01*
G01Y619148D01*
G02X975072Y619117I-200J4D01*
G01Y619115D01*
G02X975066Y619090I-197J34D01*
G01X975063Y619083D01*
X975059Y619073D01*
X975056Y619067D01*
X975011Y618961D01*
X974982Y618933D01*
G03X974525Y617853I1048J-1080D01*
G03X977529I1502J0D01*
G03X977072Y618933I-1505J0D01*
G01X977043Y618961D01*
X976998Y619066D01*
Y619067D01*
X976988Y619089D01*
G02X976982Y619115I191J58D01*
G01Y619117D01*
G02X976979Y619148I197J35D01*
G01Y619358D01*
G02X976982Y619389I200J-4D01*
G01Y619391D01*
G02X976988Y619416I197J-34D01*
G01X976991Y619423D01*
X976995Y619433D01*
X976998Y619439D01*
X977043Y619545D01*
X977072Y619573D01*
G03X977529Y620632I-1047J1080D01*
G01Y620653D01*
G03X977509Y620899I-1502J2D01*
G01X977506Y620915D01*
Y620916D01*
G02X977509Y620998I197J34D01*
G02X977519Y621028I194J-48D01*
G01X977525Y621041D01*
X977531Y621052D01*
G02X977539Y621064I170J-105D01*
G01X977574Y621107D01*
G02X977576Y621109I142J-140D01*
G01X977734Y621299D01*
X977751Y621319D01*
G02X977899Y621385I148J-134D01*
G01X982639D01*
G02X982822Y621264I-1J-200D01*
G01X982957Y620888D01*
G02X982904Y620686I-191J-58D01*
G01X982892Y620676D01*
G03X982341Y619513I952J-1163D01*
G03X982798Y618433I1505J0D01*
G01X982827Y618405D01*
X982872Y618300D01*
Y618299D01*
X982882Y618277D01*
G02X982888Y618251I-191J-58D01*
G01Y618249D01*
G02X982891Y618218I-197J-35D01*
G01Y618008D01*
G02X982874Y617928I-200J1D01*
G01X982828Y617822D01*
X982799Y617794D01*
G03Y615632I1044J-1081D01*
G01X982828Y615604D01*
X982874Y615498D01*
G02X982891Y615418I-183J-81D01*
G01Y615208D01*
G02X982888Y615177I-200J4D01*
G01Y615175D01*
G02X982882Y615150I-197J34D01*
G01X982879Y615143D01*
X982875Y615133D01*
X982872Y615127D01*
X982827Y615021D01*
X982798Y614993D01*
G03X982341Y613913I1048J-1080D01*
G03X985345I1502J0D01*
G03X984888Y614993I-1505J0D01*
G01X984859Y615021D01*
X984814Y615126D01*
Y615127D01*
X984804Y615149D01*
G02X984798Y615175I191J58D01*
G01Y615177D01*
G02X984795Y615208I197J35D01*
G01Y615418D01*
G02X984812Y615498I200J-1D01*
G01X984858Y615604D01*
X984887Y615632D01*
G03Y617794I-1044J1081D01*
G01X984858Y617822D01*
X984812Y617928D01*
G02X984795Y618008I183J81D01*
G01Y618218D01*
G02X984798Y618249I200J-4D01*
G01Y618251D01*
G02X984804Y618276I197J-34D01*
G01X984807Y618283D01*
X984811Y618293D01*
X984814Y618299D01*
X984859Y618405D01*
X984888Y618433D01*
G03X984849Y620630I-1048J1080D01*
G03X984847Y620632I-142J-140D01*
G03X984794Y620676I-986J-1134D01*
G01X984782Y620686D01*
G02X984729Y620888I138J144D01*
G01X984864Y621264D01*
G02X985047Y621385I184J-79D01*
G01X994460D01*
G02X994641Y621269I0J-200D01*
G01X994687Y621171D01*
X994797Y620935D01*
G02X994776Y620742I-184J-78D01*
G01X994774Y620740D01*
X994765Y620729D01*
X994764Y620728D01*
G03X994410Y619759I1149J-969D01*
G01Y619758D01*
G03X994414Y619641I1503J-7D01*
G01X994421Y619581D01*
G03X994591Y619044I1493J177D01*
G03X994865Y618681I1323J714D01*
G02X994867Y618679I-140J-142D01*
G01X994871Y618675D01*
G02X994913Y618612I-142J-140D01*
G01X994942Y618545D01*
X994953Y618520D01*
G02X994957Y618501I-193J-51D01*
G02X994961Y618464I-196J-40D01*
G01Y618253D01*
G02X994944Y618173I-200J1D01*
G01X994898Y618067D01*
X994869Y618039D01*
G03Y615877I1044J-1081D01*
G01X994898Y615849D01*
X994944Y615743D01*
G02X994961Y615663I-183J-81D01*
G01Y615438D01*
G02X994952Y615393I-200J17D01*
G01X994943Y615372D01*
X994942Y615371D01*
X994913Y615304D01*
G02X994871Y615241I-184J77D01*
G01X994868Y615238D01*
G03X994411Y614158I1048J-1080D01*
G03X997415I1502J0D01*
G03X996960Y615236I-1505J0D01*
G01X996955Y615241D01*
G02X996914Y615301I142J141D01*
G01X996913Y615303D01*
Y615304D01*
X996884Y615371D01*
X996873Y615396D01*
G02X996869Y615415I193J51D01*
G02X996865Y615452I196J40D01*
G01Y615663D01*
G02X996882Y615743I200J-1D01*
G01X996928Y615849D01*
X996957Y615877D01*
G03Y618039I-1044J1081D01*
G01X996928Y618067D01*
X996882Y618173D01*
G02X996865Y618253I183J81D01*
G01Y618478D01*
G02X996874Y618523I200J-17D01*
G01X996883Y618544D01*
X996884Y618545D01*
X996913Y618612D01*
G02X996914Y618614I179J-88D01*
G01X996917Y618621D01*
G02X996953Y618673I180J-86D01*
G01X996963Y618682D01*
G02X997094Y618734I134J-148D01*
G01X997227Y618737D01*
G02X997341Y618695I-9J-200D01*
G01X997351Y618686D01*
G02X997359Y618679I-128J-154D01*
G01X998969Y617069D01*
G03X1000599Y616394I1630J1631D01*
G01X1017434D01*
G02X1017554Y616354I0J-200D01*
G02X1017576Y616335I-119J-160D01*
G01X1049235Y584676D01*
G02X1049254Y584654I-141J-141D01*
G02X1049294Y584534I-160J-120D01*
G01Y553399D01*
G03X1049969Y551769I2306J0D01*
G01X1058169Y543569D01*
G03X1059799Y542894I1630J1631D01*
G01X1076662D01*
G02X1076776Y542859I1J-200D01*
G02X1076792Y542846I-118J-162D01*
G01X1085469Y534169D01*
G03X1086721Y533525I1631J1631D01*
G01X1086722D01*
X1086754Y533519D01*
X1086781Y533505D01*
G02X1086830Y533469I-93J-177D01*
G01X1088297Y532002D01*
G02X1088350Y531900I-143J-139D01*
G02X1088354Y531862I-196J-40D01*
G01Y470357D01*
G03X1088413Y470215I200J0D01*
G01X1089528Y469100D01*
G02X1089581Y468998I-143J-139D01*
G02X1089585Y468960I-196J-40D01*
G01Y459419D01*
G02X1089504Y459259I-200J1D01*
G01X1089246Y459068D01*
G02X1089163Y459032I-119J160D01*
G01X1089116Y459023D01*
X1089070Y459037D01*
G03X1088005Y459194I-1067J-3545D01*
G01X1088002D01*
G03Y451790I0J-3702D01*
G01X1088005D01*
G03X1089070Y451947I-2J3702D01*
G01X1089093Y451954D01*
X1089140Y451957D01*
X1089163Y451952D01*
G02X1089246Y451916I-36J-196D01*
G01X1089504Y451725D01*
G02X1089585Y451565I-119J-161D01*
G01Y376709D01*
G02X1089563Y376618I-200J0D01*
G02X1089527Y376568I-178J90D01*
G01X1089400Y376441D01*
G03X1088724Y374810I1631J-1632D01*
G01Y374809D01*
G03X1089497Y373087I2306J1D01*
G01X1089516Y373069D01*
X1089566Y372960D01*
G02X1089585Y372876I-181J-85D01*
G01Y313709D01*
G02X1089563Y313618I-200J0D01*
G02X1089527Y313568I-178J90D01*
G01X1088354Y312395D01*
G02X1088332Y312304I-200J0D01*
G02X1088296Y312254I-178J90D01*
G01X1077826Y301784D01*
G02X1077776Y301748I-140J142D01*
G02X1077685Y301726I-91J178D01*
G01X1076000D01*
G03X1074355Y301045I0J-2327D01*
G01X1068304Y294994D01*
G02X1068254Y294958I-140J142D01*
G02X1068163Y294936I-91J178D01*
G01X1039726D01*
G02X1039640Y295002I74J186D01*
G02X1039635Y295009I160J120D01*
G01X1039448Y295282D01*
G02X1039418Y295350I165J113D01*
G01X1039426Y295369D01*
G03X1039617Y296293I-2137J924D01*
G01Y296294D01*
G03X1039202Y297620I-2327J0D01*
G02X1039252Y297746I200J-7D01*
G03X1039646Y298789I-1185J1044D01*
G03X1036490I-1578J0D01*
G01Y298787D01*
G03X1036501Y298603I1578J2D01*
G02X1036471Y298472I-198J-23D01*
G03X1035869Y298136I821J-2178D01*
G02X1035811Y298105I-122J159D01*
G01X1035784Y298096D01*
X1035429D01*
X1035428D01*
G02X1035309Y298136I1J200D01*
G01X1035308Y298137D01*
G03X1034710Y298471I-1421J-1842D01*
G02X1034681Y298543I167J109D01*
G02X1034678Y298588I197J36D01*
G03X1034690Y298786I-1567J194D01*
G01Y298789D01*
G03X1031534I-1578J0D01*
G03X1031928Y297746I1579J1D01*
G02X1031978Y297619I-150J-132D01*
G03X1031564Y296296I1912J-1325D01*
G01Y296293D01*
G03X1032245Y294648I2327J0D01*
G01X1032660Y294232D01*
G02X1032705Y294137I-152J-130D01*
G02X1032708Y294102I-197J-35D01*
G01Y293768D01*
G03X1032725Y293491I2327J4D01*
G03X1032758Y293292I2309J281D01*
G02X1032760Y293269I-198J-29D01*
G01Y293268D01*
G03X1033430Y291731I2290J84D01*
G01X1035231Y289930D01*
G03X1036632Y289269I1621J1620D01*
G02X1036666Y289262I-23J-199D01*
G01X1036668D01*
G03X1037299Y289174I634J2238D01*
G01X1058041D01*
G02X1058161Y289134I0J-200D01*
G02X1058183Y289115I-119J-160D01*
G01X1058963Y288335D01*
G02X1059016Y288233I-143J-139D01*
G02X1059020Y288195I-196J-40D01*
G01Y285574D01*
G02X1058998Y285483I-200J0D01*
G02X1058962Y285433I-178J90D01*
G01X1055627Y282098D01*
G02X1055577Y282062I-140J142D01*
G02X1055486Y282040I-91J178D01*
G01X1005007D01*
G02X1004961Y282046I3J200D01*
G01X1004874Y282072D01*
X1004851Y282086D01*
G03X1003271I-790J-1277D01*
G01X1003248Y282072D01*
X1003161Y282046D01*
G02X1003115Y282040I-49J194D01*
G01X998869D01*
G02X998672Y282210I1J200D01*
G03X995702I-1485J-228D01*
G02X995505Y282040I-198J30D01*
G01X992865D01*
G02X992675Y282178I0J200D01*
G03X989817I-1429J-462D01*
G01X989807Y282147D01*
X989770Y282097D01*
X989744Y282078D01*
G02X989627Y282040I-117J162D01*
G01X944779D01*
G02X944750Y282042I-1J200D01*
G02X944665Y282076I30J198D01*
G01X944641Y282093D01*
X944623Y282116D01*
G02X944594Y282169I159J121D01*
G03X944173Y282783I-1411J-516D01*
G03X941773Y282172I-990J-1131D01*
G01Y282171D01*
X941772Y282168D01*
G02X941699Y282075I-187J72D01*
G01X941675Y282058D01*
X941646Y282049D01*
G02X941587Y282040I-59J191D01*
G01X855495D01*
G02X855381Y282077I2J200D01*
G01X855379D01*
G02X855338Y282116I116J163D01*
G03X852808I-1265J-809D01*
G02X852767Y282077I-157J124D01*
G01X852765D01*
G02X852651Y282040I-116J163D01*
G01X848869D01*
G02X848672Y282210I1J200D01*
G03X845702I-1485J-228D01*
G02X845505Y282040I-198J30D01*
G01X842865D01*
G02X842675Y282178I0J200D01*
G03X839817I-1429J-462D01*
G01X839807Y282147D01*
X839770Y282097D01*
X839744Y282078D01*
G02X839627Y282040I-117J162D01*
G01X806652D01*
G02X806602Y282004I-140J142D01*
G02X806511Y281982I-91J178D01*
G01X780726D01*
G02X780635Y282004I0J200D01*
G02X780585Y282040I90J178D01*
G01X741253Y321372D01*
G03X741111Y321431I-142J-141D01*
G01X534476D01*
G02X534385Y321453I0J200D01*
G02X534335Y321489I90J178D01*
G01X526207Y329617D01*
G03X526065Y329676I-142J-141D01*
G01X509655D01*
G02X509564Y329698I0J200D01*
G02X509514Y329734I90J178D01*
G01X478108Y361140D01*
G03X477966Y361199I-142J-141D01*
G01X474032D01*
G02X474012Y361200I0J200D01*
G02X473967Y361210I21J199D01*
G01X473877Y361242D01*
X473859Y361256D01*
G03X471967I-946J-1167D01*
G01X471949Y361242D01*
X471859Y361210D01*
G02X471814Y361200I-66J189D01*
G02X471794Y361199I-20J199D01*
G01X468243D01*
G02X468191Y361206I0J200D01*
G01X468119Y361226D01*
X468106Y361233D01*
X468095Y361240D01*
G03X466575I-760J-1295D01*
G01X466564Y361233D01*
X466551Y361226D01*
X466479Y361206D01*
G02X466427Y361199I-52J193D01*
G01X464816D01*
G02X464725Y361221I0J200D01*
G02X464675Y361257I90J178D01*
G01X454974Y370958D01*
G02X454948Y370990I141J141D01*
G01X454929Y371023D01*
X454922Y371052D01*
G03X453820Y372153I-1459J-358D01*
G01X453792Y372160D01*
X453770Y372173D01*
G02X453727Y372205I97J175D01*
G01X449652Y376280D01*
X449637Y376323D01*
G03X448645Y377315I-1545J-553D01*
G01X448602Y377330D01*
X448433Y377499D01*
G02X448383Y377697I142J141D01*
G01X448428Y377849D01*
Y377851D01*
X448485Y378041D01*
G02X448528Y378113I189J-64D01*
G01X448540Y378125D01*
G02X448586Y378157I136J-147D01*
G01X448604Y378166D01*
X448631Y378172D01*
X448632Y378173D01*
X448636D01*
G03X449815Y379467I-313J1470D01*
G01X449821Y379517D01*
G03X449826Y379643I-1498J123D01*
G03X449262Y380816I-1503J0D01*
G02X449200Y380942I138J146D01*
G01X449206Y381136D01*
X449211Y381304D01*
G02X449230Y381368I198J-24D01*
G01X449240Y381386D01*
X449269Y381421D01*
X449288Y381436D01*
G03X449893Y382641I-898J1205D01*
G03X448391Y384143I-1502J0D01*
G03X446899Y382817I0J-1502D01*
G01X446893Y382762D01*
G03X446888Y382641I1498J-122D01*
G03X446908Y382400I1502J3D01*
G03X447452Y381468I1483J241D01*
G02X447514Y381342I-138J-146D01*
G01X447508Y381148D01*
X447503Y380980D01*
G02X447484Y380916I-198J24D01*
G01X447474Y380898D01*
X447445Y380863D01*
X447426Y380848D01*
G03X446821Y379643I898J-1205D01*
G03X447325Y378521I1501J0D01*
G01X447326Y378520D01*
G02X447381Y378306I-134J-148D01*
G01X447313Y378126D01*
X447246Y377951D01*
G02X447059Y377822I-187J71D01*
G01X440730D01*
G03X440712Y377823I-136J-2287D01*
G01X440701D01*
G03X440650Y377824I-70J-2290D01*
G01X434202D01*
G03X434151Y377823I19J-2291D01*
G01X434140D01*
G03X434122Y377822I118J-2288D01*
G01X433336D01*
G03X433194Y377763I0J-200D01*
G01X432634Y377203D01*
G02X432630Y377199I-143J139D01*
G03X432582Y377152I1579J-1660D01*
G01X431064Y375634D01*
G03X431017Y375586I1613J-1627D01*
G02X431013Y375582I-143J139D01*
G01X428994Y373563D01*
G03X428935Y373421I141J-142D01*
G01Y358772D01*
X428920Y358735D01*
G03X428798Y358115I1519J-621D01*
G03X428920Y357495I1641J1D01*
G01X428935Y357458D01*
Y355476D01*
G02X428872Y355331I-200J1D01*
G01X428766Y355231D01*
X428653Y355125D01*
G02X428512Y355077I-130J152D01*
G01X428511D01*
G03X428420Y355080I-95J-1499D01*
G03X428220Y355067I-3J-1502D01*
G01Y355068D01*
G03X428093Y355045I204J-1489D01*
G01X428050Y355036D01*
X428015Y355043D01*
G02X427943Y355071I35J197D01*
G01X427692Y355237D01*
G02X427644Y355287I118J161D01*
G01X427622Y355319D01*
X427614Y355361D01*
G03X426138Y356581I-1476J-283D01*
G03X424636Y355079I0J-1502D01*
G03X425962Y353587I1502J0D01*
G01X426019Y353581D01*
G03X426138Y353576I123J1498D01*
G03X426465Y353612I0J1503D01*
G01X426508Y353621D01*
X426543Y353614D01*
G02X426617Y353585I-34J-197D01*
G01X426859Y353425D01*
G02X426910Y353376I-111J-166D01*
G01X426936Y353337D01*
X426944Y353296D01*
G03X427107Y352846I1476J280D01*
G01X427114Y352835D01*
G03X428292Y352080I1306J742D01*
G01X428296D01*
G03X428350Y352077I110J1498D01*
G01X428352D01*
G03X428419Y352075I78J1500D01*
G01X428421D01*
G03X428511Y352078I-5J1503D01*
G01X428554Y352080D01*
X428589Y352068D01*
G02X428652Y352032I-66J-189D01*
G01X428872Y351825D01*
G02X428935Y351680I-137J-146D01*
G01Y347675D01*
G02X428933Y347648I-200J1D01*
G02X428883Y347543I-198J30D01*
G01X428784Y347446D01*
X428662Y347327D01*
G02X428605Y347292I-132J151D01*
G01X428570Y347278D01*
X428500D01*
G03Y344274I0J-1502D01*
G01X428570D01*
X428605Y344260D01*
G02X428670Y344217I-76J-185D01*
G01X428875Y344017D01*
G02X428935Y343874I-140J-143D01*
G01Y333148D01*
G02X428892Y333030I-200J6D01*
G01X428882Y333019D01*
X428688Y332833D01*
X428654Y332800D01*
G02X428597Y332768I-125J156D01*
G01X428561Y332755D01*
X428521Y332756D01*
G03X428459Y332757I-55J-1501D01*
G03Y329753I0J-1502D01*
G03X428520Y329754I6J1502D01*
G01X428561Y329755D01*
X428597Y329742D01*
G02X428657Y329707I-69J-187D01*
G01X428737Y329630D01*
X428880Y329493D01*
X428892Y329480D01*
G02X428935Y329362I-157J-124D01*
G01Y323660D01*
X428926Y323631D01*
G03X428911Y323580I1433J-449D01*
G01X428910Y323576D01*
X428908Y323570D01*
X428899Y323537D01*
X428866Y323496D01*
G02X428814Y323456I-146J137D01*
G01X428768Y323434D01*
G02X428764Y323432I-91J178D01*
G01X428561Y323339D01*
G02X428510Y323325I-78J184D01*
G01X428508D01*
G02X428483Y323323I-28J198D01*
G01X428415D01*
G02X428381Y323326I1J200D01*
G01X428367Y323329D01*
X428319Y323340D01*
X428318D01*
G03X428305Y323346I-636J-1361D01*
G01X428300Y323348D01*
G03X427713Y323467I-586J-1383D01*
G01X427693D01*
G03X426211Y321965I20J-1502D01*
G03X427696Y320463I1502J0D01*
G01X427721D01*
G03X428360Y320609I-7J1502D01*
G01X428384Y320620D01*
G02X428418Y320628I63J-190D01*
G02X428443Y320630I28J-198D01*
G01X428494Y320625D01*
G02X428540Y320608I-46J-194D01*
G01X428696Y320511D01*
X428850Y320414D01*
G02X428852Y320412I-138J-140D01*
G01X428864Y320402D01*
G03X428866Y320400I141J139D01*
G01X428877Y320390D01*
G02X428917Y320333I-141J-142D01*
G02X428935Y320255I-182J-83D01*
G01Y316955D01*
G02X428913Y316864I-200J0D01*
G02X428877Y316814I-178J90D01*
G01X423514Y311451D01*
G02X423434Y311403I-140J143D01*
G01X423394Y311392D01*
X423340Y311394D01*
G03X423284Y311411I-464J-1428D01*
G01X423278Y311413D01*
X423277D01*
X423273Y311414D01*
X423259Y311418D01*
G03X423074Y311455I-387J-1452D01*
G01X423072D01*
G03X423035Y311460I-220J-1486D01*
G01X423029D01*
X423022Y311461D01*
X423018D01*
G03X422958Y311466I-155J-1494D01*
G01X422949D01*
X422940Y311467D01*
X422934D01*
G03X422878Y311469I-82J-1500D01*
G01X422872D01*
G03X421605Y310772I1J-1502D01*
G01X421600Y310765D01*
X421586Y310746D01*
G02X421561Y310724I-144J139D01*
G01X421535Y310706D01*
X421451Y310657D01*
G02X421392Y310636I-96J176D01*
G02X421359Y310633I-35J197D01*
G01X380160D01*
G02X380069Y310655I0J200D01*
G02X380019Y310691I90J178D01*
G01X360308Y330402D01*
G02X360272Y330452I142J140D01*
G02X360250Y330543I178J91D01*
G01Y383649D01*
G02X360254Y383686I200J-3D01*
G01X360263Y383729D01*
G02X360282Y383780I195J-44D01*
G01X360299Y383812D01*
X360337Y383884D01*
X360363Y383903D01*
X360375Y383912D01*
G03X360390Y383923I-881J1217D01*
G03X360392Y383925I-139J141D01*
G03X360399Y383930I-869J1224D01*
G01X360400Y383931D01*
X360408Y383937D01*
G03X360546Y384058I-920J1188D01*
G03X360550Y384062I-139J143D01*
G03X360563Y384076I-1094J1029D01*
G01X360564Y384077D01*
G03X360566Y384079I-140J142D01*
G03X360572Y384086I-1135J979D01*
G01X360672Y384188D01*
G02X360726Y384227I143J-140D01*
G01X360775Y384251D01*
X360787Y384257D01*
G02X360874Y384277I87J-180D01*
G01X361098D01*
G02X361185Y384257I0J-200D01*
G01X361197Y384251D01*
X361283Y384209D01*
X361310Y384188D01*
X361312Y384186D01*
X361326Y384168D01*
G03X362486Y383621I1160J956D01*
G03X363988Y385123I0J1502D01*
G03X362662Y386615I-1502J0D01*
G01X362605Y386621D01*
G03X362486Y386626I-123J-1498D01*
G03X361324Y386077I0J-1504D01*
G01X361307Y386057D01*
X361281Y386036D01*
X361200Y385996D01*
X361185Y385989D01*
G02X361098Y385969I-87J180D01*
G01X360874D01*
G02X360787Y385989I0J200D01*
G01X360775Y385995D01*
X360691Y386036D01*
X360662Y386059D01*
X360647Y386077D01*
G03X360615Y386114I-1152J-964D01*
G01X360613Y386116D01*
X360609Y386121D01*
G03X360587Y386145I-1118J-1003D01*
G03X360566Y386167I-1097J-1026D01*
G03X360564Y386169I-142J-140D01*
G02X360562Y386171I140J142D01*
G03X360560Y386173I-1063J-1061D01*
G02X360558Y386175I140J142D01*
G03X360423Y386297I-1073J-1051D01*
G03X360400Y386315I-937J-1174D01*
G01X360397Y386318D01*
G03X360391Y386322I-835J-1245D01*
G01X360390Y386323D01*
G03X360375Y386334I-896J-1206D01*
G01X360363Y386343D01*
X360336Y386363D01*
X360273Y386482D01*
Y386483D01*
G02X360250Y386575I177J93D01*
G01Y390688D01*
G02X360320Y390841I200J1D01*
G01X360322D01*
G02X360327Y390846I143J-138D01*
G01X360347Y390860D01*
X360480Y390928D01*
X360677Y391028D01*
G02X360752Y391049I90J-178D01*
G01X360784D01*
G02X360871Y391022I-14J-200D01*
G01X360886Y391011D01*
G03X361767Y390726I881J1219D01*
G03X363269Y392228I0J1502D01*
G03X361943Y393720I-1502J0D01*
G01X361889Y393726D01*
G03X361767Y393731I-122J-1498D01*
G03X360886Y393446I0J-1504D01*
G03X360884Y393445I87J-177D01*
G03X360870Y393437I91J-175D01*
G01X360849Y393424D01*
G02X360782Y393406I-85J181D01*
G01X360727Y393402D01*
X360656Y393438D01*
X360356Y393591D01*
G02X360321Y393615I95J176D01*
G02X360250Y393768I129J153D01*
G01Y395363D01*
G02X360252Y395390I200J-1D01*
G02X360351Y395533I198J-31D01*
G01X360546Y395628D01*
X360696Y395701D01*
G02X360793Y395716I78J-184D01*
G01X360819Y395714D01*
X360871Y395694D01*
X360895Y395675D01*
G03X361811Y395364I915J1191D01*
G01X361839D01*
G03X363313Y396866I-28J1502D01*
G03X361811Y398368I-1502J0D01*
G01X361810D01*
G03X360894Y398056I1J-1502D01*
G01X360856Y398027D01*
X360848Y398021D01*
X360793Y398016D01*
G02X360686Y398035I-20J199D01*
G01X360489Y398131D01*
X360349Y398200D01*
G02X360252Y398342I101J173D01*
G02X360250Y398369I198J28D01*
G01Y401057D01*
G02X360252Y401081I200J-5D01*
G01Y401083D01*
G02X360297Y401185I198J-26D01*
G01X360304Y401193D01*
G03X360306Y401195I-140J142D01*
G01X360307Y401196D01*
G03X360318Y401208I-141J141D01*
G02X360324Y401213I131J-151D01*
G01X360603Y401415D01*
G02X360714Y401448I110J-167D01*
G01X360767Y401439D01*
X360774Y401437D01*
X360780Y401435D01*
G03X360884Y401406I455J1431D01*
G03X361000Y401383I350J1461D01*
G03X361220Y401365I232J1484D01*
G01X361243D01*
G03X361244Y404369I-9J1502D01*
G01X361232D01*
G03X360780Y404299I1J-1502D01*
G01X360774Y404297D01*
X360767Y404295D01*
X360714Y404286D01*
G02X360602Y404320I0J200D01*
G01X360596Y404324D01*
X360591Y404328D01*
X360329Y404517D01*
G02X360312Y404532I124J157D01*
G01X360306Y404539D01*
G03X360304Y404541I-142J-140D01*
G01X360297Y404549D01*
G02X360252Y404651I153J128D01*
G01Y404653D01*
G02X360250Y404677I198J29D01*
G01Y445764D01*
G02X360257Y445818I200J1D01*
G02X360262Y445832I191J-60D01*
G01X360309Y445943D01*
X360314Y445949D01*
X360327Y445963D01*
G03Y448039I-1087J1038D01*
G01X360314Y448053D01*
X360309Y448059D01*
X360262Y448170D01*
G02X360257Y448184I186J74D01*
G02X360250Y448238I193J53D01*
G01Y448553D01*
G02X360276Y448642I200J-10D01*
G01X360281Y448650D01*
G02X360345Y448713I169J-108D01*
G01X360679Y448886D01*
X360681D01*
X360699Y448896D01*
X360752Y448907D01*
X360780Y448905D01*
G02X360825Y448896I-16J-199D01*
G01X360846Y448886D01*
X360869Y448875D01*
X360881Y448868D01*
X360889Y448862D01*
G03X360899Y448855I867J1227D01*
G03X361754Y448589I854J1236D01*
G01X361773D01*
G03X362079Y448625I-21J1501D01*
G03X363027Y449295I-325J1466D01*
G02X363184Y449371I157J-124D01*
G01X363533D01*
G02X363679Y449295I-11J-200D01*
G03X364498Y448659I1274J796D01*
G01X364532Y448649D01*
G03X364794Y448597I422J1442D01*
G03X364930Y448589I156J1494D01*
G01X364955D01*
G03X365730Y448804I1J1502D01*
G01X365786Y448838D01*
G03X365801Y448848I-103J171D01*
G01X365840Y448877D01*
G03X365855Y448888I-881J1217D01*
G01X365862Y448893D01*
X365863Y448894D01*
G02X365945Y448928I116J-163D01*
G01X365991Y448936D01*
X366194Y448870D01*
X366196D01*
X366367Y448812D01*
G02X366432Y448768I-77J-184D01*
G01X366449Y448750D01*
X366472Y448711D01*
X366480Y448686D01*
G03X366874Y448038I1439J431D01*
G01X366903Y448011D01*
X366950Y447903D01*
G02X366967Y447823I-183J-81D01*
G01Y447613D01*
G02X366958Y447553I-200J-1D01*
G01X366949Y447532D01*
X366948Y447531D01*
X366919Y447464D01*
G02X366877Y447401I-184J77D01*
G01X366874Y447398D01*
G03X366417Y446318I1048J-1080D01*
G03X369421I1502J0D01*
G03X368965Y447397I-1505J0D01*
G02X368963Y447399I140J142D01*
G01X368934Y447428D01*
X368890Y447531D01*
X368889Y447532D01*
X368880Y447553D01*
G02X368871Y447613I191J59D01*
G01Y447823D01*
G02X368880Y447883I200J1D01*
G01X368889Y447904D01*
X368890Y447905D01*
X368919Y447972D01*
G02X368961Y448035I184J-77D01*
G01X368964Y448038D01*
G03X369421Y449118I-1048J1080D01*
G03X367943Y450620I-1502J0D01*
G01X367918D01*
G03X367143Y450405I-1J-1502D01*
G01X367087Y450371D01*
G03X367072Y450361I103J-171D01*
G01X367033Y450332D01*
G03X367029Y450329I899J-1203D01*
G02X367021Y450323I-124J157D01*
G01X367019Y450322D01*
X367018Y450321D01*
X367001Y450309D01*
G02X366928Y450281I-107J169D01*
G01X366883Y450273D01*
X366522Y450391D01*
G02X366440Y450442I61J190D01*
G01X366424Y450459D01*
X366401Y450496D01*
X366393Y450523D01*
G03X363680Y450887I-1439J-433D01*
G02X363533Y450811I-157J124D01*
G01X363175D01*
G02X363029Y450887I11J200D01*
G03X362039Y451567I-1275J-796D01*
G03X361330Y451532I-283J-1475D01*
G03X361215Y451493I424J-1441D01*
G03X360882Y451314I539J-1402D01*
G01X360881D01*
X360880Y451313D01*
G02X360780Y451277I-115J163D01*
G01X360725Y451273D01*
X360648Y451313D01*
X360351Y451466D01*
G02X360262Y451572I99J174D01*
G02X360250Y451640I188J68D01*
G01Y460522D01*
G02X360276Y460611I200J-10D01*
G01X360281Y460619D01*
G02X360345Y460682I169J-108D01*
G01X360679Y460855D01*
X360681D01*
X360699Y460865D01*
X360752Y460876D01*
X360780Y460874D01*
G02X360825Y460865I-16J-199D01*
G01X360846Y460854D01*
X360869Y460844D01*
X360881Y460837D01*
X360889Y460831D01*
G03X360899Y460824I867J1227D01*
G03X361754Y460558I854J1236D01*
G01X361773D01*
G03X363256Y462060I-19J1502D01*
G03X361754Y463562I-1502J0D01*
G03X360882Y463283I0J-1502D01*
G01X360881D01*
X360880Y463282D01*
G02X360780Y463246I-115J163D01*
G01X360725Y463242D01*
X360648Y463282D01*
X360351Y463435D01*
G02X360262Y463541I99J174D01*
G02X360250Y463609I188J68D01*
G01Y475379D01*
G02X360300Y475497I200J-15D01*
G01X360324Y475524D01*
X360387Y475557D01*
X360426Y475562D01*
G03Y478544I-184J1491D01*
G01X360422Y478545D01*
G02X360299Y478610I26J198D01*
G01X360276Y478637D01*
X360263Y478671D01*
G02X360260Y478678I182J82D01*
G02X360255Y478696I190J63D01*
G02X360250Y478740I195J44D01*
G01Y490645D01*
G02X360306Y490775I200J-9D01*
G03X360780Y491870I-1028J1095D01*
G03X360777Y491968I-1502J3D01*
G01X360774Y492020D01*
X360793Y492063D01*
G02X360809Y492092I183J-82D01*
G02X360820Y492106I163J-117D01*
G03X360822Y492108I-140J142D01*
G02X360851Y492136I153J-129D01*
G01X360888Y492163D01*
X360950Y492208D01*
X361110Y492324D01*
X361141Y492346D01*
G02X361228Y492378I111J-166D01*
G01X361277Y492384D01*
X361324Y492365D01*
X361326D01*
G03X361887Y492256I562J1393D01*
G03X363389Y493739I0J1502D01*
G01Y493758D01*
G03X363064Y494692I-1502J1D01*
G01X363063Y494693D01*
X363051Y494708D01*
X363033Y494743D01*
X363019Y494783D01*
Y494946D01*
X362975D01*
Y495185D01*
G02X363009Y495259I195J-45D01*
G01X363018Y495270D01*
X363019Y495271D01*
G03X363389Y496258I-1131J987D01*
G03X362063Y497750I-1502J0D01*
G01X362009Y497756D01*
G03X361888Y497761I-122J-1498D01*
G01X361886D01*
G03X361759Y497755I7J-1502D01*
G03X361738Y497753I132J-1497D01*
G01X361682Y497748D01*
G03X361662Y497745I20J-199D01*
G01X361615Y497736D01*
X361614D01*
G03X361514Y497714I273J-1478D01*
G03X360930Y497417I373J-1456D01*
G01X360909Y497400D01*
X360806Y497353D01*
X360779Y497349D01*
X360753Y497353D01*
G02X360698Y497369I28J198D01*
G01X360476Y497471D01*
X360352Y497528D01*
G02X360345Y497532I96J176D01*
G02X360251Y497684I105J170D01*
G01Y497686D01*
G02X360250Y497701I199J21D01*
G01Y506752D01*
G02X360254Y506789I200J-3D01*
G01Y506791D01*
G02X360307Y506892I196J-39D01*
G01X360784Y507369D01*
G03X360843Y507511I-141J142D01*
G01Y527503D01*
G02X360807Y527553I142J140D01*
G02X360785Y527644I178J91D01*
G01Y724146D01*
G02X360789Y724183I200J-3D01*
G01Y724185D01*
G02X360842Y724286I196J-39D01*
G01X361467Y724911D01*
G02X361569Y724964I139J-143D01*
G02X361607Y724968I40J-196D01*
G01X405845D01*
X405855Y724967D01*
G02X405933Y724944I-16J-199D01*
G02X405980Y724909I-95J-176D01*
G01X406256Y724633D01*
G02X406306Y724535I-146J-136D01*
G01Y724533D01*
G02X406310Y724496I-196J-40D01*
G01Y722085D01*
G02X406288Y721994I-200J0D01*
G02X406252Y721944I-178J90D01*
G01X395770Y711462D01*
G03X395717Y711406I848J-856D01*
G01X395708Y711396D01*
X395478Y711166D01*
X395477Y711165D01*
G02X395475Y711163I-142J140D01*
G03X395468Y711156I138J-145D01*
G01X395465Y711152D01*
X395450Y711137D01*
X395420Y711064D01*
Y710709D01*
G02X395419Y710696I-199J9D01*
G01Y710691D01*
G03X395418Y710678I1201J-99D01*
G01Y710677D01*
G03X395416Y710610I1203J-69D01*
G01Y601909D01*
G03X395419Y601828I1205J4D01*
G01Y601823D01*
G02X395420Y601810I-198J-22D01*
G01Y601455D01*
X395450Y601382D01*
X395465Y601367D01*
X395468Y601363D01*
G03X395475Y601356I145J138D01*
G02X395477Y601354I-140J-142D01*
G01X395478Y601353D01*
X395708Y601123D01*
X395717Y601113D01*
G03X395770Y601057I901J800D01*
G01X406249Y590578D01*
G02X406302Y590477I-143J-140D01*
G01Y590475D01*
G02X406306Y590438I-196J-40D01*
G01Y529330D01*
G03X406321Y529255I200J1D01*
G01X406474Y528877D01*
G03X406520Y528809I185J76D01*
G01X406665Y528669D01*
G02X406667Y528667I-140J-142D01*
G01X410789Y524545D01*
G03X411641Y524192I852J851D01*
G01X414515D01*
G02X414552Y524188I-3J-200D01*
G01X414554D01*
G02X414655Y524135I-39J-196D01*
G01X415015Y523775D01*
G03X415157Y523716I142J141D01*
G01X463566D01*
G03X463708Y523775I0J200D01*
G01X464068Y524135D01*
G02X464169Y524188I140J-143D01*
G01X464171D01*
G02X464208Y524192I40J-196D01*
G01X469580D01*
G03X469632Y524199I0J200D01*
G01X469646Y524203D01*
X470032Y524359D01*
G03X470101Y524406I-76J185D01*
G01X470240Y524550D01*
G02X470242Y524552I142J-140D01*
G01X471463Y525773D01*
G03X471816Y526625I-851J852D01*
G01Y609334D01*
G03X471814Y609388I-1204J-18D01*
G01Y609789D01*
G03X471786Y609891I-200J0D01*
G01X471772Y609915D01*
X471765Y609940D01*
G02X471758Y609992I193J52D01*
G01Y637427D01*
G02X471762Y637464I200J-3D01*
G01Y637466D01*
G02X471815Y637567I196J-39D01*
G01X475987Y641739D01*
G03X476038Y641793I-850J854D01*
G01X476047Y641803D01*
X476282Y642038D01*
G03X476290Y642046I-137J145D01*
G01X476308Y642064D01*
X476309Y642066D01*
X476338Y642094D01*
Y642534D01*
G03X476340Y642590I-1202J71D01*
G01Y722225D01*
G02X476344Y722262I200J-3D01*
G01Y722264D01*
G02X476397Y722365I196J-39D01*
G01X480068Y726036D01*
G02X480118Y726072I140J-142D01*
G02X480209Y726094I91J-178D01*
G01X541500D01*
G03X542389Y726443I0J1307D01*
G02X542482Y726486I128J-154D01*
G02X542517Y726489I35J-197D01*
G01X543555D01*
G02X543592Y726485I-3J-200D01*
G01X543594D01*
G02X543695Y726432I-39J-196D01*
G01X547958Y722169D01*
G02X548010Y722077I-142J-141D01*
G02X547959Y721888I-194J-49D01*
G01X535191Y709121D01*
G03X534820Y708225I896J-896D01*
G01Y703253D01*
G02X534814Y703207I-200J3D01*
G01X534791Y703125D01*
X534783Y703110D01*
G03X534585Y702365I1305J-746D01*
G01Y702364D01*
G03X537589I1502J0D01*
G01Y702365D01*
G03X537391Y703110I-1503J-1D01*
G01X537383Y703125D01*
X537360Y703207D01*
G02X537354Y703253I194J49D01*
G01Y707617D01*
G02X537359Y707661I200J0D01*
G02X537411Y707757I195J-44D01*
G01X549750Y720096D01*
G02X549871Y720153I141J-142D01*
G01X549910D01*
G02X549940Y720148I-18J-199D01*
G02X550015Y720110I-51J-193D01*
G01X550026Y720100D01*
X550031Y720096D01*
X553659Y716468D01*
G02X553712Y716367I-143J-140D01*
G01Y716365D01*
G02X553716Y716328I-196J-40D01*
G01Y689650D01*
G02X553694Y689559I-200J0D01*
G02X553658Y689509I-178J90D01*
G01X553352Y689203D01*
G02X553302Y689167I-140J142D01*
G02X553211Y689145I-91J178D01*
G01X549977D01*
G02X549947Y689147I-2J200D01*
G02X549836Y689203I30J198D01*
G01X544415Y694626D01*
G02X544408Y694635I154J127D01*
G01Y697979D01*
G02X544431Y698072I200J0D01*
G03X544604Y698772I-1330J700D01*
G01Y698778D01*
X544602Y698837D01*
G03X541600I-1501J-65D01*
G01X541598Y698778D01*
Y698772D01*
G03X541771Y698072I1503J0D01*
G02X541794Y697979I-177J-93D01*
G01Y695049D01*
G02X541793Y695025I-200J-4D01*
G02X541686Y694871I-199J24D01*
G01X541563Y694821D01*
X541541Y694832D01*
G02X541498Y694863I94J176D01*
G01X540493Y695869D01*
G03X539597Y696240I-896J-896D01*
G01X537591D01*
G02X537500Y696262I0J200D01*
G02X537450Y696298I90J178D01*
G01X535381Y698367D01*
G03X534457Y698750I-924J-923D01*
G01X531298D01*
G02X531137Y698832I0J200D01*
G01X530948Y699120D01*
G02X530916Y699214I167J109D01*
G01X530912Y699263D01*
X530927Y699299D01*
G03X531065Y699942I-1433J644D01*
G01Y699944D01*
G03X530460Y701184I-1574J0D01*
G01X530448Y701193D01*
X530402Y701242D01*
G02X530375Y701304I167J110D01*
G02X530369Y701351I194J49D01*
G01Y701428D01*
G02X530387Y701510I200J-1D01*
G01X530404Y701548D01*
X530436Y701577D01*
G03X530903Y702622I-936J1045D01*
G03X529501Y704024I-1402J0D01*
G03X529240Y703999I3J-1402D01*
G01X529221Y703996D01*
X529202D01*
G02X529002Y704196I0J200D01*
G01Y704395D01*
G02X529014Y704463I200J0D01*
G01X529026Y704496D01*
X529101Y704585D01*
X529169Y704666D01*
G02X529229Y704710I146J-137D01*
G01X529267Y704728D01*
X529310Y704729D01*
G03X529613Y704768I-35J1467D01*
G01X529637Y704772D01*
G03X530936Y706230I-169J1458D01*
G03X529469Y707697I-1467J0D01*
G03X529371Y707694I-4J-1467D01*
G02X529343Y707696I0J200D01*
G03X529124Y707713I-223J-1450D01*
G01X529122D01*
G03X528174Y707366I0J-1468D01*
G01X528148Y707344D01*
X528046Y707306D01*
G02X527981Y707296I-62J190D01*
G01X527941Y707298D01*
X527894Y707300D01*
X527821Y707335D01*
X527794Y707365D01*
G03X526700Y707855I-1094J-977D01*
G01X526699D01*
G03X526488Y707840I-2J-1467D01*
G01X526466Y707838D01*
X526461D01*
G03X526318Y707825I61J-1467D01*
G03X525554Y707478I200J-1454D01*
G01X525525Y707453D01*
X525494Y707441D01*
G02X525426Y707428I-71J187D01*
G01X525289Y707430D01*
X525154Y707432D01*
G02X525081Y707446I0J200D01*
G01X525049Y707459D01*
X525021Y707485D01*
X525020Y707486D01*
G03X524023Y707877I-997J-1076D01*
G01X524022D01*
G03X523951Y707875I6J-1466D01*
G01X523943D01*
G03X523655Y707830I81J-1465D01*
G01X523644Y707827D01*
X523637Y707826D01*
X523635D01*
X523631Y707825D01*
G03X522816Y707344I298J-1437D01*
G01X522757Y707275D01*
G02X522747Y707274I-25J198D01*
G01X522637Y707275D01*
G02X522548Y707296I0J200D01*
G01X522429Y707357D01*
X522421Y707368D01*
G03X521134Y708021I-1287J-942D01*
G03X519952Y707498I0J-1597D01*
G01X519924Y707467D01*
X519815Y707418D01*
G02X519733Y707400I-83J182D01*
G01X519662D01*
G02X519647Y707401I6J200D01*
G01X519645D01*
G02X519584Y707416I17J199D01*
G01X519548Y707432D01*
X519520Y707461D01*
G03X518467Y707906I-1053J-1023D01*
G03X517639Y707650I0J-1468D01*
G02X517631Y707644I-124J157D01*
G03X517529Y707576I762J-1253D01*
G03X517255Y707318I860J-1188D01*
G01X517254Y707317D01*
X517207Y707261D01*
G02X517184Y707254I-70J188D01*
G01X516992Y707230D01*
X516874Y707215D01*
X516867D01*
X516797Y707302D01*
G03X515649Y707855I-1148J-915D01*
G03X514182Y706388I0J-1467D01*
G03X514504Y705471I1467J0D01*
G01X514508Y705466D01*
X514512Y705460D01*
X514530Y705431D01*
X514534Y705424D01*
G03X515838Y704630I1304J674D01*
G03X516180Y704671I-2J1467D01*
G01X516183D01*
G02X516283Y704669I46J-195D01*
G01X516306Y704662D01*
X516327Y704650D01*
G02X516367Y704619I-102J-172D01*
G01X516380Y704606D01*
G02X516369Y704335I-152J-130D01*
G01X516359Y704325D01*
G03X516006Y703475I849J-851D01*
G01Y703215D01*
G02X516005Y703199I-200J4D01*
G01Y703197D01*
G02X515947Y703073I-199J18D01*
G01X515735Y702871D01*
G02X515664Y702828I-137J146D01*
G01X515626Y702814D01*
X515585Y702816D01*
G03X515504Y702818I-77J-1465D01*
G03Y699884I0J-1467D01*
G03X515585Y699886I4J1467D01*
G01X515624Y699888D01*
X515661Y699875D01*
X515664Y699874D01*
G02X515735Y699831I-66J-189D01*
G01X515947Y699629D01*
G02X516005Y699505I-141J-142D01*
G01Y699503D01*
G02X516006Y699487I-199J-20D01*
G01Y697619D01*
G02X515943Y697474I-200J1D01*
G01X515890Y697424D01*
X515731Y697275D01*
X515730D01*
G02X515594Y697221I-137J146D01*
G01X515580D01*
G03X515484Y697224I-94J-1464D01*
G03X514017Y695757I0J-1467D01*
G03X514846Y694436I1467J0D01*
G01X514871Y694424D01*
X514911Y694389D01*
X514927Y694365D01*
G02X514959Y694272I-167J-110D01*
G01X514967Y694060D01*
X514973Y693911D01*
G02X514962Y693838I-200J-7D01*
G02X514954Y693818I-189J64D01*
G02X514873Y693730I-181J85D01*
G01X514861Y693723D01*
G03X514841Y691319I712J-1208D01*
G03X515549Y691113I732J1196D01*
G01X515575D01*
G03X516563Y691521I-1J1402D01*
G03X516565Y691523I-140J142D01*
G02X516625Y691565I143J-140D01*
G01X516639Y691570D01*
X516645Y691573D01*
X516647D01*
X516700Y691597D01*
G02X516723Y691604I70J-188D01*
G01X516727D01*
G02X516783Y691610I49J-194D01*
G01X516830Y691607D01*
X516831D01*
X516931Y691550D01*
X516950Y691540D01*
X516986Y691519D01*
X516991Y691511D01*
X516992Y691510D01*
G03X518299Y690812I1307J875D01*
G01X518300D01*
G03X519334Y691201I-1J1572D01*
G01X519355Y691218D01*
X519453Y691256D01*
G02X519526Y691270I73J-186D01*
G01X519572D01*
G02X519645Y691256I0J-200D01*
G01X519743Y691218D01*
X519764Y691201D01*
G03X520798Y690812I1035J1183D01*
G01X520799D01*
G03X522371Y692384I0J1572D01*
G01Y692386D01*
G03X522352Y692630I-1572J0D01*
G01X522350Y692661D01*
G02X522403Y692797I200J1D01*
G01X522426Y692822D01*
X522451Y692849D01*
G02X522596Y692912I146J-137D01*
G01X522699D01*
G02X522800Y692881I-6J-200D01*
G02X522837Y692850I-109J-168D01*
G01X522867Y692818D01*
X522882Y692803D01*
G02X522935Y692679I-147J-136D01*
G01Y692666D01*
X522934Y692641D01*
X522933Y692635D01*
G03X522921Y692445I1560J-194D01*
G01Y692443D01*
G03X524493Y690871I1572J0D01*
G01X524494D01*
G03X525660Y691389I0J1571D01*
G01X525670Y691401D01*
G03X525687Y691420I-1162J1057D01*
G01X525786Y691465D01*
G02X525806Y691472I76J-185D01*
G01X525882Y691489D01*
X525885D01*
G02X525957Y691475I-2J-200D01*
G01X525990Y691462D01*
X526023Y691430D01*
G03X526485Y691136I969J1013D01*
G01X526524Y691121D01*
X527958Y689686D01*
G03X528423Y689391I895J896D01*
G03X528575Y689347I427J1192D01*
G01X528590Y689343D01*
G03X528854Y689316I260J1239D01*
G01X534480D01*
G02X534663Y689196I0J-200D01*
G01X534729Y689021D01*
X534803Y688825D01*
G02X534806Y688715I-191J-60D01*
G01X534800Y688688D01*
X534769Y688637D01*
X534767Y688635D01*
X534757Y688627D01*
X534745Y688616D01*
G03X534236Y687525I993J-1127D01*
G01Y687489D01*
G03X534581Y686530I1502J-1D01*
G01X534583Y686528D01*
X534596Y686512D01*
G02X534628Y686370I-166J-112D01*
G01X534535Y686018D01*
G02X534494Y685949I-189J66D01*
G01X534478Y685932D01*
X534439Y685906D01*
X534416Y685897D01*
G03X533438Y684489I525J-1408D01*
G03X534940Y682987I1502J0D01*
G03X536442Y684453I0J1502D01*
G01Y684489D01*
G03X536097Y685448I-1502J1D01*
G01X536095Y685450D01*
X536082Y685466D01*
G02X536050Y685608I166J112D01*
G01X536143Y685960D01*
G02X536184Y686029I189J-66D01*
G01X536200Y686046D01*
X536239Y686072D01*
X536262Y686081D01*
G03X536700Y686335I-524J1408D01*
G01X536729Y686359D01*
X536764Y686371D01*
G02X536835Y686381I63J-190D01*
G01X536918Y686377D01*
X536920D01*
X537087Y686367D01*
G02X537131Y686356I-26J-198D01*
G01X537242Y686306D01*
X537268Y686281D01*
G03X537320Y686232I1056J1068D01*
G03X537322Y686230I142J140D01*
G03X538314Y685855I993J1127D01*
G01X538347D01*
G03X538851Y685953I-31J1504D01*
G03X539554Y686505I-535J1406D01*
G01X539567Y686524D01*
X539601Y686556D01*
X539619Y686566D01*
G02X539691Y686590I98J-174D01*
G01X539825Y686603D01*
X539827D01*
X540021Y686620D01*
G02X540154Y686573I4J-200D01*
G01X551373Y675354D01*
G03X551838Y675059I895J896D01*
G03X551990Y675015I427J1192D01*
G01X552005Y675011D01*
G03X552269Y674984I260J1239D01*
G01X552600D01*
G02X552615Y674983I-6J-200D01*
G01X552617D01*
G02X552785Y674860I-17J-199D01*
G01X552786Y674858D01*
X552791Y674845D01*
Y674844D01*
X552795Y674835D01*
X552797Y674829D01*
X552803Y674773D01*
X552797Y674745D01*
G02X552750Y674651I-196J39D01*
G01X551859Y673761D01*
X551308Y673210D01*
G02X551167Y673152I-141J142D01*
G01X539922D01*
G02X539831Y673174I0J200D01*
G02X539781Y673210I90J178D01*
G01X523633Y689358D01*
G03X522711Y689740I-923J-924D01*
G01X510991D01*
G03X510069Y689358I1J-1306D01*
G01X500255Y679544D01*
G02X500249Y679538I-145J139D01*
G01X500241Y679532D01*
G02X500093Y679487I-128J154D01*
G01X499756Y679540D01*
G02X499619Y679642I39J196D01*
G01X499618Y679643D01*
Y679644D01*
G03X499507Y679824I-1330J-696D01*
G01Y679825D01*
G03X499416Y679940I-1222J-873D01*
G01X499412Y679944D01*
G02X499368Y680051I155J126D01*
G02X499367Y680070I199J20D01*
G01Y680336D01*
G02X499368Y680355I200J-1D01*
G02X499412Y680462I199J-19D01*
G01X499416Y680466D01*
G03X499786Y681453I-1131J987D01*
G03X496782I-1502J0D01*
G03X497119Y680506I1501J1D01*
G02X497121Y680502I-174J-89D01*
G01X497130Y680491D01*
X497152Y680428D01*
Y680265D01*
X497201D01*
Y680070D01*
G02X497200Y680051I-200J1D01*
G02X497156Y679944I-199J19D01*
G01X497152Y679940D01*
G03X496782Y678953I1131J-987D01*
G03X497002Y678171I1502J1D01*
G01X497003Y678169D01*
G02X497032Y678069I-171J-104D01*
G01X497033Y678017D01*
X496834Y677664D01*
G02X496660Y677562I-174J98D01*
G01X495343D01*
G03X494421Y677180I1J-1306D01*
G01X487841Y670600D01*
G03X487458Y669676I923J-924D01*
G01Y668014D01*
G02X487457Y667998I-200J4D01*
G02X487441Y667933I-199J15D01*
G01X487435Y667922D01*
G03X487263Y667224I1330J-698D01*
G03X488765Y665722I1502J0D01*
G03X489805Y666140I0J1503D01*
G01X489833Y666167D01*
X489866Y666181D01*
G02X489937Y666196I76J-185D01*
G01X490012Y666198D01*
X490216Y666204D01*
G02X490344Y666155I-3J-200D01*
G03X491324Y665791I980J1137D01*
G03Y668795I0J1502D01*
G01X491323D01*
G03X490670Y668645I1J-1502D01*
G02X490629Y668631I-85J181D01*
G01X490562Y668615D01*
G02X490462Y668642I0J200D01*
G01X490157Y668829D01*
G02X490072Y668993I115J164D01*
G01Y669052D01*
G02X490129Y669192I200J0D01*
G01X492011Y671074D01*
X495829Y674893D01*
G02X495939Y674948I140J-143D01*
G02X495969Y674950I28J-198D01*
G01X498817D01*
G03X499739Y675332I-1J1306D01*
G01X510076Y685669D01*
G02X510242Y685726I141J-141D01*
G01X510555Y685688D01*
G02X510640Y685657I-24J-199D01*
G01X510659Y685645D01*
X510690Y685612D01*
X510702Y685592D01*
G03X511990Y684863I1288J773D01*
G03X513492Y686365I0J1502D01*
G03X513464Y686652I-1502J-2D01*
G01X513462Y686660D01*
G02X513506Y686817I198J29D01*
G01X513703Y687055D01*
G02X513857Y687128I154J-127D01*
G01X519682D01*
G02X519838Y687053I0J-200D01*
G01X519941Y686925D01*
X520034Y686809D01*
G02X520073Y686728I-156J-125D01*
G01X520083Y686686D01*
X520073Y686642D01*
G03X520038Y686323I1467J-322D01*
G03Y686316I1502J-3D01*
G01Y686302D01*
G03X521093Y684885I1502J17D01*
G01X521095D01*
G02X521175Y684836I-62J-190D01*
G01X534437Y671575D01*
G02X534479Y671357I-142J-140D01*
G01X534434Y671249D01*
X534410Y671242D01*
G02X534354Y671234I-56J192D01*
G01X525256D01*
G03X524380Y670882I1J-1267D01*
G01X524341Y670843D01*
X524338Y670839D01*
X524186Y670687D01*
X523413Y669913D01*
X521583Y668083D01*
G02X521502Y668034I-141J142D01*
G01X521492Y668031D01*
G03X520414Y666953I376J-1454D01*
G01X520411Y666943D01*
G02X520362Y666862I-191J60D01*
G01X520285Y666785D01*
G02X520006Y666782I-141J142D01*
G01X519994Y666793D01*
X519987Y666802D01*
G03X518812Y667369I-1175J-934D01*
G03X517310Y665867I0J-1502D01*
G03X517746Y664809I1502J0D01*
G01X517747Y664808D01*
G02X517804Y664677I-143J-140D01*
G01X517803Y664386D01*
G02X517745Y664245I-200J0D01*
G01X507471Y653971D01*
G02X507421Y653935I-140J142D01*
G02X507330Y653913I-91J178D01*
G01X496509D01*
G02X496356Y653984I0J200D01*
G01X496281Y654072D01*
X496158Y654218D01*
G02X496118Y654293I153J130D01*
G01X496107Y654334D01*
X496114Y654378D01*
G03X496134Y654622I-1482J244D01*
G03X495404Y655910I-1501J0D01*
G01X495403Y655911D01*
G02X495308Y656059I104J171D01*
G01X495288Y656438D01*
X495287Y656453D01*
X495318Y656520D01*
X495349Y656558D01*
X495369Y656573D01*
G03X495967Y657772I-903J1199D01*
G03X492963I-1502J0D01*
G03X493693Y656484I1501J0D01*
G01X493694Y656483D01*
G02X493789Y656335I-104J-171D01*
G01X493809Y655956D01*
X493810Y655941D01*
X493779Y655874D01*
X493748Y655836D01*
X493728Y655821D01*
G03X493130Y654622I903J-1199D01*
G03X493150Y654378I1502J0D01*
G01X493157Y654334D01*
X493146Y654293D01*
G02X493106Y654218I-193J55D01*
G01X492848Y653913D01*
X492802D01*
X484185Y645296D01*
G03X484126Y645154I141J-142D01*
G01Y630782D01*
G02X484125Y630765I-200J3D01*
G02X484030Y630617I-199J23D01*
G03Y628005I742J-1306D01*
G02X484125Y627857I-104J-171D01*
G02X484126Y627840I-199J-20D01*
G01Y626782D01*
G02X484125Y626765I-200J3D01*
G02X484030Y626617I-199J23D01*
G03Y624005I742J-1306D01*
G02X484125Y623857I-104J-171D01*
G02X484126Y623840I-199J-20D01*
G01Y622782D01*
G02X484125Y622765I-200J3D01*
G02X484030Y622617I-199J23D01*
G03Y620005I742J-1306D01*
G02X484125Y619857I-104J-171D01*
G02X484126Y619840I-199J-20D01*
G01Y554440D01*
G02X484071Y554304I-200J2D01*
G01X484044Y554280D01*
X483890Y554182D01*
X483734Y554084D01*
G02X483646Y554061I-93J177D01*
G01X483574Y554096D01*
G03X482905Y554251I-670J-1370D01*
G03Y551201I0J-1525D01*
G03X483574Y551356I-1J1525D01*
G01X483645Y551391D01*
G02X483719Y551374I-7J-200D01*
G01X483721D01*
G02X483729Y551370I-85J-181D01*
G01X483799Y551326D01*
X483801D01*
X484032Y551180D01*
G02X484057Y551162I-104J-171D01*
G02X484117Y551069I-131J-151D01*
G02X484126Y551011I-191J-59D01*
G01Y550440D01*
G02X484071Y550304I-200J2D01*
G01X484044Y550280D01*
X483890Y550182D01*
X483734Y550084D01*
G02X483646Y550061I-93J177D01*
G01X483574Y550096D01*
G03X482905Y550251I-670J-1370D01*
G03Y547201I0J-1525D01*
G03X483574Y547356I-1J1525D01*
G01X483645Y547391D01*
G02X483719Y547374I-7J-200D01*
G01X483721D01*
G02X483729Y547370I-85J-181D01*
G01X483799Y547326D01*
X483801D01*
X484032Y547180D01*
G02X484057Y547162I-104J-171D01*
G02X484117Y547069I-131J-151D01*
G02X484126Y547011I-191J-59D01*
G01Y546440D01*
G02X484071Y546304I-200J2D01*
G01X484044Y546280D01*
X483890Y546182D01*
X483734Y546084D01*
G02X483646Y546061I-93J177D01*
G01X483574Y546096D01*
G03X482905Y546251I-670J-1370D01*
G03Y543201I0J-1525D01*
G03X483574Y543356I-1J1525D01*
G01X483645Y543391D01*
G02X483719Y543374I-7J-200D01*
G01X483721D01*
G02X483729Y543370I-85J-181D01*
G01X483799Y543326D01*
X483801D01*
X484032Y543180D01*
G02X484057Y543162I-104J-171D01*
G02X484117Y543069I-131J-151D01*
G02X484126Y543011I-191J-59D01*
G01Y542440D01*
G02X484071Y542304I-200J2D01*
G01X484044Y542280D01*
X483890Y542182D01*
X483734Y542084D01*
G02X483646Y542061I-93J177D01*
G01X483574Y542096D01*
G03X482905Y542251I-670J-1370D01*
G03Y539201I0J-1525D01*
G03X483574Y539356I-1J1525D01*
G01X483645Y539391D01*
G02X483719Y539374I-7J-200D01*
G01X483721D01*
G02X483729Y539370I-85J-181D01*
G01X483799Y539326D01*
X483801D01*
X484032Y539180D01*
G02X484057Y539162I-104J-171D01*
G02X484117Y539069I-131J-151D01*
G02X484126Y539011I-191J-59D01*
G01Y538840D01*
G02X484041Y538677I-200J1D01*
G01X483906Y538600D01*
X483730Y538500D01*
X483703Y538486D01*
G02X483617Y538468I-83J182D01*
G01X483567Y538469D01*
X483525Y538494D01*
X483518Y538498D01*
X483517Y538499D01*
G03X482738Y538717I-779J-1284D01*
G01X482643D01*
G03X482614Y538715I-1J-200D01*
G01X482526Y538702D01*
G03X481838Y538418I211J-1487D01*
G03X481591Y538186I898J-1204D01*
G03X481587Y538182I1056J-1060D01*
G01X481548Y538135D01*
G03X481537Y538121I152J-130D01*
G01X481510Y538083D01*
Y538081D01*
G03X481245Y537391I1226J-867D01*
G01X481239Y537337D01*
G03X481234Y537215I1498J-122D01*
G03X481837Y536011I1504J0D01*
G01X481857Y535996D01*
G02X481917Y535871I-139J-144D01*
G01X481924Y535625D01*
Y535623D01*
X481927Y535536D01*
G02X481911Y535459I-200J1D01*
G01X481893Y535419D01*
X481886Y535413D01*
X481881Y535409D01*
X481858Y535389D01*
G03X481334Y534249I978J-1140D01*
G03X481740Y533222I1502J0D01*
G01X481765Y533195D01*
X481779Y533162D01*
G02X481794Y533091I-185J-76D01*
G01X481796Y533028D01*
Y533026D01*
X481801Y532825D01*
G02X481791Y532756I-200J-6D01*
G02X481762Y532701I-189J65D01*
G01X481751Y532688D01*
G03X481403Y531727I1154J-961D01*
G01Y531710D01*
G03X482897Y530224I1502J16D01*
G01X482914D01*
G03X482962Y530225I-7J1502D01*
G03X483542Y530365I-55J1501D01*
G03X483545Y530367I-108J166D01*
G01X483547D01*
G03X483554Y530371I-741J1304D01*
G01X483565Y530376D01*
X483569Y530378D01*
X483637Y530391D01*
G02X483719Y530374I1J-200D01*
G01X483721D01*
G02X483734Y530367I-88J-179D01*
G01X483800Y530326D01*
X484032Y530180D01*
G02X484057Y530162I-104J-171D01*
G02X484117Y530069I-131J-151D01*
G02X484126Y530011I-191J-59D01*
G01Y529440D01*
G02X484071Y529304I-200J2D01*
G01X484044Y529280D01*
X483890Y529182D01*
X483734Y529084D01*
G02X483646Y529061I-93J177D01*
G01X483574Y529096D01*
G03X482905Y529251I-670J-1370D01*
G03Y526201I0J-1525D01*
G03X483574Y526356I-1J1525D01*
G01X483645Y526391D01*
G02X483719Y526374I-7J-200D01*
G01X483721D01*
G02X483729Y526370I-85J-181D01*
G01X483799Y526326D01*
X483801D01*
X484032Y526180D01*
G02X484057Y526162I-104J-171D01*
G02X484117Y526069I-131J-151D01*
G02X484126Y526011I-191J-59D01*
G01Y449654D01*
G03X484185Y449512I200J0D01*
G01X492436Y441261D01*
G02X492437Y440979I-141J-142D01*
G01X492435Y440977D01*
G03X491983Y439903I1050J-1074D01*
G03X493485Y438401I1502J0D01*
G03X494559Y438853I0J1502D01*
G01X494561Y438855D01*
G02X494843Y438854I140J-142D01*
G01X495909Y437788D01*
G03X496051Y437729I142J141D01*
G01X540398D01*
G03X540540Y437788I0J200D01*
G01X552919Y450167D01*
G03X552978Y450309I-141J142D01*
G01Y523734D01*
G02X552982Y523771I200J-3D01*
G01Y523773D01*
G02X553035Y523874I196J-39D01*
G01X571098Y541937D01*
G02X571199Y541990I140J-143D01*
G01X571201D01*
G02X571238Y541994I40J-196D01*
G01X630008D01*
G02X630189Y541878I0J-200D01*
G01X630207Y541803D01*
X630208Y541784D01*
G03X632009Y540059I1801J78D01*
G01X632010D01*
X632025Y540060D01*
G03X632472Y540120I-14J1802D01*
G01X632514Y540131D01*
X632554Y540125D01*
G02X632625Y540099I-32J-198D01*
G01X632682Y540062D01*
X632887Y539928D01*
G02X632939Y539874I-115J-163D01*
G01X632941Y539871D01*
X632963Y539836D01*
X632970Y539794D01*
Y539793D01*
G03X634455Y538518I1485J227D01*
G03X635957Y540020I0J1502D01*
G03X634457Y541522I-1502J0D01*
G01X634455D01*
G03X634453I-1J-1502D01*
G03X634130Y541487I-1J-1502D01*
G02X633979Y541532I-23J199D01*
G01X633978Y541533D01*
X633870Y541622D01*
G02X633809Y541772I139J144D01*
G01Y541777D01*
X633810Y541783D01*
X633811Y541802D01*
X633829Y541879D01*
G02X634010Y541994I181J-85D01*
G01X663970D01*
G02X664158Y541860I-1J-200D01*
G01X664213Y541697D01*
X664283Y541490D01*
G02X664282Y541376I-192J-55D01*
G02X664222Y541283I-192J58D01*
G03X664215Y541278I914J-1287D01*
G03X664209Y541274I108J-168D01*
G03X663608Y540269I958J-1255D01*
G01X663605Y540252D01*
X663601Y540227D01*
X663580Y540193D01*
G02X663534Y540142I-169J106D01*
G01X663407Y540054D01*
X663405D01*
X663278Y539965D01*
G02X663143Y539938I-104J171D01*
G01X663105Y539946D01*
G03X662338Y539928I-342J-1770D01*
G01X662293Y539917D01*
X662260Y539923D01*
G02X662183Y539954I34J197D01*
G01X662060Y540036D01*
X661935Y540119D01*
G02X661879Y540176I112J166D01*
G01X661857Y540209D01*
X661850Y540253D01*
G03X660366Y541522I-1484J-233D01*
G03Y538518I0J-1502D01*
G03X660624Y538540I2J1502D01*
G01X660626Y538541D01*
X660628D01*
X660636Y538542D01*
X660670Y538545D01*
G02X660791Y538505I1J-200D01*
G01X660890Y538420D01*
X660902Y538409D01*
G02X660966Y538263I-136J-147D01*
G01Y538255D01*
G03X660964Y538175I1801J-85D01*
G01Y534775D01*
G03X660966Y534699I1803J9D01*
G02X660909Y534549I-200J-10D01*
G02X660897Y534538I-141J142D01*
G01X660862Y534508D01*
G02X660860Y534506I-142J140D01*
G01X660792Y534449D01*
G02X660675Y534408I-121J159D01*
G01X660639Y534411D01*
X660631Y534412D01*
X660626Y534413D01*
G03X660369Y534435I-256J-1480D01*
G01X660366D01*
G03Y531431I0J-1502D01*
G03X661850Y532698I0J1503D01*
G01X661853Y532720D01*
G02X661928Y532828I193J-54D01*
G01X662040Y532902D01*
X662182Y532997D01*
G02X662259Y533027I110J-167D01*
G01X662265Y533028D01*
X662299Y533034D01*
X662339Y533024D01*
G03X662767Y532972I430J1751D01*
G03X662979Y532985I-4J1803D01*
G01X662981D01*
G03X662995Y532987I-248J1785D01*
G01X662998D01*
X663139Y533005D01*
X663141D01*
X663201Y533012D01*
G02X663280Y532983I-28J-198D01*
G01X663468Y532854D01*
X663497Y532834D01*
G02X663522Y532814I-112J-166D01*
G01X663534Y532801D01*
G02X663540Y532794I-149J-134D01*
G01X663579Y532740D01*
G02X663611Y532661I-165J-113D01*
G03X665167Y531353I1556J272D01*
G03X665302Y531359I-3J1579D01*
G01X665331Y531361D01*
X665381Y531368D01*
G03X666197Y531736I-214J1564D01*
G01X666223Y531758D01*
X666327Y531799D01*
G02X666389Y531809I63J-190D01*
G01X666445D01*
G02X666507Y531799I-1J-200D01*
G01X666611Y531758D01*
X666637Y531736D01*
G03X667666Y531354I1029J1196D01*
G01X667667D01*
G03X667933Y531376I3J1578D01*
G01X667935D01*
G02X668090Y531338I34J-197D01*
G01X668202Y531242D01*
G02X668264Y531098I-138J-145D01*
G01Y527679D01*
G02X668202Y527535I-200J1D01*
G01X668091Y527440D01*
G02X667935Y527401I-122J158D01*
G01X667934D01*
X667919Y527404D01*
G03X667671Y527424I-251J-1559D01*
G01X667658D01*
G03X666636Y527041I9J-1579D01*
G01X666632Y527037D01*
X666609Y527018D01*
X666509Y526979D01*
G02X666442Y526968I-65J189D01*
G01X666389D01*
G02X666327Y526978I1J200D01*
G01X666223Y527019D01*
X666197Y527041D01*
G03X666091Y527125I-1032J-1194D01*
G03X666051Y527153I-925J-1279D01*
G03X665167Y527424I-884J-1308D01*
G03X663611Y526116I0J-1580D01*
G02X663579Y526037I-197J34D01*
G01X663540Y525983D01*
G02X663534Y525976I-155J127D01*
G01X663522Y525963D01*
G02X663497Y525943I-137J146D01*
G01X663468Y525923D01*
X663277Y525792D01*
G02X663139Y525766I-104J171D01*
G01X663115Y525771D01*
X663112Y525772D01*
X663110D01*
X663104Y525773D01*
G03X663012Y525788I-336J-1771D01*
G01X663010D01*
G03X662975Y525793I-272J-1782D01*
G01X662973D01*
G03X662767Y525804I-199J-1791D01*
G03X662340Y525753I-1J-1802D01*
G01X662299Y525743D01*
X662260Y525750D01*
G02X662183Y525780I33J197D01*
G01X662060Y525862D01*
X661931Y525949D01*
G02X661879Y526003I115J163D01*
G01X661857Y526036D01*
X661852Y526068D01*
X661850Y526081D01*
G03X660366Y527349I-1484J-234D01*
G03Y524345I0J-1502D01*
G03X660624Y524367I2J1502D01*
G01X660626Y524368D01*
X660628D01*
X660636Y524369D01*
X660670Y524372D01*
G02X660791Y524332I1J-200D01*
G01X660890Y524247D01*
X660902Y524236D01*
G02X660966Y524090I-136J-147D01*
G01Y524082D01*
G03X660964Y524002I1801J-85D01*
G01Y520602D01*
G03X660966Y520526I1803J9D01*
G02X660909Y520376I-200J-10D01*
G02X660897Y520365I-141J142D01*
G01X660862Y520335D01*
G02X660860Y520333I-142J140D01*
G01X660792Y520276D01*
G02X660675Y520235I-121J159D01*
G01X660639Y520238D01*
X660631Y520239D01*
X660626Y520240D01*
G03X660369Y520262I-256J-1480D01*
G01X660366D01*
G03Y517258I0J-1502D01*
G03X661850Y518525I0J1503D01*
G01X661853Y518547D01*
G02X661928Y518655I193J-54D01*
G01X662040Y518729D01*
X662186Y518826D01*
G02X662259Y518854I107J-169D01*
G01X662265Y518855D01*
X662299Y518861D01*
X662311Y518858D01*
X662334Y518852D01*
G03X662353Y518847I468J1741D01*
G01X662355D01*
G03X662387Y518839I453J1744D01*
G01X662394Y518838D01*
G03X662439Y518829I376J1763D01*
G03X662561Y518811I324J1773D01*
G03X662766Y518800I199J1791D01*
G01X662768D01*
G03X662973Y518811I6J1802D01*
G01X662975D01*
G03X663010Y518816I-237J1787D01*
G01X663012D01*
G03X663114Y518833I-245J1786D01*
G01X663124Y518835D01*
G03X663134Y518837I-348J1768D01*
G01X663172Y518841D01*
G02X663277Y518811I0J-200D01*
G01X663468Y518681D01*
X663497Y518661D01*
G02X663522Y518641I-112J-166D01*
G01X663534Y518628D01*
G02X663540Y518621I-149J-134D01*
G01X663579Y518567D01*
G02X663611Y518488I-165J-113D01*
G03X665172Y517180I1556J271D01*
G03X665672Y517263I-5J1579D01*
G01X665673D01*
X665690Y517269D01*
G03X666198Y517563I-523J1490D01*
G01X666224Y517586D01*
X666321Y517623D01*
G02X666392Y517636I71J-187D01*
G01X666442D01*
G02X666513Y517623I0J-200D01*
G01X666610Y517586D01*
X666637Y517563D01*
G03X667266Y517232I1031J1196D01*
G01X667271Y517231D01*
X667289Y517226D01*
G03X667419Y517200I374J1534D01*
G03X667563Y517184I246J1559D01*
G01X667565D01*
G03X667658Y517180I114J1574D01*
G01X667667D01*
G03X667670I2J1579D01*
G03X667934Y517202I1J1579D01*
G01X667955Y517206D01*
X667958D01*
G02X667990Y517205I10J-200D01*
G01X667996Y517204D01*
G02X668084Y517168I-29J-198D01*
G01X668144Y517118D01*
G02X668146Y517116I-140J-142D01*
G01X668205Y517066D01*
G02X668264Y516925I-141J-142D01*
G01Y513506D01*
G02X668200Y513360I-200J1D01*
G01X668115Y513287D01*
X668091Y513268D01*
G02X667971Y513226I-122J158D01*
G01X667948Y513227D01*
X667944D01*
X667935Y513228D01*
G03X667917Y513231I-268J-1555D01*
G01X667915D01*
G03X667898Y513234I-283J-1552D01*
G01X667896D01*
X667883Y513236D01*
G03X667831Y513242I-207J-1565D01*
G03X667667Y513250I-159J-1570D01*
G03Y510094I0J-1578D01*
G03X667867Y510106I6J1578D01*
G03X667963Y510121I-196J1567D01*
G01X667967Y510122D01*
G03X669212Y511344I-300J1550D01*
G01X669213Y511349D01*
G03X669216Y511361I-1529J389D01*
G01X669220Y511383D01*
X669224Y511407D01*
G02X669255Y511480I196J-40D01*
G01X669294Y511534D01*
G02X669300Y511541I155J-127D01*
G01X669312Y511554D01*
G02X669337Y511574I137J-146D01*
G01X669366Y511594D01*
X669560Y511727D01*
G02X669679Y511753I100J-173D01*
G03X669879Y511721I385J1762D01*
G03X670363Y511735I190J1793D01*
G01X670367Y511736D01*
X670501Y511752D01*
G02X670580Y511723I-28J-198D01*
G01X670768Y511594D01*
X670826Y511554D01*
X670827Y511553D01*
X670831Y511551D01*
G02X670881Y511497I-119J-161D01*
G01X670884Y511492D01*
G02X670904Y511447I-171J-103D01*
G01Y511445D01*
X670908Y511422D01*
G03X671167Y510776I1559J250D01*
G01X671174Y510767D01*
G03X671188Y510747I1300J895D01*
G03X671190Y510743I178J86D01*
G03X671212Y510714I1269J940D01*
G03X671214Y510712I141J139D01*
G03X671219Y510705I1287J914D01*
G03X671221Y510703I141J139D01*
G03X672466Y510094I1246J969D01*
G01X672467D01*
G03Y513250I0J1578D01*
G03X672303Y513242I-5J-1578D01*
G03X672276Y513239I161J-1570D01*
G01X672274D01*
G03X672238Y513234I199J-1566D01*
G01X672236D01*
G03X672219Y513231I266J-1555D01*
G01X672217D01*
G03X672199Y513228I250J-1558D01*
G01X672190Y513227D01*
G02X672043Y513268I-24J198D01*
G01X672019Y513287D01*
X671934Y513360D01*
G02X671870Y513506I136J147D01*
G01Y513507D01*
G03Y513515I-1803J4D01*
G01Y516925D01*
G02X671932Y517069I200J-1D01*
G01X672043Y517164D01*
G02X672199Y517203I122J-158D01*
G01X672200D01*
X672215Y517200D01*
G03X672464Y517180I251J1559D01*
G01X672467D01*
G03Y520338I0J1579D01*
G03X670908Y519009I0J-1579D01*
G01Y519005D01*
X670904Y518984D01*
X670901Y518967D01*
X670880Y518933D01*
G02X670837Y518884I-170J106D01*
G01X670707Y518794D01*
X670705D01*
X670578Y518705D01*
G02X670453Y518677I-104J171D01*
G03X670181Y518715I-385J-1762D01*
G03X669771Y518695I-118J-1799D01*
G01X669767Y518694D01*
X669632Y518678D01*
G02X669552Y518708I29J198D01*
G01X669429Y518794D01*
X669427D01*
X669297Y518884D01*
G02X669254Y518933I127J155D01*
G01X669233Y518967D01*
X669230Y518984D01*
X669226Y519005D01*
Y519009D01*
G03X667662Y520338I-1559J-250D01*
G03X667162Y520255I5J-1579D01*
G01X667161D01*
X667144Y520249D01*
G03X666636Y519955I523J-1490D01*
G01X666610Y519932D01*
X666513Y519895D01*
G02X666442Y519882I-71J187D01*
G01X666392D01*
G02X666321Y519895I0J200D01*
G01X666224Y519932D01*
X666197Y519955D01*
G03X665568Y520286I-1031J-1196D01*
G01X665563Y520287D01*
X665545Y520292D01*
G03X665415Y520318I-374J-1534D01*
G03X665271Y520334I-246J-1559D01*
G01X665269D01*
G03X665176Y520338I-114J-1574D01*
G01X665167D01*
G03X665164I-2J-1579D01*
G03X664900Y520316I-1J-1579D01*
G01X664879Y520312D01*
X664876D01*
G02X664844Y520313I-10J200D01*
G01X664838Y520314D01*
G02X664750Y520350I29J198D01*
G01X664690Y520400D01*
G02X664688Y520402I140J142D01*
G01X664629Y520452D01*
G02X664570Y520593I141J142D01*
G01Y524011D01*
G02X664632Y524155I200J-1D01*
G01X664743Y524250D01*
G02X664899Y524289I122J-158D01*
G01X664900D01*
X664915Y524286D01*
G03X665163Y524266I251J1559D01*
G01X665176D01*
G03X666198Y524649I-9J1579D01*
G01X666202Y524653D01*
X666225Y524672D01*
X666325Y524711D01*
G02X666392Y524722I65J-189D01*
G01X666445D01*
G02X666507Y524712I-1J-200D01*
G01X666611Y524671D01*
X666637Y524649D01*
G03X666743Y524565I1032J1194D01*
G03X666783Y524537I925J1279D01*
G03X667667Y524266I884J1308D01*
G03X669223Y525574I0J1580D01*
G02X669255Y525653I197J-34D01*
G01X669294Y525707D01*
G02X669300Y525714I155J-127D01*
G01X669312Y525727D01*
G02X669337Y525747I137J-146D01*
G01X669366Y525767D01*
X669557Y525898D01*
G02X669695Y525924I104J-171D01*
G01X669719Y525919D01*
X669722Y525918D01*
X669724D01*
X669730Y525917D01*
G03X669822Y525902I336J1771D01*
G01X669824D01*
G03X669859Y525897I272J1782D01*
G01X669861D01*
G03X670066Y525886I199J1791D01*
G01X670068D01*
G03X670273Y525897I6J1802D01*
G01X670275D01*
G03X670310Y525902I-237J1787D01*
G01X670312D01*
G03X670414Y525919I-245J1786D01*
G01X670424Y525921D01*
G03X670434Y525923I-348J1768D01*
G01X670472Y525927D01*
G02X670577Y525897I0J-200D01*
G01X670768Y525767D01*
X670797Y525747D01*
G02X670822Y525727I-112J-166D01*
G01X670834Y525714D01*
G02X670840Y525707I-149J-134D01*
G01X670879Y525653D01*
G02X670911Y525574I-165J-113D01*
G03X672467Y524266I1556J272D01*
G03Y527424I0J1579D01*
G01X672464D01*
G03X672215Y527404I2J-1579D01*
G01X672200Y527401D01*
X672199D01*
G02X672043Y527440I-34J197D01*
G01X671932Y527535D01*
G02X671870Y527679I138J145D01*
G01Y531098D01*
G02X671932Y531242I200J-1D01*
G01X672044Y531338D01*
G02X672199Y531376I121J-159D01*
G01X672201D01*
G03X672467Y531354I263J1556D01*
G03Y534510I0J1578D01*
G03X672267Y534498I-6J-1578D01*
G03X670908Y533183I200J-1566D01*
G01X670902Y533141D01*
X670880Y533106D01*
G02X670830Y533052I-169J107D01*
G01X670707Y532967D01*
X670705D01*
X670659Y532935D01*
X670578Y532878D01*
G02X670442Y532851I-105J171D01*
G01X670411Y532858D01*
G03X670320Y532873I-339J-1771D01*
G01X670318D01*
G03X670312Y532874I-299J-1777D01*
G01X670311D01*
X670298Y532876D01*
G03X670068Y532890I-224J-1788D01*
G01X670066D01*
G03X669861Y532879I-6J-1802D01*
G01X669859D01*
G03X669824Y532874I237J-1787D01*
G01X669822D01*
G03X669720Y532857I245J-1786D01*
G01X669710Y532855D01*
X669709D01*
X669700Y532853D01*
G02X669556Y532878I-40J196D01*
G01X669429Y532967D01*
X669427D01*
X669304Y533052D01*
G02X669254Y533106I119J161D01*
G01X669232Y533141D01*
X669226Y533183D01*
G03X667667Y534511I-1559J-251D01*
G03X667532Y534505I3J-1579D01*
G01X667503Y534503D01*
X667453Y534496D01*
G03X666637Y534128I214J-1564D01*
G01X666611Y534106D01*
X666507Y534065D01*
G02X666445Y534055I-63J190D01*
G01X666389D01*
G02X666327Y534065I1J200D01*
G01X666223Y534106D01*
X666197Y534128D01*
G03X665168Y534510I-1029J-1196D01*
G01X665167D01*
G03X665003Y534502I-5J-1578D01*
G03X664976Y534499I161J-1570D01*
G01X664974D01*
G03X664938Y534494I199J-1566D01*
G01X664936D01*
G03X664919Y534491I266J-1555D01*
G01X664917D01*
G03X664899Y534488I250J-1558D01*
G01X664890Y534487D01*
G02X664743Y534528I-24J198D01*
G01X664719Y534547D01*
X664634Y534620D01*
G02X664570Y534766I136J147D01*
G01Y538185D01*
G02X664632Y538329I200J-1D01*
G01X664743Y538424D01*
G02X664899Y538463I122J-158D01*
G01X664900D01*
X664915Y538460D01*
G03X665164Y538440I251J1559D01*
G01X665167D01*
G03X666746Y540019I0J1579D01*
G01Y540020D01*
G03X666740Y540157I-1579J-1D01*
G01Y540158D01*
G03X666122Y541276I-1572J-139D01*
G01X666097Y541295D01*
X666062Y541347D01*
X666052Y541376D01*
G02X666051Y541490I191J59D01*
G01X666121Y541697D01*
X666176Y541860D01*
G02X666364Y541994I189J-66D01*
G01X680531D01*
G02X680559Y541992I0J-200D01*
G02X680703Y541895I-29J-198D01*
G01X680798Y541711D01*
X680877Y541559D01*
G02X680893Y541465I-184J-80D01*
G01X680889Y541411D01*
X680567Y540947D01*
G03X680560Y540730I165J-114D01*
G01X680575Y540704D01*
X680590Y540645D01*
X680587Y540598D01*
G03X680584Y540500I1499J-95D01*
G01Y540473D01*
G03X683588I1502J27D01*
G01Y540500D01*
G03X683316Y541363I-1502J1D01*
G01X683315Y541364D01*
X683310Y541372D01*
G02X683279Y541465I168J108D01*
G01X683277Y541493D01*
X683288Y541546D01*
X683305Y541580D01*
X683471Y541898D01*
G02X683613Y541992I171J-104D01*
G02X683641Y541994I28J-198D01*
G01X687809D01*
G03X687951Y542053I0J200D01*
G01X711027Y565129D01*
G02X711131Y565184I141J-141D01*
G01X711207D01*
X711215Y565183D01*
X711216D01*
X711222Y565182D01*
G03X711246Y565179I208J1564D01*
G01X711252D01*
X711257Y565178D01*
X711270Y565177D01*
G03X711391Y565173I113J1575D01*
G01X711393D01*
G03X712951Y566502I-1J1579D01*
G01Y566504D01*
X712958Y566543D01*
Y566545D01*
X712979Y566579D01*
G02X713027Y566631I168J-107D01*
G01X713152Y566718D01*
X713153Y566719D01*
X713179Y566737D01*
X713280Y566806D01*
G02X713412Y566835I106J-170D01*
G01X713426Y566832D01*
G03X713434Y566830I441J1748D01*
G01X713437Y566829D01*
X713452Y566826D01*
G03X713811Y566793I344J1770D01*
G01X713814D01*
G03X714048Y566811I-21J1803D01*
G01X714052Y566812D01*
X714062Y566813D01*
X714063D01*
X714119Y566820D01*
X714121D01*
X714220Y566833D01*
X714227Y566834D01*
G02X714307Y566804I-29J-198D01*
G01X714322Y566794D01*
X714509Y566664D01*
X714559Y566629D01*
G02X714605Y566579I-122J-158D01*
G01X714626Y566545D01*
X714633Y566503D01*
Y566502D01*
G03X716191Y565173I1559J250D01*
G01X716193D01*
G03X716236Y565174I-15J1578D01*
G01X716243D01*
G03X717222Y565556I-52J1578D01*
G01X717248Y565578D01*
X717352Y565619D01*
G02X717414Y565629I63J-190D01*
G01X717470D01*
G02X717532Y565619I-1J-200D01*
G01X717636Y565578D01*
X717662Y565556D01*
G03X718691Y565174I1029J1196D01*
G01X718692D01*
G03X718958Y565196I3J1578D01*
G01X718993Y565199D01*
G02X719113Y565158I-1J-200D01*
G01X719223Y565066D01*
G02X719288Y564945I-133J-149D01*
G02X719290Y564917I-198J-28D01*
G01Y561498D01*
G02X719289Y561483I-200J6D01*
G01Y561481D01*
G02X719263Y561398I-199J17D01*
G02X719242Y561369I-172J103D01*
G02X719225Y561352I-150J133D01*
G01X719171Y561307D01*
G03X719169Y561305I140J-142D01*
G01X719150Y561289D01*
X719118Y561262D01*
X719104Y561251D01*
G02X718960Y561221I-110J167D01*
G01X718959D01*
X718944Y561224D01*
G03X718695Y561244I-251J-1559D01*
G01X718692D01*
G03Y558086I0J-1579D01*
G01X718693D01*
G03X720251Y559415I-1J1579D01*
G01Y559416D01*
X720258Y559458D01*
X720279Y559492D01*
G02X720320Y559538I168J-108D01*
G01X720451Y559631D01*
X720453D01*
X720583Y559722D01*
G02X720711Y559747I100J-173D01*
G01X720728Y559744D01*
X720749Y559740D01*
G03X720770Y559736I348J1769D01*
G03X720778Y559734I52J193D01*
G01X720786Y559733D01*
X720788D01*
G03X720847Y559724I301J1777D01*
G01X720851D01*
G03X720884Y559719I286J1779D01*
G01X720886D01*
G03X720900Y559717I262J1783D01*
G01X720904D01*
G03X720933Y559714I200J1791D01*
G01X720972Y559711D01*
X720978D01*
G03X721075Y559708I104J1799D01*
G03X721092I9J1802D01*
G01X721093D01*
G03X721096I1J1802D01*
G03X721110I7J1802D01*
G01X721137D01*
G03X721175Y559709I-28J1802D01*
G01X721177D01*
G03X721262Y559715I-84J1801D01*
G01X721271Y559716D01*
X721273D01*
G03X721292Y559718I-179J1793D01*
G01X721298Y559719D01*
G03X721346Y559725I-200J1792D01*
G03X721536Y559762I-249J1785D01*
G01X721545Y559764D01*
X721549Y559765D01*
X721560Y559768D01*
X721597Y559761D01*
G02X721673Y559731I-34J-197D01*
G01X721903Y559578D01*
X721927Y559562D01*
G02X721978Y559509I-116J-163D01*
G01X722000Y559476D01*
X722007Y559431D01*
G03X723491Y558163I1484J234D01*
G03X724993Y559665I0J1502D01*
G03X723493Y561167I-1502J0D01*
G01X723489D01*
G03X723487I-1J-1502D01*
G03X723224Y561144I-1J-1502D01*
G01X723211Y561142D01*
X723188Y561140D01*
G02X723065Y561183I1J200D01*
G01X723039Y561206D01*
X722962Y561272D01*
G02X722892Y561412I130J152D01*
G01X722893Y561432D01*
G03X722894Y561499I-1801J60D01*
G01Y561501D01*
G03Y561510I-1802J5D01*
G01Y564958D01*
G03X722893Y564985I-1801J-53D01*
G01Y565016D01*
G02X722949Y565134I199J-22D01*
G01X723023Y565198D01*
X723065Y565234D01*
G03X723491Y565175I427J1518D01*
G03Y568329I0J1577D01*
G03X721930Y566980I0J-1578D01*
G01X721924Y566939D01*
X721860Y566835D01*
G02X721800Y566773I-170J105D01*
G01X721771Y566753D01*
X721663Y566682D01*
G02X721538Y566657I-100J173D01*
G01X721518Y566662D01*
G03X721300Y566701I-426J-1752D01*
G01X721294D01*
G03X721275Y566703I-198J-1790D01*
G01X721273D01*
G03X721092Y566712I-180J-1793D01*
G03X720726Y566675I-3J-1802D01*
G01X720687Y566667D01*
X720642Y566676D01*
G02X720617Y566684I48J194D01*
G01X720615D01*
G02X720577Y566703I70J188D01*
G01X720358Y566854D01*
G02X720321Y566891I122J159D01*
G03X720320Y566893I-176J-87D01*
G02X720318Y566896I165J112D01*
G01X720251Y567001D01*
X720244Y567039D01*
G03X718692Y568330I-1552J-287D01*
G01X718691D01*
G03X717662Y567948I0J-1578D01*
G01X717636Y567926D01*
X717532Y567885D01*
G02X717470Y567875I-63J190D01*
G01X717414D01*
G02X717352Y567885I1J200D01*
G01X717248Y567926D01*
X717222Y567948D01*
G03X716193Y568330I-1029J-1196D01*
G01X716192D01*
G03X716029Y568322I-4J-1578D01*
G01X716027D01*
G03X715999Y568319I154J-1571D01*
G01X715996D01*
X715992Y568318D01*
X715990D01*
X715986Y568317D01*
G03X715977Y568316I170J-1569D01*
G01X715973D01*
X715947Y568312D01*
X715944Y568311D01*
X715942D01*
G03X715924Y568308I250J-1558D01*
G01X715917Y568307D01*
G02X715763Y568351I-27J198D01*
G01X715715Y568392D01*
G03X715713Y568394I-142J-140D01*
G01X715663Y568435D01*
G02X715656Y568442I138J145D01*
G01X715649Y568450D01*
G03X715640Y568460I-152J-128D01*
G03X715638Y568462I-142J-140D01*
G02X715594Y568580I156J125D01*
G01Y568589D01*
G03Y568597I-1802J4D01*
G01Y569613D01*
G02X715616Y569704I200J0D01*
G02X715652Y569754I178J-90D01*
G01X718146Y572248D01*
G02X718242Y572301I141J-142D01*
G01X718330D01*
X718365Y572293D01*
X718368Y572292D01*
X718373Y572291D01*
X718376D01*
X718395Y572287D01*
G03X718483Y572273I292J1552D01*
G03X718491Y572272I200J1566D01*
G01X718498Y572271D01*
G03X718526Y572268I182J1568D01*
G01X718528D01*
X718537Y572267D01*
X718538D01*
G03X718681Y572260I149J1571D01*
G01X718691D01*
X718712Y572259D01*
G03X720251Y573589I-20J1579D01*
G01X720257Y573631D01*
X720279Y573666D01*
G02X720335Y573724I169J-107D01*
G01X720452Y573806D01*
X720454D01*
X720580Y573893D01*
G02X720726Y573919I106J-170D01*
G03X720731Y573918I356J1767D01*
G01X720733Y573917D01*
X720734D01*
X720738Y573916D01*
X720739D01*
X720751Y573914D01*
X720754Y573913D01*
G03X720782Y573908I331J1772D01*
G01X720784D01*
X720800Y573905D01*
G03X720811Y573903I328J1773D01*
G01X720813D01*
G03X720839Y573899I287J1779D01*
G01X720847Y573898D01*
X720861Y573896D01*
G03X720884Y573893I245J1786D01*
G01X720886D01*
G03X720900Y573891I262J1783D01*
G01X720904D01*
G03X720933Y573888I200J1791D01*
G01X720972Y573885D01*
X720978D01*
G03X721075Y573882I104J1799D01*
G03X721092I9J1802D01*
G01X721093D01*
G03X721096I1J1802D01*
G03X721110I7J1802D01*
G01X721137D01*
G03X721175Y573883I-28J1802D01*
G01X721177D01*
G03X721262Y573889I-84J1801D01*
G01X721271Y573890D01*
X721273D01*
G03X721292Y573892I-179J1793D01*
G01X721298Y573893D01*
G03X721346Y573899I-200J1792D01*
G03X721536Y573936I-249J1785D01*
G01X721545Y573938D01*
X721549Y573939D01*
X721560Y573942D01*
X721597Y573935D01*
G02X721673Y573905I-34J-197D01*
G01X721903Y573752D01*
X721927Y573736D01*
G02X721978Y573683I-116J-163D01*
G01X722000Y573650D01*
X722007Y573605D01*
G03X723491Y572337I1484J234D01*
G03X724993Y573839I0J1502D01*
G03X723493Y575341I-1502J0D01*
G01X723489D01*
G03X723487I-1J-1502D01*
G37*
G36*
G01X492382Y54588D02*
X520615D01*
X520833Y54370D01*
Y52809D01*
X520615Y52591D01*
X492382D01*
G03X486445Y46654I0J-5937D01*
G01Y7874D01*
G02X480571Y2000I-5874J0D01*
G01X385689D01*
G02X379815Y7874I0J5874D01*
G01Y45301D01*
X381812D01*
Y7874D01*
G03X385687Y3998I3876J0D01*
G01X480571D01*
G03X484448Y7874I0J3877D01*
G01Y46654D01*
G02X492382Y54588I7934J0D01*
G37*
G36*
G01X389002Y952691D02*
X433488D01*
G02X433630Y952632I0J-200D01*
G01X434097Y952165D01*
G02X434156Y952023I-141J-142D01*
G01Y881193D01*
X434183Y881166D01*
Y840498D01*
G02X433983Y840298I-200J0D01*
G01X387128D01*
G02X386987Y840356I0J200D01*
G01X385867Y841476D01*
G02X385808Y841618I141J142D01*
G01Y862545D01*
G02X385882Y862700I200J0D01*
G01X386157Y862924D01*
X386243Y862946D01*
X386288Y862936D01*
G03X386589Y862906I299J1472D01*
G03Y865910I0J1502D01*
G03X386288Y865880I-2J-1502D01*
G01X386243Y865870D01*
X386157Y865892D01*
X385882Y866116D01*
G02X385808Y866271I126J155D01*
G01Y946734D01*
G02X385873Y946881I200J0D01*
G03X386358Y947987I-1017J1105D01*
G03X385873Y949093I-1502J1D01*
G02X385808Y949240I135J147D01*
G01Y949603D01*
G02X385931Y949788I200J0D01*
G01X385988Y949812D01*
X386106Y949788D01*
X388702Y947191D01*
G03X390047Y946634I1345J1345D01*
G01X392910D01*
G03Y950438I0J1902D01*
G01X390917D01*
G02X390776Y950496I0J200D01*
G01X388922Y952350D01*
G02X388879Y952568I142J141D01*
G01X388903Y952624D01*
X389002Y952691D01*
G37*
G36*
G01X382016Y1003008D02*
G03I-639J0D01*
G37*
G36*
G01X381684Y1009444D02*
G03I-639J0D01*
G37*
G36*
G01X401416Y1155944D02*
X530601D01*
G02X530743Y1155885I0J-200D01*
G01X533757Y1152871D01*
G02X533759Y1152869I-140J-142D01*
G02X533816Y1152729I-143J-140D01*
G01Y1099862D01*
G02X533658Y1099666I-200J0D01*
G03Y1073642I2759J-13012D01*
G02X533816Y1073446I-42J-196D01*
G01Y1057907D01*
G03X533875Y1057765I200J0D01*
G01X539706Y1051934D01*
G02X539765Y1051792I-141J-142D01*
G01Y1028332D01*
G02X539565Y1028132I-200J0D01*
G01X524531D01*
G03X524219Y1028107I-5J-1901D01*
G03X523636Y1027910I309J-1876D01*
G01Y1027909D01*
X523604Y1027892D01*
G03X523186Y1027576I927J-1661D01*
G01X516566Y1020956D01*
G02X516400Y1020899I-141J141D01*
G01X516041Y1020944D01*
X515964Y1020994D01*
X515940Y1021034D01*
G03X514649Y1021768I-1291J-768D01*
G03X513147Y1020266I0J-1502D01*
G03X513881Y1018975I1502J0D01*
G01X513921Y1018951D01*
X513971Y1018874D01*
X514016Y1018515D01*
G02X513959Y1018349I-198J-25D01*
G01X513221Y1017611D01*
G03X512664Y1016266I1345J-1345D01*
G03X514566Y1014364I1902J0D01*
G03X515911Y1014921I0J1902D01*
G01X523035Y1022046D01*
X525260Y1024271D01*
G02X525401Y1024330I142J-141D01*
G01X539585D01*
G02X539765Y1024130I-21J-200D01*
G01Y1009160D01*
G02X539706Y1009018I-200J0D01*
G01X538571Y1007883D01*
Y1007848D01*
X538537Y1007797D01*
G03X538192Y1006674I1655J-1123D01*
G01Y992668D01*
G02X538133Y992527I-200J1D01*
G01X536968Y991362D01*
X536940Y991333D01*
X536866Y991303D01*
X532131D01*
G03X532055Y991288I0J-200D01*
G01X532019Y991273D01*
X532014Y991268D01*
G02X531814Y991068I-200J0D01*
G01X523846D01*
G02X523661Y991194I1J200D01*
G01X523501Y991598D01*
X523527Y991717D01*
X523573Y991759D01*
G03X524046Y992854I-1029J1094D01*
G03X521042I-1502J0D01*
G03X521515Y991759I1502J-1D01*
G01X521561Y991717D01*
X521587Y991598D01*
X521427Y991194D01*
G02X521242Y991068I-186J74D01*
G01X495802D01*
G02X495660Y991127I0J200D01*
G01X494286Y992501D01*
G03X494144Y992560I-142J-141D01*
G01X484531D01*
G03X484389Y992501I0J-200D01*
G01X483015Y991127D01*
X482987Y991098D01*
X482913Y991068D01*
X476570D01*
G02X476392Y991176I0J200D01*
G01X476203Y991542D01*
X476211Y991653D01*
X476243Y991699D01*
G03X476520Y992568I-1225J869D01*
G03X473516I-1502J0D01*
G03X473793Y991699I1502J0D01*
G01X473825Y991653D01*
X473833Y991542D01*
X473644Y991176D01*
G02X473466Y991068I-178J92D01*
G01X437150D01*
X437076Y991098D01*
X437048Y991127D01*
X392202Y1035973D01*
X392173Y1036001D01*
X392143Y1036075D01*
Y1046235D01*
G03X392113Y1046340I-200J0D01*
G01X392099Y1046364D01*
X392084Y1046416D01*
Y1126924D01*
G02X392167Y1127086I200J0D01*
G01X392168D01*
G02X392257Y1127122I117J-162D01*
G03X404386Y1141024I-1903J13902D01*
G03X399563Y1151612I-14033J0D01*
G01X399529Y1151641D01*
X399494Y1151719D01*
Y1154023D01*
G02X399551Y1154163I200J0D01*
G01X399552Y1154164D01*
X401274Y1155885D01*
G02X401276Y1155887I142J-140D01*
G02X401416Y1155944I140J-143D01*
G37*
G36*
G01X413783Y1419300D02*
X421800D01*
G02X421997Y1419136I0J-200D01*
G01X423097Y1413143D01*
G02X423100Y1413107I-197J-35D01*
G01Y1405183D01*
G02X423041Y1405041I-200J0D01*
G01X421259Y1403259D01*
G03X421200Y1403117I141J-142D01*
G01Y1392228D01*
G02X421146Y1392091I-200J0D01*
G01X420932Y1391863D01*
X420865Y1391831D01*
X420826Y1391829D01*
G03Y1388831I99J-1499D01*
G01X420865Y1388829D01*
X420932Y1388797D01*
X421146Y1388569D01*
G02X421200Y1388432I-146J-137D01*
G01Y1385807D01*
G02X421135Y1385659I-200J0D01*
G01X420886Y1385431D01*
X420808Y1385405D01*
X420766Y1385408D01*
G03X420636Y1385414I-134J-1496D01*
G03Y1382410I0J-1502D01*
G03X420766Y1382416I-4J1502D01*
G01X420808Y1382419D01*
X420886Y1382393D01*
X421135Y1382165D01*
G02X421200Y1382017I-135J-148D01*
G01Y1375083D01*
G03X421259Y1374941I200J0D01*
G01X427341Y1368859D01*
G02X427400Y1368717I-141J-142D01*
G01Y1363051D01*
G02X427341Y1362909I-200J0D01*
G01X426393Y1361961D01*
X426291Y1361933D01*
X426239Y1361947D01*
G03X425855Y1361997I-384J-1452D01*
G03X424390Y1360826I0J-1502D01*
G01X424378Y1360772D01*
X424303Y1360693D01*
X423914Y1360580D01*
G02X423717Y1360631I-55J192D01*
G01X417394Y1366954D01*
G02X417336Y1367095I142J141D01*
G01Y1369901D01*
G02X417432Y1370072I200J0D01*
G01X417768Y1370277D01*
X417873Y1370280D01*
X417919Y1370256D01*
G03X418610Y1370088I690J1334D01*
G03Y1373092I0J1502D01*
G03X417583Y1372686I0J-1502D01*
G01X417555Y1372660D01*
X417486Y1372632D01*
X417138Y1372630D01*
X417069Y1372657D01*
X417040Y1372682D01*
G03X416029Y1373074I-1012J-1110D01*
G03X414527Y1371572I0J-1502D01*
G03X414700Y1370873I1502J1D01*
G01X414711Y1370851D01*
X414722Y1370804D01*
Y1366471D01*
G03X415105Y1365547I1306J0D01*
G01X421935Y1358717D01*
G02X421994Y1358576I-141J-142D01*
G01Y1357644D01*
G02X421935Y1357503I-200J1D01*
G01X420659Y1356227D01*
G03X420600Y1356085I141J-142D01*
G01Y1333683D01*
G02X420541Y1333541I-200J0D01*
G01X411959Y1324959D01*
G02X411817Y1324900I-142J141D01*
G01X404783D01*
G03X404641Y1324841I0J-200D01*
G01X401359Y1321559D01*
G03X401300Y1321417I141J-142D01*
G01Y1311083D01*
G02X401241Y1310941I-200J0D01*
G01X400559Y1310259D01*
G02X400417Y1310200I-142J141D01*
G01X385983D01*
G02X385841Y1310259I0J200D01*
G01X383159Y1312941D01*
G02X383100Y1313083I141J142D01*
G01Y1368517D01*
G02X383159Y1368659I200J0D01*
G01X391441Y1376941D01*
G02X391583Y1377000I142J-141D01*
G01X393337D01*
G02X393493Y1376926I1J-200D01*
G03X395821I1164J949D01*
G02X395977Y1377000I155J-126D01*
G01X413917D01*
G03X414059Y1377059I0J200D01*
G01X414941Y1377941D01*
G03X415000Y1378083I-141J142D01*
G01Y1392017D01*
G03X414941Y1392159I-200J0D01*
G01X412059Y1395041D01*
G02X412000Y1395183I141J142D01*
G01Y1417517D01*
G02X412059Y1417659I200J0D01*
G01X413641Y1419241D01*
G02X413783Y1419300I142J-141D01*
G37*
G36*
G01X396421Y601910D02*
Y710609D01*
G02X396480Y710751I200J0D01*
G01X410639Y724909D01*
G02X410781Y724968I142J-141D01*
G01X422977D01*
G03X423274Y725003I-3J1307D01*
G01X423297Y725008D01*
X472636D01*
G02X472778Y724949I0J-200D01*
G01X475277Y722450D01*
G02X475336Y722308I-141J-142D01*
G01Y642592D01*
G02X475277Y642450I-200J0D01*
G01X470812Y637985D01*
G03X470753Y637843I141J-142D01*
G01Y609556D01*
G03X470768Y609479I200J-1D01*
G01X470797Y609411D01*
G02X470812Y609334I-185J-76D01*
G01Y526626D01*
G02X470790Y526535I-200J0D01*
G02X470754Y526485I-178J90D01*
G01X469523Y525254D01*
G02X469473Y525218I-140J142D01*
G02X469382Y525196I-91J178D01*
G01X411642D01*
G02X411551Y525218I0J200D01*
G02X411501Y525254I90J178D01*
G01X407369Y529386D01*
G02X407333Y529436I142J140D01*
G02X407311Y529527I178J91D01*
G01Y590854D01*
G03X407252Y590996I-200J0D01*
G01X396480Y601768D01*
G02X396421Y601910I141J142D01*
G37*
G36*
G01X431078Y358115D02*
G03I-639J0D01*
G37*
G36*
G01X448731Y375770D02*
G03I-639J0D01*
G37*
G36*
G01X462881Y809792D02*
G03I-639J0D01*
G37*
G36*
G01X463712Y859203D02*
G03I-577J0D01*
G37*
G36*
G01X461033Y867050D02*
G03I-577J0D01*
G37*
G36*
G01X468072Y924532D02*
G03I-577J0D01*
G37*
G36*
G01X626475Y1217890D02*
X626476D01*
G03X626702Y1217910I-1J1302D01*
G01X626704D01*
X626737Y1217916D01*
X626826Y1217888D01*
X627127Y1217602D01*
X627159Y1217512D01*
X627153Y1217466D01*
G03X627144Y1217322I1193J-147D01*
G03X629548I1202J0D01*
G03X629539Y1217464I-1202J-5D01*
G01Y1217467D01*
G02X629599Y1217633I199J22D01*
G01X629865Y1217888D01*
X629954Y1217916D01*
X629973Y1217913D01*
G03X630215Y1217890I244J1279D01*
G01X630216D01*
G03X630442Y1217910I-1J1302D01*
G01X630444D01*
X630477Y1217916D01*
X630566Y1217888D01*
X630867Y1217602D01*
X630899Y1217512D01*
X630893Y1217466D01*
G03X630884Y1217322I1193J-147D01*
G03X633288I1202J0D01*
G03X633279Y1217465I-1202J-4D01*
G02X633340Y1217634I198J24D01*
G01X633606Y1217888D01*
X633695Y1217916D01*
X633719Y1217912D01*
G03X633956Y1217890I238J1280D01*
G01X633957D01*
G03X634183Y1217910I-1J1302D01*
G01X634185D01*
X634218Y1217916D01*
X634307Y1217888D01*
X634608Y1217602D01*
X634640Y1217512D01*
X634634Y1217466D01*
G03X634625Y1217322I1193J-147D01*
G03X637029I1202J0D01*
G03X637020Y1217464I-1202J-5D01*
G01Y1217467D01*
G02X637080Y1217633I199J22D01*
G01X637346Y1217888D01*
X637435Y1217916D01*
X637454Y1217913D01*
G03X637696Y1217890I244J1279D01*
G03X638998Y1219192I0J1302D01*
G03X638997Y1219247I-1302J4D01*
G01X638996Y1219260D01*
X638995Y1219301D01*
X639020Y1219347D01*
G02X639090Y1219422I176J-94D01*
G01X639280Y1219541D01*
X639388Y1219609D01*
G02X639490Y1219639I105J-170D01*
G01X639545Y1219640D01*
G03X639982Y1219425I1891J3292D01*
G01X640009Y1219414D01*
X640064Y1219369D01*
G02X640134Y1219217I-130J-152D01*
G01Y1219192D01*
G03X642738I1302J0D01*
G01Y1219223D01*
X642737Y1219252D01*
X642753Y1219309D01*
X642770Y1219336D01*
X642787Y1219362D01*
X642834Y1219401D01*
X642863Y1219413D01*
G03X643282Y1219614I-1430J3517D01*
G01X643283Y1219615D01*
G02X643385Y1219639I95J-176D01*
G01X643438Y1219638D01*
X643782Y1219422D01*
G02X643852Y1219347I-106J-169D01*
G01X643877Y1219301D01*
X643876Y1219260D01*
X643875Y1219247D01*
G03X643874Y1219192I1301J-51D01*
G03X646478I1302J0D01*
G03X646477Y1219247I-1302J4D01*
G01X646476Y1219260D01*
X646475Y1219301D01*
X646500Y1219347D01*
G02X646570Y1219422I176J-94D01*
G01X646760Y1219541D01*
X646868Y1219609D01*
G02X646970Y1219639I105J-170D01*
G01X647025Y1219640D01*
G03X647462Y1219425I1891J3292D01*
G01X647489Y1219414D01*
X647544Y1219369D01*
G02X647614Y1219217I-130J-152D01*
G01Y1219192D01*
G03X648916Y1217890I1302J0D01*
G03X649820Y1218255I0J1302D01*
G01X649821Y1218256D01*
G02X649962Y1218312I139J-144D01*
G01X650162Y1218310D01*
X650227Y1218309D01*
X650233D01*
X650251Y1218308D01*
G02X650330Y1218288I-9J-200D01*
G01X650360Y1218273D01*
X650386Y1218245D01*
X651711Y1216920D01*
G02X651725Y1216904I-143J-139D01*
G01X651739Y1216886D01*
G02X651773Y1216786I-166J-112D01*
G01X651776Y1216534D01*
Y1216498D01*
G02X651720Y1216357I-200J-2D01*
G01X651719Y1216356D01*
G03X651354Y1215452I937J-904D01*
G03X652604Y1214151I1302J0D01*
G01X652642Y1214150D01*
X652676Y1214135D01*
G02X652736Y1214094I-81J-183D01*
G01X652822Y1214009D01*
G02X652882Y1213866I-140J-143D01*
G01Y1213298D01*
G02X652872Y1213235I-200J-1D01*
G02X652822Y1213155I-190J63D01*
G01X652791Y1213125D01*
G03X652789Y1213123I140J-142D01*
G01X652737Y1213071D01*
G02X652687Y1213034I-143J140D01*
G02X652673Y1213028I-86J181D01*
G01X652640Y1213014D01*
X652622D01*
G03X652604Y1210411I32J-1302D01*
G01X652642Y1210410D01*
X652676Y1210395D01*
G02X652736Y1210354I-81J-183D01*
G01X652822Y1210269D01*
G02X652882Y1210126I-140J-143D01*
G01Y1209558D01*
G02X652872Y1209495I-200J-1D01*
G02X652822Y1209415I-190J63D01*
G01X652791Y1209385D01*
G03X652789Y1209383I140J-142D01*
G01X652737Y1209331D01*
G02X652687Y1209294I-143J140D01*
G02X652673Y1209288I-86J181D01*
G01X652640Y1209274D01*
X652622D01*
G03X652604Y1206671I32J-1302D01*
G01X652642Y1206670D01*
X652676Y1206655D01*
G02X652736Y1206614I-81J-183D01*
G01X652822Y1206529D01*
G02X652882Y1206386I-140J-143D01*
G01Y1205818D01*
G02X652872Y1205755I-200J-1D01*
G02X652822Y1205675I-190J63D01*
G01X652791Y1205645D01*
G03X652789Y1205643I140J-142D01*
G01X652737Y1205591D01*
G02X652687Y1205554I-143J140D01*
G02X652673Y1205548I-86J181D01*
G01X652640Y1205534D01*
X652622D01*
G03X652604Y1202931I32J-1302D01*
G01X652642Y1202930D01*
X652676Y1202915D01*
G02X652736Y1202874I-81J-183D01*
G01X652822Y1202789D01*
G02X652882Y1202646I-140J-143D01*
G01Y1202077D01*
G02X652872Y1202014I-200J-1D01*
G02X652822Y1201934I-190J63D01*
G01X652791Y1201904D01*
G03X652789Y1201902I140J-142D01*
G01X652737Y1201850D01*
G02X652687Y1201813I-143J140D01*
G02X652673Y1201807I-86J181D01*
G01X652640Y1201793D01*
X652622D01*
G03X652604Y1199190I32J-1302D01*
G01X652642Y1199189D01*
X652676Y1199174D01*
G02X652736Y1199133I-81J-183D01*
G01X652822Y1199048D01*
G02X652882Y1198905I-140J-143D01*
G01Y1198337D01*
G02X652872Y1198274I-200J-1D01*
G02X652822Y1198194I-190J63D01*
G01X652791Y1198164D01*
G03X652789Y1198162I140J-142D01*
G01X652737Y1198110D01*
G02X652687Y1198073I-143J140D01*
G02X652673Y1198067I-86J181D01*
G01X652640Y1198053D01*
X652622D01*
G03X652604Y1195450I32J-1302D01*
G01X652642Y1195449D01*
X652676Y1195434D01*
G02X652736Y1195393I-81J-183D01*
G01X652822Y1195308D01*
G02X652882Y1195165I-140J-143D01*
G01Y1194597D01*
G02X652872Y1194534I-200J-1D01*
G02X652822Y1194454I-190J63D01*
G01X652791Y1194424D01*
G03X652789Y1194422I140J-142D01*
G01X652737Y1194370D01*
G02X652687Y1194333I-143J140D01*
G02X652673Y1194327I-86J181D01*
G01X652640Y1194313D01*
X652622D01*
G03X652604Y1191710I32J-1302D01*
G01X652642Y1191709D01*
X652676Y1191694D01*
G02X652736Y1191653I-81J-183D01*
G01X652822Y1191568D01*
G02X652882Y1191425I-140J-143D01*
G01Y1190857D01*
G02X652872Y1190794I-200J-1D01*
G02X652822Y1190714I-190J63D01*
G01X652791Y1190684D01*
G03X652789Y1190682I140J-142D01*
G01X652737Y1190630D01*
G02X652687Y1190593I-143J140D01*
G02X652673Y1190587I-86J181D01*
G01X652639Y1190573D01*
G03X651354Y1189271I17J-1302D01*
G03X652656Y1187969I1302J0D01*
G03X652821Y1187979I4J1302D01*
G01X652825Y1187980D01*
X652828D01*
X652848Y1187981D01*
G02X653044Y1187811I-2J-200D01*
G01Y1187804D01*
X653045Y1187784D01*
Y1187018D01*
X653044Y1186998D01*
Y1186991D01*
G02X652848Y1186821I-198J30D01*
G01X652828Y1186822D01*
X652825D01*
X652821Y1186823D01*
G03X652656Y1186833I-161J-1293D01*
G03Y1184229I0J-1302D01*
G03X652821Y1184239I4J1303D01*
G01X652825Y1184240D01*
X652828D01*
X652848Y1184241D01*
G02X653044Y1184071I-2J-200D01*
G01Y1184064D01*
X653045Y1184044D01*
Y1179875D01*
G03X653049Y1179835I200J0D01*
G01X653057Y1179797D01*
G02X653015Y1179655I-199J-18D01*
G01X652813Y1179423D01*
Y1179421D01*
X652812D01*
G02X652746Y1179371I-151J131D01*
G01X652706Y1179353D01*
X652656D01*
G03Y1176749I0J-1302D01*
G01X652658D01*
G03X653599Y1177151I0J1303D01*
G01X653600Y1177153D01*
X653603Y1177156D01*
G02X653706Y1177214I145J-138D01*
G01X653735Y1177220D01*
X653792Y1177215D01*
X654145Y1177074D01*
X654171Y1177064D01*
X654194Y1177050D01*
G02X654291Y1176879I-103J-171D01*
G01Y1176268D01*
G03X654350Y1176126I200J0D01*
G01X654960Y1175516D01*
X655011D01*
X655303Y1175027D01*
G02X655282Y1174812I-178J-91D01*
G01X655269Y1174795D01*
X655153Y1174696D01*
G03X655095Y1174312I1244J-384D01*
G01Y1174310D01*
G03X657699I1302J0D01*
G01Y1174312D01*
G03X657553Y1174911I-1302J0D01*
G03X657544Y1174928I-1155J-601D01*
G01X657523Y1174966D01*
X657520Y1175007D01*
G02X657548Y1175123I200J13D01*
G01X657694Y1175369D01*
X657723Y1175418D01*
G02X657745Y1175448I172J-103D01*
G01X657766Y1175471D01*
X657791Y1175486D01*
G02X657846Y1175509I104J-171D01*
G01X657872Y1175516D01*
X660820D01*
G03X660962Y1175575I0J200D01*
G01X661237Y1175850D01*
G02X661339Y1175903I139J-143D01*
G02X661377Y1175907I40J-196D01*
G01X662588D01*
G03X662610Y1175908I2J200D01*
G01X662621Y1175910D01*
X662622D01*
X662651Y1175914D01*
X662677Y1175911D01*
G02X662733Y1175897I-20J-199D01*
G01X662768Y1175879D01*
G02X662851Y1175784I-101J-172D01*
G01X662993Y1175443D01*
G02X663001Y1175419I-186J-75D01*
G02X662952Y1175227I-193J-53D01*
G01X662949Y1175224D01*
G03X662575Y1174311I928J-913D01*
G01Y1174310D01*
G03X665179I1302J0D01*
G01Y1174311D01*
G03X664803Y1175226I-1302J0D01*
G01X664802Y1175227D01*
G02X664748Y1175329I142J141D01*
G01X664743Y1175357D01*
X664749Y1175416D01*
X664843Y1175640D01*
Y1175642D01*
X664905Y1175792D01*
G02X664967Y1175867I181J-86D01*
G01X664983Y1175878D01*
G02X665045Y1175903I105J-171D01*
G02X665087Y1175907I40J-196D01*
G01X670068D01*
G03X670090Y1175908I2J200D01*
G01X670101Y1175910D01*
X670102D01*
X670131Y1175914D01*
X670157Y1175911D01*
G02X670213Y1175897I-20J-199D01*
G01X670248Y1175879D01*
G02X670331Y1175784I-101J-172D01*
G01X670473Y1175443D01*
G02X670481Y1175419I-186J-75D01*
G02X670432Y1175227I-193J-53D01*
G01X670429Y1175224D01*
G03X670055Y1174311I928J-913D01*
G01Y1174310D01*
G03X672659I1302J0D01*
G01Y1174311D01*
G03X672283Y1175226I-1302J0D01*
G01X672282Y1175227D01*
G02X672228Y1175329I142J141D01*
G01X672223Y1175357D01*
X672229Y1175416D01*
X672323Y1175640D01*
Y1175642D01*
X672385Y1175792D01*
G02X672447Y1175867I181J-86D01*
G01X672463Y1175878D01*
G02X672525Y1175903I105J-171D01*
G02X672567Y1175907I40J-196D01*
G01X677548D01*
G03X677570Y1175908I2J200D01*
G01X677581Y1175910D01*
X677582D01*
X677611Y1175914D01*
X677637Y1175911D01*
G02X677693Y1175897I-20J-199D01*
G01X677728Y1175879D01*
G02X677811Y1175784I-101J-172D01*
G01X677953Y1175443D01*
G02X677961Y1175419I-186J-75D01*
G02X677912Y1175227I-193J-53D01*
G01X677909Y1175224D01*
G03X677535Y1174311I928J-913D01*
G01Y1174310D01*
G03X680139I1302J0D01*
G01Y1174311D01*
G03X679763Y1175226I-1302J0D01*
G01X679762Y1175227D01*
G02X679708Y1175329I142J141D01*
G01X679703Y1175357D01*
X679709Y1175416D01*
X679803Y1175640D01*
Y1175642D01*
X679865Y1175792D01*
G02X679927Y1175867I181J-86D01*
G01X679943Y1175878D01*
G02X680005Y1175903I105J-171D01*
G02X680047Y1175907I40J-196D01*
G01X685029D01*
G03X685051Y1175908I2J200D01*
G01X685062Y1175910D01*
X685063D01*
X685092Y1175914D01*
X685118Y1175911D01*
G02X685174Y1175897I-20J-199D01*
G01X685209Y1175879D01*
G02X685292Y1175784I-101J-172D01*
G01X685434Y1175443D01*
G02X685442Y1175419I-186J-75D01*
G02X685393Y1175227I-193J-53D01*
G01X685390Y1175224D01*
G03X685016Y1174311I928J-913D01*
G01Y1174310D01*
G03X687620I1302J0D01*
G01Y1174311D01*
G03X687244Y1175226I-1302J0D01*
G01X687243Y1175227D01*
G02X687189Y1175329I142J141D01*
G01X687184Y1175357D01*
X687190Y1175416D01*
X687284Y1175640D01*
Y1175642D01*
X687346Y1175792D01*
G02X687408Y1175867I181J-86D01*
G01X687424Y1175878D01*
G02X687486Y1175903I105J-171D01*
G02X687528Y1175907I40J-196D01*
G01X696249D01*
G03X696271Y1175908I2J200D01*
G01X696282Y1175910D01*
X696283D01*
X696312Y1175914D01*
X696338Y1175911D01*
G02X696394Y1175897I-20J-199D01*
G01X696429Y1175879D01*
G02X696512Y1175784I-101J-172D01*
G01X696654Y1175443D01*
G02X696662Y1175419I-186J-75D01*
G02X696613Y1175227I-193J-53D01*
G01X696610Y1175224D01*
G03X696236Y1174311I928J-913D01*
G01Y1174310D01*
G03X698840I1302J0D01*
G01Y1174311D01*
G03X698464Y1175226I-1302J0D01*
G01X698463Y1175227D01*
G02X698409Y1175329I142J141D01*
G01X698404Y1175357D01*
X698410Y1175416D01*
X698504Y1175640D01*
Y1175642D01*
X698566Y1175792D01*
G02X698628Y1175867I181J-86D01*
G01X698644Y1175878D01*
G02X698706Y1175903I105J-171D01*
G02X698748Y1175907I40J-196D01*
G01X703730D01*
G03X703752Y1175908I2J200D01*
G01X703763Y1175910D01*
X703764D01*
X703793Y1175914D01*
X703819Y1175911D01*
G02X703875Y1175897I-20J-199D01*
G01X703910Y1175879D01*
G02X703993Y1175784I-101J-172D01*
G01X704135Y1175443D01*
G02X704143Y1175419I-186J-75D01*
G02X704094Y1175227I-193J-53D01*
G01X704091Y1175224D01*
G03X703717Y1174311I928J-913D01*
G01Y1174310D01*
G03X706321I1302J0D01*
G01Y1174311D01*
G03X705945Y1175226I-1302J0D01*
G01X705944Y1175227D01*
G02X705890Y1175329I142J141D01*
G01X705885Y1175357D01*
X705891Y1175416D01*
X705985Y1175640D01*
Y1175642D01*
X706047Y1175792D01*
G02X706109Y1175867I181J-86D01*
G01X706125Y1175878D01*
G02X706187Y1175903I105J-171D01*
G02X706229Y1175907I40J-196D01*
G01X711210D01*
G03X711232Y1175908I2J200D01*
G01X711243Y1175910D01*
X711244D01*
X711273Y1175914D01*
X711299Y1175911D01*
G02X711355Y1175897I-20J-199D01*
G01X711390Y1175879D01*
G02X711473Y1175784I-101J-172D01*
G01X711615Y1175443D01*
G02X711623Y1175419I-186J-75D01*
G02X711574Y1175227I-193J-53D01*
G01X711571Y1175224D01*
G03X711197Y1174311I928J-913D01*
G01Y1174310D01*
G03X713801I1302J0D01*
G01Y1174311D01*
G03X713425Y1175226I-1302J0D01*
G01X713424Y1175227D01*
G02X713370Y1175329I142J141D01*
G01X713365Y1175357D01*
X713371Y1175416D01*
X713465Y1175640D01*
Y1175642D01*
X713527Y1175792D01*
G02X713589Y1175867I181J-86D01*
G01X713605Y1175878D01*
G02X713667Y1175903I105J-171D01*
G02X713709Y1175907I40J-196D01*
G01X718690D01*
G03X718712Y1175908I2J200D01*
G01X718723Y1175910D01*
X718724D01*
X718753Y1175914D01*
X718779Y1175911D01*
G02X718835Y1175897I-20J-199D01*
G01X718870Y1175879D01*
G02X718953Y1175784I-101J-172D01*
G01X719095Y1175443D01*
G02X719103Y1175419I-186J-75D01*
G02X719054Y1175227I-193J-53D01*
G01X719051Y1175224D01*
G03X718677Y1174311I928J-913D01*
G01Y1174310D01*
G03X721281I1302J0D01*
G01Y1174311D01*
G03X720905Y1175226I-1302J0D01*
G01X720904Y1175227D01*
G02X720850Y1175329I142J141D01*
G01X720845Y1175357D01*
X720851Y1175416D01*
X720945Y1175640D01*
Y1175642D01*
X721007Y1175792D01*
G02X721069Y1175867I181J-86D01*
G01X721085Y1175878D01*
G02X721147Y1175903I105J-171D01*
G02X721189Y1175907I40J-196D01*
G01X724490D01*
G02X724528Y1175903I-2J-200D01*
G02X724630Y1175850I-37J-196D01*
G01X724904Y1175576D01*
G02X724957Y1175474I-143J-139D01*
G02X724961Y1175436I-196J-40D01*
G01Y1174184D01*
G03X725020Y1174042I200J0D01*
G01X726795Y1172267D01*
G02X726817Y1172241I-141J-142D01*
G02X726834Y1172212I-164J-115D01*
G01X726842Y1172190D01*
G02X726853Y1172102I-188J-68D01*
G01X726822Y1171798D01*
G02X726794Y1171716I-199J22D01*
G01X726772Y1171679D01*
X726735Y1171653D01*
X726733D01*
G03X726157Y1170570I730J-1083D01*
G03X727459Y1169268I1302J0D01*
G03X727576Y1169273I3J1302D01*
G01X727619Y1169277D01*
X727658Y1169264D01*
G02X727729Y1169221I-66J-189D01*
G01X727945Y1169022D01*
G02X728010Y1168875I-135J-148D01*
G01Y1168525D01*
G02X727979Y1168419I-200J1D01*
G02X727945Y1168378I-170J106D01*
G01X727677Y1168133D01*
G02X727669Y1168126I-136J147D01*
G01X727667D01*
G02X727479Y1168103I-115J163D01*
G01X727408Y1168131D01*
G03X726157Y1166830I51J-1301D01*
G03X727459Y1165528I1302J0D01*
G03X727576Y1165533I3J1302D01*
G01X727619Y1165537D01*
X727658Y1165524D01*
G02X727729Y1165481I-66J-189D01*
G01X727945Y1165282D01*
G02X728010Y1165135I-135J-148D01*
G01Y1161045D01*
G02X727979Y1160939I-200J1D01*
G02X727945Y1160898I-170J106D01*
G01X727677Y1160653D01*
G02X727669Y1160646I-136J147D01*
G01X727667D01*
G02X727479Y1160623I-115J163D01*
G01X727408Y1160651D01*
G03X726157Y1159350I51J-1301D01*
G03X727459Y1158048I1302J0D01*
G03X727576Y1158053I3J1302D01*
G01X727619Y1158057D01*
X727658Y1158044D01*
G02X727729Y1158001I-66J-189D01*
G01X727945Y1157802D01*
G02X728010Y1157655I-135J-148D01*
G01Y1157305D01*
G02X727979Y1157199I-200J1D01*
G02X727945Y1157158I-170J106D01*
G01X727677Y1156913D01*
G02X727669Y1156906I-136J147D01*
G01X727667D01*
G02X727479Y1156883I-115J163D01*
G01X727408Y1156911D01*
G03X726157Y1155610I51J-1301D01*
G03X727459Y1154308I1302J0D01*
G03X727576Y1154313I3J1302D01*
G01X727619Y1154317D01*
X727658Y1154304D01*
G02X727729Y1154261I-66J-189D01*
G01X727945Y1154062D01*
G02X728010Y1153915I-135J-148D01*
G01Y1153564D01*
G02X727979Y1153458I-200J1D01*
G02X727945Y1153417I-170J106D01*
G01X727677Y1153172D01*
G02X727669Y1153165I-136J147D01*
G01X727667D01*
G02X727479Y1153142I-115J163D01*
G01X727408Y1153170D01*
G03X726157Y1151869I51J-1301D01*
G03X727459Y1150567I1302J0D01*
G03X727576Y1150572I3J1302D01*
G01X727619Y1150576D01*
X727658Y1150563D01*
G02X727729Y1150520I-66J-189D01*
G01X727945Y1150321D01*
G02X728010Y1150174I-135J-148D01*
G01Y1149824D01*
G02X727979Y1149718I-200J1D01*
G02X727945Y1149677I-170J106D01*
G01X727677Y1149432D01*
G02X727669Y1149425I-136J147D01*
G01X727667D01*
G02X727479Y1149402I-115J163D01*
G01X727408Y1149430D01*
G03X726157Y1148129I51J-1301D01*
G03X727459Y1146827I1302J0D01*
G03X727576Y1146832I3J1302D01*
G01X727619Y1146836D01*
X727658Y1146823D01*
G02X727729Y1146780I-66J-189D01*
G01X727945Y1146581D01*
G02X728010Y1146434I-135J-148D01*
G01Y1146084D01*
G02X727979Y1145978I-200J1D01*
G02X727945Y1145937I-170J106D01*
G01X727677Y1145692D01*
G02X727669Y1145685I-136J147D01*
G01X727667D01*
G02X727479Y1145662I-115J163D01*
G01X727408Y1145690D01*
G03X726157Y1144389I51J-1301D01*
G03X727459Y1143087I1302J0D01*
G03X727576Y1143092I3J1302D01*
G01X727619Y1143096D01*
X727658Y1143083D01*
G02X727729Y1143040I-66J-189D01*
G01X727945Y1142841D01*
G02X728010Y1142694I-135J-148D01*
G01Y1142344D01*
G02X727979Y1142238I-200J1D01*
G02X727945Y1142197I-170J106D01*
G01X727677Y1141952D01*
G02X727669Y1141945I-136J147D01*
G01X727667D01*
G02X727479Y1141922I-115J163D01*
G01X727408Y1141950D01*
G03X726157Y1140649I51J-1301D01*
G01Y1140648D01*
G03X726311Y1140034I1302J0D01*
G01X726312Y1140033D01*
G02X726335Y1139935I-177J-93D01*
G01X726334Y1139884D01*
X726218Y1139690D01*
X726130Y1139543D01*
G02X726113Y1139519I-171J103D01*
G02X725979Y1139447I-155J127D01*
G01X724794D01*
X724783Y1139445D01*
G03X724729Y1139441I62J-1200D01*
G01X724727D01*
G02X724636Y1139454I-18J199D01*
G01X724619Y1139462D01*
G02X724547Y1139523I90J179D01*
G01X724532Y1139544D01*
X724513Y1139593D01*
X724511Y1139619D01*
G02X724527Y1139721I199J21D01*
G01X724531Y1139730D01*
G02X724547Y1139760I184J-79D01*
G01X724581Y1139810D01*
X724593Y1139823D01*
G03X724922Y1140649I-872J826D01*
G03X723720Y1141851I-1202J0D01*
G03X722518Y1140675I0J-1202D01*
G01Y1140648D01*
G03X722848Y1139821I1202J0D01*
G01X722860Y1139809D01*
X722901Y1139748D01*
X722919Y1139707D01*
G02Y1139574I-189J-66D01*
G01X722865Y1139493D01*
G02X722861Y1139489I-143J139D01*
G01X722842Y1139472D01*
X722775Y1139447D01*
X721054D01*
X721043Y1139445D01*
G03X720989Y1139441I62J-1200D01*
G01X720987D01*
G02X720896Y1139454I-18J199D01*
G01X720879Y1139462D01*
G02X720807Y1139523I90J179D01*
G01X720792Y1139544D01*
X720773Y1139593D01*
X720771Y1139619D01*
G02X720787Y1139721I199J21D01*
G01X720791Y1139730D01*
G02X720807Y1139760I184J-79D01*
G01X720841Y1139810D01*
X720853Y1139823D01*
G03X721182Y1140649I-872J826D01*
G03X719980Y1141851I-1202J0D01*
G03X718778Y1140675I0J-1202D01*
G01Y1140648D01*
G03X719108Y1139821I1202J0D01*
G01X719120Y1139809D01*
X719161Y1139748D01*
X719179Y1139707D01*
G02Y1139574I-189J-66D01*
G01X719125Y1139493D01*
G02X719121Y1139489I-143J139D01*
G01X719102Y1139472D01*
X719035Y1139447D01*
X717314D01*
X717303Y1139445D01*
G03X717249Y1139441I62J-1200D01*
G01X717247D01*
G02X717156Y1139454I-18J199D01*
G01X717139Y1139462D01*
G02X717067Y1139523I90J179D01*
G01X717052Y1139544D01*
X717033Y1139593D01*
X717031Y1139619D01*
G02X717047Y1139721I199J21D01*
G01X717051Y1139730D01*
G02X717067Y1139760I184J-79D01*
G01X717101Y1139810D01*
X717113Y1139823D01*
G03X717442Y1140649I-872J826D01*
G03X716240Y1141851I-1202J0D01*
G03X715038Y1140675I0J-1202D01*
G01Y1140648D01*
G03X715368Y1139821I1202J0D01*
G01X715380Y1139809D01*
X715421Y1139748D01*
X715439Y1139707D01*
G02Y1139574I-189J-66D01*
G01X715385Y1139493D01*
G02X715381Y1139489I-143J139D01*
G01X715362Y1139472D01*
X715295Y1139447D01*
X713574D01*
X713563Y1139445D01*
G03X713509Y1139441I62J-1200D01*
G01X713507D01*
G02X713416Y1139454I-18J199D01*
G01X713399Y1139462D01*
G02X713327Y1139523I90J179D01*
G01X713312Y1139544D01*
X713293Y1139593D01*
X713291Y1139619D01*
G02X713307Y1139721I199J21D01*
G01X713311Y1139730D01*
G02X713327Y1139760I184J-79D01*
G01X713361Y1139810D01*
X713373Y1139823D01*
G03X713702Y1140649I-872J826D01*
G03X712500Y1141851I-1202J0D01*
G03X711298Y1140675I0J-1202D01*
G01Y1140648D01*
G03X711628Y1139821I1202J0D01*
G01X711640Y1139809D01*
X711681Y1139748D01*
X711699Y1139707D01*
G02Y1139574I-189J-66D01*
G01X711645Y1139493D01*
G02X711641Y1139489I-143J139D01*
G01X711622Y1139472D01*
X711555Y1139447D01*
X709834D01*
X709823Y1139445D01*
G03X709769Y1139441I62J-1200D01*
G01X709767D01*
G02X709676Y1139454I-18J199D01*
G01X709659Y1139462D01*
G02X709587Y1139523I90J179D01*
G01X709572Y1139544D01*
X709553Y1139593D01*
X709551Y1139619D01*
G02X709567Y1139721I199J21D01*
G01X709571Y1139730D01*
G02X709587Y1139760I184J-79D01*
G01X709621Y1139810D01*
X709633Y1139823D01*
G03X709962Y1140649I-872J826D01*
G03X708760Y1141851I-1202J0D01*
G03X707558Y1140675I0J-1202D01*
G01Y1140648D01*
G03X707888Y1139821I1202J0D01*
G01X707900Y1139809D01*
X707941Y1139748D01*
X707959Y1139707D01*
G02Y1139574I-189J-66D01*
G01X707905Y1139493D01*
G02X707901Y1139489I-143J139D01*
G01X707882Y1139472D01*
X707815Y1139447D01*
X706094D01*
X706083Y1139445D01*
G03X706029Y1139441I62J-1200D01*
G01X706027D01*
G02X705936Y1139454I-18J199D01*
G01X705919Y1139462D01*
G02X705847Y1139523I90J179D01*
G01X705832Y1139544D01*
X705813Y1139593D01*
X705811Y1139619D01*
G02X705827Y1139721I199J21D01*
G01X705831Y1139730D01*
G02X705847Y1139760I184J-79D01*
G01X705881Y1139810D01*
X705893Y1139823D01*
G03X706222Y1140649I-872J826D01*
G03X705020Y1141851I-1202J0D01*
G03X703818Y1140675I0J-1202D01*
G01Y1140648D01*
G03X704148Y1139821I1202J0D01*
G01X704160Y1139809D01*
X704201Y1139748D01*
X704219Y1139707D01*
G02Y1139574I-189J-66D01*
G01X704165Y1139493D01*
G02X704161Y1139489I-143J139D01*
G01X704142Y1139472D01*
X704075Y1139447D01*
X702353D01*
X702342Y1139445D01*
G03X702288Y1139441I62J-1200D01*
G01X702286D01*
G02X702195Y1139454I-18J199D01*
G01X702178Y1139462D01*
G02X702106Y1139523I90J179D01*
G01X702091Y1139544D01*
X702072Y1139593D01*
X702070Y1139619D01*
G02X702086Y1139721I199J21D01*
G01X702090Y1139730D01*
G02X702106Y1139760I184J-79D01*
G01X702140Y1139810D01*
X702152Y1139823D01*
G03X702481Y1140649I-872J826D01*
G03X701279Y1141851I-1202J0D01*
G03X700077Y1140675I0J-1202D01*
G01Y1140648D01*
G03X700407Y1139821I1202J0D01*
G01X700419Y1139809D01*
X700460Y1139748D01*
X700478Y1139707D01*
G02Y1139574I-189J-66D01*
G01X700424Y1139493D01*
G02X700420Y1139489I-143J139D01*
G01X700401Y1139472D01*
X700334Y1139447D01*
X698613D01*
X698602Y1139445D01*
G03X698548Y1139441I62J-1200D01*
G01X698546D01*
G02X698455Y1139454I-18J199D01*
G01X698438Y1139462D01*
G02X698366Y1139523I90J179D01*
G01X698351Y1139544D01*
X698332Y1139593D01*
X698330Y1139619D01*
G02X698346Y1139721I199J21D01*
G01X698350Y1139730D01*
G02X698366Y1139760I184J-79D01*
G01X698400Y1139810D01*
X698412Y1139823D01*
G03X698741Y1140649I-872J826D01*
G03X697539Y1141851I-1202J0D01*
G03X696337Y1140675I0J-1202D01*
G01Y1140648D01*
G03X696667Y1139821I1202J0D01*
G01X696679Y1139809D01*
X696720Y1139748D01*
X696738Y1139707D01*
G02Y1139574I-189J-66D01*
G01X696684Y1139493D01*
G02X696680Y1139489I-143J139D01*
G01X696661Y1139472D01*
X696594Y1139447D01*
X694873D01*
X694862Y1139445D01*
G03X694808Y1139441I62J-1200D01*
G01X694806D01*
G02X694715Y1139454I-18J199D01*
G01X694698Y1139462D01*
G02X694626Y1139523I90J179D01*
G01X694611Y1139544D01*
X694592Y1139593D01*
X694590Y1139619D01*
G02X694606Y1139721I199J21D01*
G01X694610Y1139730D01*
G02X694626Y1139760I184J-79D01*
G01X694660Y1139810D01*
X694672Y1139823D01*
G03X695001Y1140649I-872J826D01*
G03X693799Y1141851I-1202J0D01*
G03X692597Y1140675I0J-1202D01*
G01Y1140648D01*
G03X692927Y1139821I1202J0D01*
G01X692939Y1139809D01*
X692980Y1139748D01*
X692998Y1139707D01*
G02Y1139574I-189J-66D01*
G01X692944Y1139493D01*
G02X692940Y1139489I-143J139D01*
G01X692921Y1139472D01*
X692854Y1139447D01*
X687393D01*
X687382Y1139445D01*
G03X687328Y1139441I62J-1200D01*
G01X687326D01*
G02X687235Y1139454I-18J199D01*
G01X687218Y1139462D01*
G02X687146Y1139523I90J179D01*
G01X687131Y1139544D01*
X687112Y1139593D01*
X687110Y1139619D01*
G02X687126Y1139721I199J21D01*
G01X687130Y1139730D01*
G02X687146Y1139760I184J-79D01*
G01X687180Y1139810D01*
X687192Y1139823D01*
G03X687521Y1140649I-872J826D01*
G03X686319Y1141851I-1202J0D01*
G03X685117Y1140675I0J-1202D01*
G01Y1140648D01*
G03X685447Y1139821I1202J0D01*
G01X685459Y1139809D01*
X685500Y1139748D01*
X685518Y1139707D01*
G02Y1139574I-189J-66D01*
G01X685464Y1139493D01*
G02X685460Y1139489I-143J139D01*
G01X685441Y1139472D01*
X685374Y1139447D01*
X683653D01*
X683642Y1139445D01*
G03X683588Y1139441I62J-1200D01*
G01X683586D01*
G02X683495Y1139454I-18J199D01*
G01X683478Y1139462D01*
G02X683406Y1139523I90J179D01*
G01X683391Y1139544D01*
X683372Y1139593D01*
X683370Y1139619D01*
G02X683386Y1139721I199J21D01*
G01X683390Y1139730D01*
G02X683406Y1139760I184J-79D01*
G01X683440Y1139810D01*
X683452Y1139823D01*
G03X683781Y1140649I-872J826D01*
G03X682579Y1141851I-1202J0D01*
G03X681377Y1140675I0J-1202D01*
G01Y1140648D01*
G03X681707Y1139821I1202J0D01*
G01X681719Y1139809D01*
X681760Y1139748D01*
X681778Y1139707D01*
G02Y1139574I-189J-66D01*
G01X681724Y1139493D01*
G02X681720Y1139489I-143J139D01*
G01X681701Y1139472D01*
X681634Y1139447D01*
X679912D01*
X679901Y1139445D01*
G03X679847Y1139441I62J-1200D01*
G01X679845D01*
G02X679754Y1139454I-18J199D01*
G01X679737Y1139462D01*
G02X679665Y1139523I90J179D01*
G01X679650Y1139544D01*
X679631Y1139593D01*
X679629Y1139619D01*
G02X679645Y1139721I199J21D01*
G01X679649Y1139730D01*
G02X679665Y1139760I184J-79D01*
G01X679699Y1139810D01*
X679711Y1139823D01*
G03X680040Y1140649I-872J826D01*
G03X678838Y1141851I-1202J0D01*
G03X677636Y1140675I0J-1202D01*
G01Y1140648D01*
G03X677966Y1139821I1202J0D01*
G01X677978Y1139809D01*
X678019Y1139748D01*
X678037Y1139707D01*
G02Y1139574I-189J-66D01*
G01X677983Y1139493D01*
G02X677979Y1139489I-143J139D01*
G01X677960Y1139472D01*
X677893Y1139447D01*
X676172D01*
X676161Y1139445D01*
G03X676107Y1139441I62J-1200D01*
G01X676105D01*
G02X676014Y1139454I-18J199D01*
G01X675997Y1139462D01*
G02X675925Y1139523I90J179D01*
G01X675910Y1139544D01*
X675891Y1139593D01*
X675889Y1139619D01*
G02X675905Y1139721I199J21D01*
G01X675909Y1139730D01*
G02X675925Y1139760I184J-79D01*
G01X675959Y1139810D01*
X675971Y1139823D01*
G03X676300Y1140649I-872J826D01*
G03X675098Y1141851I-1202J0D01*
G03X673896Y1140675I0J-1202D01*
G01Y1140648D01*
G03X674226Y1139821I1202J0D01*
G01X674238Y1139809D01*
X674279Y1139748D01*
X674297Y1139707D01*
G02Y1139574I-189J-66D01*
G01X674243Y1139493D01*
G02X674239Y1139489I-143J139D01*
G01X674220Y1139472D01*
X674153Y1139447D01*
X672432D01*
X672421Y1139445D01*
G03X672367Y1139441I62J-1200D01*
G01X672365D01*
G02X672274Y1139454I-18J199D01*
G01X672257Y1139462D01*
G02X672185Y1139523I90J179D01*
G01X672170Y1139544D01*
X672151Y1139593D01*
X672149Y1139619D01*
G02X672165Y1139721I199J21D01*
G01X672169Y1139730D01*
G02X672185Y1139760I184J-79D01*
G01X672219Y1139810D01*
X672231Y1139823D01*
G03X672560Y1140649I-872J826D01*
G03X671358Y1141851I-1202J0D01*
G03X670156Y1140675I0J-1202D01*
G01Y1140648D01*
G03X670486Y1139821I1202J0D01*
G01X670498Y1139809D01*
X670539Y1139748D01*
X670557Y1139707D01*
G02Y1139574I-189J-66D01*
G01X670503Y1139493D01*
G02X670499Y1139489I-143J139D01*
G01X670480Y1139472D01*
X670413Y1139447D01*
X668692D01*
X668681Y1139445D01*
G03X668627Y1139441I62J-1200D01*
G01X668625D01*
G02X668534Y1139454I-18J199D01*
G01X668517Y1139462D01*
G02X668445Y1139523I90J179D01*
G01X668430Y1139544D01*
X668411Y1139593D01*
X668409Y1139619D01*
G02X668425Y1139721I199J21D01*
G01X668429Y1139730D01*
G02X668445Y1139760I184J-79D01*
G01X668479Y1139810D01*
X668491Y1139823D01*
G03X668820Y1140649I-872J826D01*
G03X667618Y1141851I-1202J0D01*
G03X666416Y1140675I0J-1202D01*
G01Y1140648D01*
G03X666746Y1139821I1202J0D01*
G01X666758Y1139809D01*
X666799Y1139748D01*
X666817Y1139707D01*
G02Y1139574I-189J-66D01*
G01X666763Y1139493D01*
G02X666759Y1139489I-143J139D01*
G01X666740Y1139472D01*
X666673Y1139447D01*
X664952D01*
X664941Y1139445D01*
G03X664887Y1139441I62J-1200D01*
G01X664885D01*
G02X664794Y1139454I-18J199D01*
G01X664777Y1139462D01*
G02X664705Y1139523I90J179D01*
G01X664690Y1139544D01*
X664671Y1139593D01*
X664669Y1139619D01*
G02X664685Y1139721I199J21D01*
G01X664689Y1139730D01*
G02X664705Y1139760I184J-79D01*
G01X664739Y1139810D01*
X664751Y1139823D01*
G03X665080Y1140649I-872J826D01*
G03X663878Y1141851I-1202J0D01*
G03X662676Y1140675I0J-1202D01*
G01Y1140648D01*
G03X663006Y1139821I1202J0D01*
G01X663018Y1139809D01*
X663059Y1139748D01*
X663077Y1139707D01*
G02Y1139574I-189J-66D01*
G01X663023Y1139493D01*
G02X663019Y1139489I-143J139D01*
G01X663000Y1139472D01*
X662933Y1139447D01*
X661212D01*
X661201Y1139445D01*
G03X661147Y1139441I62J-1200D01*
G01X661145D01*
G02X661054Y1139454I-18J199D01*
G01X661037Y1139462D01*
G02X660965Y1139523I90J179D01*
G01X660950Y1139544D01*
X660931Y1139593D01*
X660929Y1139619D01*
G02X660945Y1139721I199J21D01*
G01X660949Y1139730D01*
G02X660965Y1139760I184J-79D01*
G01X660999Y1139810D01*
X661011Y1139823D01*
G03X661340Y1140649I-872J826D01*
G03X660138Y1141851I-1202J0D01*
G03X658936Y1140675I0J-1202D01*
G01Y1140648D01*
G03X659266Y1139821I1202J0D01*
G01X659278Y1139809D01*
X659319Y1139748D01*
X659337Y1139707D01*
G02Y1139574I-189J-66D01*
G01X659283Y1139493D01*
G02X659279Y1139489I-143J139D01*
G01X659260Y1139472D01*
X659193Y1139447D01*
X657472D01*
X657461Y1139445D01*
G03X657407Y1139441I62J-1200D01*
G01X657405D01*
G02X657314Y1139454I-18J199D01*
G01X657297Y1139462D01*
G02X657225Y1139523I90J179D01*
G01X657210Y1139544D01*
X657191Y1139593D01*
X657189Y1139619D01*
G02X657205Y1139721I199J21D01*
G01X657209Y1139730D01*
G02X657225Y1139760I184J-79D01*
G01X657259Y1139810D01*
X657271Y1139823D01*
G03X657600Y1140649I-872J826D01*
G03X656398Y1141851I-1202J0D01*
G03X655196Y1140675I0J-1202D01*
G01Y1140648D01*
G03X655526Y1139821I1202J0D01*
G01X655538Y1139809D01*
X655579Y1139748D01*
X655597Y1139707D01*
G02Y1139574I-189J-66D01*
G01X655543Y1139493D01*
G02X655539Y1139489I-143J139D01*
G01X655520Y1139472D01*
X655453Y1139447D01*
X654040D01*
X654012Y1139448D01*
G02X653875Y1139538I32J198D01*
G01X653783Y1139696D01*
Y1139698D01*
X653697Y1139848D01*
G02X653671Y1139949I174J99D01*
G01Y1140001D01*
X653683Y1140022D01*
X653697Y1140047D01*
G03X653859Y1140649I-1040J603D01*
G03X651455I-1202J0D01*
G03X651472Y1140449I1202J1D01*
G01X651471D01*
G03X652568Y1139450I1186J200D01*
G01X652605Y1139447D01*
X652637Y1139432D01*
G02X652695Y1139391I-84J-181D01*
G01X652739Y1139347D01*
G02X652797Y1139207I-142J-141D01*
G01Y1139168D01*
X652768Y1139096D01*
X652740Y1139068D01*
G03X652400Y1138288I862J-840D01*
G01X652399Y1138259D01*
X652391Y1138235D01*
G02X652364Y1138183I-189J65D01*
G01X652300Y1138095D01*
G02X652260Y1138053I-163J115D01*
G01X652239Y1138037D01*
X652212Y1138026D01*
G03X651540Y1137355I445J-1117D01*
G01Y1137354D01*
X651529Y1137327D01*
X651513Y1137306D01*
G02X651471Y1137266I-157J123D01*
G01X651383Y1137202D01*
G02X651331Y1137175I-117J162D01*
G01X651307Y1137167D01*
X651278Y1137166D01*
G03X650756Y1137016I63J-1201D01*
G03X650619Y1136928I579J-1053D01*
G03X650578Y1136896I719J-963D01*
G03X650499Y1136826I758J-935D01*
G01X650497Y1136824D01*
G02X650358Y1136768I-139J144D01*
G01X650320D01*
X650248Y1136798D01*
X650175Y1136871D01*
G02X650134Y1136929I140J142D01*
G01X650119Y1136961D01*
X650116Y1136998D01*
Y1136999D01*
G03X648917Y1138111I-1199J-90D01*
G03X647715Y1136909I0J-1202D01*
G03X648908Y1135707I1202J0D01*
G01X648922D01*
G03X649416Y1135815I-4J1202D01*
G01X649418Y1135816D01*
X649440Y1135826D01*
X649485Y1135835D01*
G02X649716Y1135686I37J-197D01*
G01X649720Y1135669D01*
G02X649722Y1135639I-198J-28D01*
G01X649721Y1135626D01*
G03X649719Y1135550I1201J-70D01*
G01Y1134802D01*
G02X649718Y1134782I-200J0D01*
G02X649225Y1134434I-398J40D01*
G03X648918Y1134471I-308J-1265D01*
G01X648916D01*
G03X647614Y1133169I0J-1302D01*
G03X647991Y1132253I1301J0D01*
G01X648012Y1132232D01*
X648039Y1132181D01*
X648046Y1132151D01*
G02X648033Y1132032I-196J-39D01*
G01X647994Y1131940D01*
Y1131938D01*
X647892Y1131694D01*
G02X647708Y1131571I-185J77D01*
G01X646431D01*
G03X646408Y1131570I-3J-200D01*
G01X646380Y1131567D01*
X646352Y1131572D01*
G02X646295Y1131591I34J197D01*
G01X646261Y1131609D01*
X646212Y1131664D01*
X646203Y1131686D01*
X646199Y1131697D01*
G03X646192Y1131714I-188J-68D01*
G01X646189Y1131720D01*
X646055Y1132043D01*
G02X646043Y1132111I188J68D01*
G01X646069Y1132175D01*
X646087Y1132218D01*
G02X646126Y1132279I185J-75D01*
G03X646478Y1133169I-949J890D01*
G03X643874I-1302J0D01*
G03X644251Y1132253I1301J0D01*
G01X644272Y1132232D01*
X644299Y1132181D01*
X644306Y1132151D01*
G02X644293Y1132032I-196J-39D01*
G01X644254Y1131940D01*
Y1131938D01*
X644152Y1131694D01*
G02X643968Y1131571I-185J77D01*
G01X642691D01*
G03X642668Y1131570I-3J-200D01*
G01X642640Y1131567D01*
X642612Y1131572D01*
G02X642555Y1131591I34J197D01*
G01X642521Y1131609D01*
X642472Y1131664D01*
X642463Y1131686D01*
X642459Y1131697D01*
G03X642452Y1131714I-188J-68D01*
G01X642449Y1131720D01*
X642315Y1132043D01*
G02X642303Y1132111I188J68D01*
G01X642329Y1132175D01*
X642347Y1132218D01*
G02X642386Y1132279I185J-75D01*
G03X642738Y1133169I-949J890D01*
G03X640134I-1302J0D01*
G03X640511Y1132253I1301J0D01*
G01X640532Y1132232D01*
X640559Y1132181D01*
X640566Y1132151D01*
G02X640553Y1132032I-196J-39D01*
G01X640514Y1131940D01*
Y1131938D01*
X640412Y1131694D01*
G02X640228Y1131571I-185J77D01*
G01X638951D01*
G03X638928Y1131570I-3J-200D01*
G01X638900Y1131567D01*
X638872Y1131572D01*
G02X638815Y1131591I34J197D01*
G01X638781Y1131609D01*
X638732Y1131664D01*
X638723Y1131686D01*
X638719Y1131697D01*
G03X638712Y1131714I-188J-68D01*
G01X638709Y1131720D01*
X638575Y1132043D01*
G02X638563Y1132111I188J68D01*
G01X638589Y1132175D01*
X638607Y1132218D01*
G02X638646Y1132279I185J-75D01*
G03X638998Y1133169I-949J890D01*
G03X636394I-1302J0D01*
G03X636771Y1132253I1301J0D01*
G01X636792Y1132232D01*
X636819Y1132181D01*
X636826Y1132151D01*
G02X636813Y1132032I-196J-39D01*
G01X636774Y1131940D01*
Y1131938D01*
X636672Y1131694D01*
G02X636488Y1131571I-185J77D01*
G01X635211D01*
G03X635188Y1131570I-3J-200D01*
G01X635160Y1131567D01*
X635132Y1131572D01*
G02X635075Y1131591I34J197D01*
G01X635041Y1131609D01*
X634992Y1131664D01*
X634983Y1131686D01*
X634979Y1131697D01*
G03X634972Y1131714I-188J-68D01*
G01X634969Y1131720D01*
X634835Y1132043D01*
G02X634823Y1132111I188J68D01*
G01X634849Y1132175D01*
X634867Y1132218D01*
G02X634906Y1132279I185J-75D01*
G03X635258Y1133169I-949J890D01*
G03X632654I-1302J0D01*
G03X633031Y1132253I1301J0D01*
G01X633052Y1132232D01*
X633079Y1132181D01*
X633086Y1132151D01*
G02X633073Y1132032I-196J-39D01*
G01X633034Y1131940D01*
Y1131938D01*
X632932Y1131694D01*
G02X632748Y1131571I-185J77D01*
G01X620250D01*
G03X620227Y1131570I-3J-200D01*
G01X620199Y1131567D01*
X620171Y1131572D01*
G02X620114Y1131591I34J197D01*
G01X620080Y1131609D01*
X620031Y1131664D01*
X620022Y1131686D01*
X620018Y1131697D01*
G03X620011Y1131714I-188J-68D01*
G01X620008Y1131720D01*
X619874Y1132043D01*
G02X619862Y1132111I188J68D01*
G01X619888Y1132175D01*
X619906Y1132218D01*
G02X619945Y1132279I185J-75D01*
G03X620297Y1133169I-949J890D01*
G03X617693I-1302J0D01*
G03X618070Y1132253I1301J0D01*
G01X618091Y1132232D01*
X618118Y1132181D01*
X618125Y1132151D01*
G02X618112Y1132032I-196J-39D01*
G01X618073Y1131940D01*
Y1131938D01*
X617971Y1131694D01*
G02X617787Y1131571I-185J77D01*
G01X609030D01*
G03X609007Y1131570I-3J-200D01*
G01X608979Y1131567D01*
X608951Y1131572D01*
G02X608894Y1131591I34J197D01*
G01X608860Y1131609D01*
X608811Y1131664D01*
X608802Y1131686D01*
X608798Y1131697D01*
G03X608791Y1131714I-188J-68D01*
G01X608788Y1131720D01*
X608654Y1132043D01*
G02X608642Y1132111I188J68D01*
G01X608668Y1132175D01*
X608686Y1132218D01*
G02X608725Y1132279I185J-75D01*
G03X609077Y1133169I-949J890D01*
G03X606473I-1302J0D01*
G03X606850Y1132253I1301J0D01*
G01X606871Y1132232D01*
X606898Y1132181D01*
X606905Y1132151D01*
G02X606892Y1132032I-196J-39D01*
G01X606853Y1131940D01*
Y1131938D01*
X606751Y1131694D01*
G02X606567Y1131571I-185J77D01*
G01X605289D01*
G03X605266Y1131570I-3J-200D01*
G01X605238Y1131567D01*
X605210Y1131572D01*
G02X605153Y1131591I34J197D01*
G01X605119Y1131609D01*
X605070Y1131664D01*
X605061Y1131686D01*
X605057Y1131697D01*
G03X605050Y1131714I-188J-68D01*
G01X605047Y1131720D01*
X604913Y1132043D01*
G02X604901Y1132111I188J68D01*
G01X604927Y1132175D01*
X604945Y1132218D01*
G02X604984Y1132279I185J-75D01*
G03X605336Y1133169I-949J890D01*
G03X602732I-1302J0D01*
G03X603109Y1132253I1301J0D01*
G01X603130Y1132232D01*
X603157Y1132181D01*
X603164Y1132151D01*
G02X603151Y1132032I-196J-39D01*
G01X603112Y1131940D01*
Y1131938D01*
X603010Y1131694D01*
G02X602826Y1131571I-185J77D01*
G01X601549D01*
G03X601526Y1131570I-3J-200D01*
G01X601498Y1131567D01*
X601470Y1131572D01*
G02X601413Y1131591I34J197D01*
G01X601379Y1131609D01*
X601330Y1131664D01*
X601321Y1131686D01*
X601317Y1131697D01*
G03X601310Y1131714I-188J-68D01*
G01X601307Y1131720D01*
X601173Y1132043D01*
G02X601161Y1132111I188J68D01*
G01X601187Y1132175D01*
X601205Y1132218D01*
G02X601244Y1132279I185J-75D01*
G03X601596Y1133169I-949J890D01*
G03X598992I-1302J0D01*
G03X599369Y1132253I1301J0D01*
G01X599390Y1132232D01*
X599417Y1132181D01*
X599424Y1132151D01*
G02X599411Y1132032I-196J-39D01*
G01X599372Y1131940D01*
Y1131938D01*
X599270Y1131694D01*
G02X599086Y1131571I-185J77D01*
G01X591799D01*
X591767Y1131579D01*
X591702Y1131596D01*
X591680Y1131608D01*
G03X590957Y1131793I-722J-1317D01*
G01X590955D01*
G03X590243Y1131613I1J-1501D01*
G01X590232Y1131607D01*
X590200Y1131595D01*
X590189Y1131591D01*
X590138Y1131577D01*
G02X590090Y1131571I-49J194D01*
G01X588309D01*
X588277Y1131579D01*
X588212Y1131596D01*
X588190Y1131608D01*
G03X587467Y1131793I-722J-1317D01*
G01X587465D01*
G03X586753Y1131613I1J-1501D01*
G01X586742Y1131607D01*
X586710Y1131595D01*
X586699Y1131591D01*
X586648Y1131577D01*
G02X586600Y1131571I-49J194D01*
G01X582809D01*
X582777Y1131579D01*
X582712Y1131596D01*
X582690Y1131608D01*
G03X581967Y1131793I-722J-1317D01*
G01X581965D01*
G03X581253Y1131613I1J-1501D01*
G01X581242Y1131607D01*
X581210Y1131595D01*
X581199Y1131591D01*
X581148Y1131577D01*
G02X581100Y1131571I-49J194D01*
G01X539006D01*
G02X538915Y1131593I0J200D01*
G02X538865Y1131629I90J178D01*
G01X536869Y1133625D01*
G02X536833Y1133675I142J140D01*
G02X536811Y1133766I178J91D01*
G01Y1154338D01*
G03X536752Y1154480I-200J0D01*
G01X533946Y1157286D01*
G03X533804Y1157345I-142J-141D01*
G01X468988D01*
G02X468897Y1157367I0J200D01*
G02X468847Y1157403I90J178D01*
G01X467896Y1158354D01*
G02X467860Y1158404I142J140D01*
G02X467838Y1158495I178J91D01*
G01Y1233766D01*
G02X467860Y1233857I200J0D01*
G02X467896Y1233907I178J-90D01*
G01X467897Y1233908D01*
X467866Y1233992D01*
G02X467857Y1234037I190J61D01*
G02X467856Y1234054I199J20D01*
G01Y1290947D01*
G02X467860Y1290985I200J-2D01*
G02X467913Y1291087I196J-37D01*
G01X470754Y1293928D01*
G02X470856Y1293981I139J-143D01*
G02X470894Y1293985I40J-196D01*
G01X518827D01*
G02X518860Y1293982I-2J-200D01*
G02X518967Y1293928I-32J-197D01*
G01X533642Y1279253D01*
G03X533784Y1279194I142J141D01*
G01X562358D01*
G02X562596Y1278473I0J-400D01*
G03X555016Y1263388I11222J-15086D01*
G01Y1263386D01*
G03X592620I18802J0D01*
G01Y1263387D01*
G03X589533Y1273708I-18802J-1D01*
G02X589501Y1273829I168J109D01*
G01X589502Y1273861D01*
X589525Y1273919D01*
X589790Y1274241D01*
G02X589896Y1274308I154J-127D01*
G01X589959Y1274324D01*
X590000Y1274307D01*
X590021Y1274298D01*
X612187Y1265116D01*
X612208Y1265108D01*
X615119Y1263083D01*
G02X615146Y1263061I-112J-165D01*
G01X618938Y1259269D01*
G02X618991Y1259167I-143J-139D01*
G02X618995Y1259129I-196J-40D01*
G01Y1257982D01*
G02X618947Y1257852I-200J0D01*
G01X618923Y1257824D01*
X618861Y1257789D01*
X618836Y1257786D01*
X618823Y1257784D01*
G03X618797Y1257780I170J-1190D01*
G03X618774Y1257776I194J-1186D01*
G01X618725Y1257767D01*
X618630Y1257796D01*
X618362Y1258065D01*
G02X618307Y1258242I142J141D01*
G01Y1258243D01*
G03X618328Y1258465I-1181J224D01*
G03X617126Y1257263I-1202J0D01*
G03X617347Y1257283I3J1202D01*
G01X617396Y1257292D01*
X617491Y1257263D01*
X617794Y1256959D01*
X617823Y1256866D01*
X617820Y1256846D01*
G03X617806Y1256419I1175J-252D01*
G01Y1256415D01*
X617809Y1256393D01*
X617778Y1256303D01*
X617477Y1256014D01*
X617387Y1255986D01*
X617340Y1255994D01*
G03X617126Y1256012I-215J-1270D01*
G03Y1253436I0J-1288D01*
G03X617340Y1253454I-1J1288D01*
G01X617387Y1253462D01*
X617477Y1253434D01*
X617778Y1253145D01*
X617809Y1253055D01*
X617806Y1253032D01*
G03Y1252679I1189J-176D01*
G01Y1252675D01*
X617809Y1252653D01*
X617778Y1252563D01*
X617477Y1252274D01*
X617387Y1252246D01*
X617340Y1252254D01*
G03X617126Y1252272I-215J-1270D01*
G03Y1249696I0J-1288D01*
G03X617259Y1249703I-1J1288D01*
G01X617260D01*
G02X617422Y1249645I20J-199D01*
G01X617641Y1249424D01*
G02X617698Y1249261I-142J-141D01*
G01Y1249260D01*
G03X617690Y1249113I1294J-144D01*
G01Y1248837D01*
G02X617624Y1248688I-200J0D01*
G01X617404Y1248490D01*
G02X617250Y1248439I-134J148D01*
G01X617249D01*
G03X617126Y1248445I-120J-1196D01*
G03Y1246041I0J-1202D01*
G03X617249Y1246047I3J1202D01*
G01X617250D01*
G02X617404Y1245996I20J-199D01*
G01X617624Y1245798D01*
G02X617690Y1245649I-134J-149D01*
G01Y1245373D01*
G03X617712Y1245134I1302J-1D01*
G02X617713Y1245128I-196J-36D01*
G01X617716Y1245112D01*
X617688Y1245023D01*
X617435Y1244758D01*
G02X617266Y1244697I-145J137D01*
G03X617126Y1244705I-138J-1194D01*
G03Y1242301I0J-1202D01*
G03X617346Y1242322I-4J1202D01*
G01X617348D01*
G02X617525Y1242267I36J-197D01*
G01X617794Y1241997D01*
X617823Y1241904D01*
X617817Y1241872D01*
G03X617816Y1241400I1178J-238D01*
G01Y1241398D01*
X617823Y1241362D01*
X617794Y1241269D01*
X617525Y1240999D01*
G02X617348Y1240944I-141J142D01*
G01X617347D01*
G03X617126Y1240965I-224J-1181D01*
G03Y1238561I0J-1202D01*
G03X617269Y1238569I4J1202D01*
G01X617316Y1238575D01*
X617404Y1238543D01*
X617691Y1238243D01*
X617719Y1238154D01*
X617715Y1238130D01*
G03X617693Y1237893I1280J-238D01*
G03X617701Y1237746I1302J-3D01*
G01X617706Y1237701D01*
X617677Y1237615D01*
X617392Y1237329D01*
X617307Y1237298D01*
X617262Y1237303D01*
G03X617126Y1237310I-134J-1280D01*
G03Y1234736I0J-1287D01*
G03X617262Y1234743I2J1287D01*
G01X617307Y1234748D01*
X617392Y1234717D01*
X617677Y1234431D01*
X617706Y1234345D01*
X617701Y1234300D01*
G03X617693Y1234153I1294J-144D01*
G03X617701Y1234006I1302J-3D01*
G01X617706Y1233961D01*
X617677Y1233875D01*
X617392Y1233589D01*
X617307Y1233558D01*
X617262Y1233563D01*
G03X617126Y1233570I-134J-1280D01*
G03Y1230996I0J-1287D01*
G03X617262Y1231003I2J1287D01*
G01X617307Y1231008D01*
X617392Y1230977D01*
X617677Y1230691D01*
X617706Y1230605D01*
X617701Y1230560D01*
G03X617693Y1230413I1294J-144D01*
G03X617715Y1230178I1302J3D01*
G01Y1230174D01*
X617719Y1230152D01*
X617691Y1230063D01*
X617404Y1229763D01*
X617316Y1229731D01*
X617269Y1229737D01*
G03X617126Y1229745I-139J-1194D01*
G03Y1227341I0J-1202D01*
G03X617268Y1227349I3J1202D01*
G01X617315Y1227355D01*
X617403Y1227323D01*
X617690Y1227023D01*
X617718Y1226934D01*
X617714Y1226908D01*
G03X617692Y1226672I1281J-238D01*
G01Y1226396D01*
G02X617626Y1226247I-200J0D01*
G01X617374Y1226020D01*
X617292Y1225994D01*
X617251Y1225999D01*
G03X617126Y1226005I-120J-1196D01*
G03Y1223601I0J-1202D01*
G03X617251Y1223607I5J1202D01*
G01X617292Y1223612D01*
X617374Y1223586D01*
X617626Y1223359D01*
G02X617692Y1223210I-134J-149D01*
G01Y1222932D01*
G03X617714Y1222696I1303J2D01*
G01Y1222692D01*
X617718Y1222671D01*
X617690Y1222582D01*
X617403Y1222282D01*
X617315Y1222250D01*
X617268Y1222256D01*
G03X617126Y1222264I-139J-1194D01*
G03X618328Y1221062I0J-1202D01*
G03X618258Y1221466I-1201J0D01*
G02X618253Y1221484I190J62D01*
G02X618512Y1221722I194J49D01*
G03X618611Y1221687I483J1210D01*
G01X618612D01*
X618622Y1221684D01*
G03X618655Y1221674I394J1241D01*
G03X618669Y1221670I365J1250D01*
G01X618685Y1221666D01*
G03X618995Y1221630I304J1267D01*
G01X618996D01*
G03X619377Y1221687I0J1302D01*
G03X619458Y1221714I-371J1249D01*
G02X619490Y1221723I70J-187D01*
G01X619546Y1221734D01*
G02X619746Y1221534I0J-200D01*
G01X619737Y1221483D01*
G02X619729Y1221453I-197J36D01*
G03X619664Y1221064I1137J-390D01*
G01Y1221062D01*
G03X620866Y1219860I1202J0D01*
G03X621009Y1219868I4J1202D01*
G01X621056Y1219874D01*
X621144Y1219842D01*
X621431Y1219542D01*
X621459Y1219453D01*
X621455Y1219429D01*
G03X621433Y1219192I1280J-238D01*
G03X621441Y1219045I1302J-3D01*
G01X621446Y1219000D01*
X621417Y1218914D01*
X621132Y1218628D01*
X621047Y1218597D01*
X621002Y1218602D01*
G03X620867Y1218610I-144J-1280D01*
G01X620865D01*
G03X619578Y1217322I1J-1288D01*
G03X620866Y1216034I1288J0D01*
G03X622154Y1217321I0J1288D01*
G01Y1217323D01*
G03X622146Y1217457I-1288J-10D01*
G01Y1217459D01*
X622141Y1217504D01*
X622172Y1217589D01*
X622458Y1217874D01*
X622544Y1217903D01*
X622589Y1217898D01*
G03X622735Y1217890I144J1294D01*
G03X622883Y1217898I4J1302D01*
G01X622928Y1217903D01*
X623014Y1217874D01*
X623300Y1217589D01*
X623331Y1217504D01*
X623326Y1217459D01*
G03X623318Y1217323I1280J-144D01*
G01Y1217321D01*
G03X625894I1288J1D01*
G01Y1217323D01*
G03X625886Y1217457I-1288J-10D01*
G01Y1217459D01*
X625881Y1217504D01*
X625912Y1217589D01*
X626198Y1217874D01*
X626284Y1217903D01*
X626329Y1217898D01*
G03X626475Y1217890I144J1294D01*
G37*
G36*
G01X492454Y651418D02*
X537679D01*
G02X537819Y651361I0J-200D01*
G01X537820Y651360D01*
X545656Y643524D01*
G02X545658Y643522I-140J-142D01*
G02X545715Y643382I-143J-140D01*
G01Y607266D01*
G02X545635Y607105I-200J-1D01*
G01X545339Y606885D01*
X545246Y606868D01*
X545200Y606882D01*
G03X544770Y606945I-430J-1439D01*
G03Y603941I0J-1502D01*
G03X545200Y604004I0J1502D01*
G01X545246Y604018D01*
X545339Y604001D01*
X545635Y603781D01*
G02X545715Y603620I-120J-160D01*
G01Y583471D01*
G02X545633Y583310I-200J0D01*
G01X545333Y583091D01*
X545239Y583076D01*
X545193Y583090D01*
G03X544738Y583161I-456J-1431D01*
G03Y580157I0J-1502D01*
G03X545193Y580228I-1J1502D01*
G01X545239Y580242D01*
X545333Y580227D01*
X545633Y580008D01*
G02X545715Y579847I-118J-161D01*
G01Y451459D01*
G02X545656Y451317I-200J0D01*
G01X534251Y439913D01*
G02X534109Y439854I-142J141D01*
G01X505347D01*
X505233Y439960D01*
X505226Y440038D01*
G03X502232I-1497J-119D01*
G01X502225Y439960D01*
X502111Y439854D01*
X497433D01*
G02X497291Y439913I0J200D01*
G01X485186Y452018D01*
G02X485128Y452159I142J141D01*
G01Y619767D01*
X485202Y619870D01*
X485263Y619891D01*
G03Y622731I-492J1420D01*
G01X485202Y622752D01*
X485128Y622855D01*
Y623767D01*
X485202Y623870D01*
X485263Y623891D01*
G03Y626731I-492J1420D01*
G01X485202Y626752D01*
X485128Y626855D01*
Y627767D01*
X485202Y627870D01*
X485263Y627891D01*
G03Y630731I-492J1420D01*
G01X485202Y630752D01*
X485128Y630855D01*
Y644092D01*
G02X485187Y644234I200J0D01*
G01X492312Y651359D01*
G02X492314Y651361I142J-140D01*
G02X492454Y651418I140J-143D01*
G37*
G36*
G01X486463Y819787D02*
G03I-639J0D01*
G37*
G36*
G01X482232Y826387D02*
G03I-639J0D01*
G37*
G36*
G01X475610Y843252D02*
G03I-577J0D01*
G37*
G36*
G01X489047Y857013D02*
G03I-577J0D01*
G37*
G36*
G01X475256Y857919D02*
G03I-577J0D01*
G37*
G36*
G01X475624Y885952D02*
G03I-577J0D01*
G37*
G36*
G01X484214Y952152D02*
G03I-577J0D01*
G37*
G36*
G01X504980Y812040D02*
G03I-639J0D01*
G37*
G36*
G01X492294Y829173D02*
G03I-639J0D01*
G37*
G36*
G01X506885Y824689D02*
G03I-639J0D01*
G37*
G36*
G01X492092Y834546D02*
G03I-639J0D01*
G37*
G36*
G01X493438Y846488D02*
G03I-639J0D01*
G37*
G36*
G01X500279Y861538D02*
G03I-639J0D01*
G37*
G36*
G01X500173Y963963D02*
G03I-577J0D01*
G37*
G36*
G01X521488Y704864D02*
X527509D01*
G02X527651Y704805I0J-200D01*
G01X527942Y704514D01*
G02X528001Y704372I-141J-142D01*
G01Y694482D01*
G02X527942Y694340I-200J0D01*
G01X527574Y693972D01*
G02X527432Y693913I-142J141D01*
G01X517562D01*
G02X517420Y693972I0J200D01*
G01X517067Y694325D01*
G02X517008Y694467I141J142D01*
G01Y695264D01*
X517017Y695292D01*
G03Y696222I-1532J465D01*
G01X517008Y696250D01*
Y700800D01*
X517019Y700831D01*
G03X517106Y701351I-1515J521D01*
G03X517019Y701871I-1602J-1D01*
G01X517008Y701902D01*
Y703474D01*
G02X517067Y703616I200J0D01*
G01X518256Y704805D01*
G02X518398Y704864I142J-141D01*
G01X520780D01*
X520800Y704860D01*
G03X521134Y704824I338J1566D01*
G03X521468Y704860I-4J1602D01*
G01X521488Y704864D01*
G37*
G36*
G01X509702Y782867D02*
G03I-639J0D01*
G37*
G36*
G01X508769Y787488D02*
G03I-639J0D01*
G37*
G36*
G01X508688Y877789D02*
G03I-639J0D01*
G37*
G36*
G01X510067Y888390D02*
G03I-639J0D01*
G37*
G36*
G01X511664Y911443D02*
G03I-639J0D01*
G37*
G36*
G01X516834Y939157D02*
G03I-577J0D01*
G37*
G36*
G01X515464Y952189D02*
G03I-577J0D01*
G37*
G36*
G01X594744Y54588D02*
X623251D01*
X623486Y54353D01*
Y52826D01*
X623251Y52591D01*
X594744D01*
G03X588807Y46654I0J-5937D01*
G01Y7874D01*
G02X582933Y2000I-5874J0D01*
G01X535689D01*
G02X529815Y7874I0J5874D01*
G01Y45747D01*
X531812D01*
Y7874D01*
G03X535687Y3998I3876J0D01*
G01X582933D01*
G03X586810Y7874I0J3877D01*
G01Y46654D01*
G02X594744Y54588I7934J0D01*
G37*
G36*
G01X550275Y758128D02*
Y770128D01*
X549775Y770628D01*
X535275D01*
X534275Y769628D01*
Y758628D01*
X535275Y757628D01*
X549775D01*
X550275Y758128D01*
G37*
G36*
G01X528372Y847026D02*
G03I-639J0D01*
G37*
G36*
G01X605595Y1130192D02*
X647357D01*
G02X647513Y1130116I-1J-200D01*
G01X647737Y1129835D01*
X647757Y1129747D01*
X647746Y1129701D01*
G03X647715Y1129429I1171J-271D01*
G03X648917Y1128227I1202J0D01*
G03X649279Y1128283I-1J1202D01*
G01X649326Y1128298D01*
X649419Y1128282D01*
X649718Y1128063D01*
G02X649800Y1127902I-118J-161D01*
G01Y1115995D01*
G02X649718Y1115834I-200J0D01*
G01X649419Y1115615D01*
X649326Y1115599D01*
X649279Y1115614D01*
G03X648917Y1115670I-363J-1146D01*
G03Y1113266I0J-1202D01*
G03X649279Y1113322I-1J1202D01*
G01X649326Y1113337D01*
X649419Y1113321D01*
X649718Y1113102D01*
G02X649800Y1112941I-118J-161D01*
G01Y1109778D01*
G02X649758Y1109656I-200J1D01*
G03Y1108060I1030J-798D01*
G02X649800Y1107938I-158J-123D01*
G01Y1106013D01*
G02X649760Y1105893I-200J0D01*
G03Y1104341I1028J-776D01*
G02X649800Y1104221I-160J-120D01*
G01Y1102272D01*
G02X649760Y1102152I-200J0D01*
G03Y1100600I1028J-776D01*
G02X649800Y1100480I-160J-120D01*
G01Y1098557D01*
G02X649758Y1098435I-200J1D01*
G03Y1096839I1030J-798D01*
G02X649800Y1096717I-158J-123D01*
G01Y1094817D01*
G02X649758Y1094695I-200J1D01*
G03Y1093099I1030J-798D01*
G02X649800Y1092977I-158J-123D01*
G01Y1091077D01*
G02X649758Y1090955I-200J1D01*
G03Y1089359I1030J-798D01*
G02X649800Y1089237I-158J-123D01*
G01Y1087313D01*
G02X649760Y1087193I-200J0D01*
G03Y1085641I1028J-776D01*
G02X649800Y1085521I-160J-120D01*
G01Y1083573D01*
G02X649760Y1083453I-200J0D01*
G03Y1081901I1028J-776D01*
G02X649800Y1081781I-160J-120D01*
G01Y1079856D01*
G02X649758Y1079734I-200J1D01*
G03Y1078138I1030J-798D01*
G02X649800Y1078016I-158J-123D01*
G01Y1076116D01*
G02X649758Y1075994I-200J1D01*
G03Y1074398I1030J-798D01*
G02X649800Y1074276I-158J-123D01*
G01Y1060945D01*
G02X649741Y1060803I-200J0D01*
G01X649713Y1060775D01*
G03X649654Y1060633I141J-142D01*
G01Y1043154D01*
G02X649595Y1043012I-200J0D01*
G01X646886Y1040303D01*
X646811Y1040273D01*
X646769Y1040275D01*
G03X646706Y1040276I-68J-2306D01*
G01X618345D01*
G03X616714Y1039600I1J-2307D01*
G01X616428Y1039314D01*
G02X616286Y1039255I-142J141D01*
G01X615707D01*
G03X615565Y1039196I0J-200D01*
G01X613640Y1037271D01*
G03X613581Y1037129I141J-142D01*
G01Y1036550D01*
G02X613522Y1036408I-200J0D01*
G01X612866Y1035752D01*
G03X612190Y1034121I1631J-1632D01*
G01Y1013145D01*
G03X612866Y1011514I2307J1D01*
G01X618913Y1005467D01*
G02X618972Y1005326I-141J-142D01*
G01Y983331D01*
G02X618913Y983190I-200J1D01*
G01X616906Y981183D01*
G02X616765Y981124I-142J141D01*
G01X588406D01*
G03X586775Y980449I-1J-2306D01*
G01X586236Y979910D01*
G02X586095Y979852I-141J142D01*
G01X562815D01*
G02X562667Y979917I0J200D01*
G01X562439Y980169D01*
X562413Y980249D01*
X562417Y980292D01*
G03X562425Y980443I-1494J155D01*
G03X559421I-1502J0D01*
G03X559429Y980292I1502J4D01*
G01X559433Y980249D01*
X559407Y980169D01*
X559179Y979917D01*
G02X559031Y979852I-148J135D01*
G01X558805D01*
G02X558654Y979921I0J200D01*
G01X558427Y980183D01*
X558403Y980265D01*
X558410Y980309D01*
G03X558425Y980523I-1487J212D01*
G03X555421I-1502J0D01*
G03X555436Y980309I1502J-2D01*
G01X555443Y980265D01*
X555419Y980183D01*
X555192Y979921D01*
G02X555041Y979852I-151J131D01*
G01X542201D01*
G02X542060Y979910I0J200D01*
G01X541977Y979993D01*
G02X541918Y980135I141J142D01*
G01Y983225D01*
G02X541943Y983322I200J0D01*
G03X542194Y984293I-1750J970D01*
G01Y996615D01*
G02X542261Y996764I200J0D01*
G01X542513Y996992D01*
X542593Y997018D01*
X542636Y997013D01*
G03X542793Y997005I155J1494D01*
G03Y1000009I0J1502D01*
G03X542636Y1000001I-2J-1502D01*
G01X542593Y999996D01*
X542513Y1000022D01*
X542261Y1000250D01*
G02X542194Y1000399I133J149D01*
G01Y1005762D01*
G02X542253Y1005904I200J0D01*
G01X542958Y1006608D01*
G02X543110Y1006667I142J-141D01*
G01X543450Y1006649D01*
X543524Y1006611D01*
X543551Y1006577D01*
G03X544719Y1006020I1168J946D01*
G03X546221Y1007522I0J1502D01*
G03X546212Y1007690I-1502J4D01*
G01X546207Y1007730D01*
X546229Y1007806D01*
X546456Y1008090D01*
X546526Y1008128D01*
X546566Y1008132D01*
G03X547764Y1008707I-218J1990D01*
G01X556111Y1017054D01*
G03X556698Y1018469I-1415J1416D01*
G03X554696Y1020470I-2001J0D01*
G03X553281Y1019884I0J-2001D01*
G01X547228Y1013832D01*
G02X547032Y1013781I-141J141D01*
G01X546643Y1013891D01*
X546568Y1013970D01*
X546556Y1014023D01*
G03X545094Y1015180I-1462J-345D01*
G03X543592Y1013678I0J-1502D01*
G03X544185Y1012483I1502J1D01*
G01X544222Y1012454D01*
X544263Y1012371D01*
Y1012324D01*
G02X544063Y1012124I-200J0D01*
G01X543641D01*
G03X542538Y1011792I1J-2002D01*
G01X542492Y1011762D01*
X542382Y1011757D01*
X542023Y1011950D01*
G02X541918Y1012126I95J176D01*
G01Y1016774D01*
X542007Y1016884D01*
X542077Y1016898D01*
G03Y1019838I-312J1470D01*
G01X542007Y1019852D01*
X541918Y1019962D01*
Y1024130D01*
G02X542118Y1024330I200J0D01*
G01X543674D01*
G02X543823Y1024263I0J-200D01*
G01X544051Y1024011D01*
X544077Y1023931D01*
X544072Y1023888D01*
G03X544064Y1023731I1494J-155D01*
G03X547068I1502J0D01*
G03X547060Y1023888I-1502J2D01*
G01X547055Y1023931D01*
X547081Y1024011D01*
X547309Y1024263D01*
G02X547458Y1024330I149J-133D01*
G01X548472D01*
G02X548613Y1024271I-1J-200D01*
G01X550328Y1022555D01*
G03X551673Y1021998I1345J1345D01*
G03X553574Y1023900I0J1901D01*
G03X553018Y1025245I-1902J1D01*
G01X550687Y1027576D01*
G03X549342Y1028132I-1344J-1346D01*
G01X542118D01*
G02X541918Y1028332I0J200D01*
G01Y1055290D01*
G03X541859Y1055432I-200J0D01*
G01X536743Y1060548D01*
G02X536684Y1060690I141J142D01*
G01Y1073160D01*
G02X536877Y1073360I200J0D01*
G03Y1099948I-459J13294D01*
G02X536684Y1100148I7J200D01*
G01Y1128697D01*
G02X536743Y1128839I200J0D01*
G01X538037Y1130133D01*
G02X538179Y1130192I142J-141D01*
G01X580365D01*
X580475Y1130099D01*
X580488Y1130027D01*
G03X581062Y1129093I1478J265D01*
G01X581099Y1129064D01*
X581140Y1128983D01*
X581146Y1128574D01*
X581107Y1128491D01*
X581071Y1128462D01*
G03X580510Y1127291I942J-1171D01*
G03X583514I1502J0D01*
G03X582917Y1128489I-1502J-1D01*
G01X582880Y1128518D01*
X582839Y1128599D01*
X582833Y1129008D01*
X582872Y1129091D01*
X582908Y1129120D01*
G03X583446Y1130027I-941J1171D01*
G01X583459Y1130099D01*
X583569Y1130192D01*
X585865D01*
X585975Y1130099D01*
X585988Y1130027D01*
G03X588946I1479J264D01*
G01X588959Y1130099D01*
X589069Y1130192D01*
X589355D01*
X589465Y1130099D01*
X589478Y1130027D01*
G03X592436I1479J264D01*
G01X592449Y1130099D01*
X592559Y1130192D01*
X598735D01*
G02X598891Y1130116I-1J-200D01*
G01X599115Y1129835D01*
X599135Y1129747D01*
X599124Y1129701D01*
G03X599093Y1129429I1171J-271D01*
G03X601497I1202J0D01*
G03X601466Y1129701I-1202J1D01*
G01X601455Y1129747D01*
X601475Y1129835D01*
X601699Y1130116D01*
G02X601855Y1130192I157J-124D01*
G01X602475D01*
G02X602631Y1130116I-1J-200D01*
G01X602855Y1129835D01*
X602875Y1129747D01*
X602864Y1129701D01*
G03X602833Y1129429I1171J-271D01*
G03X605237I1202J0D01*
G03X605206Y1129701I-1202J1D01*
G01X605195Y1129747D01*
X605215Y1129835D01*
X605439Y1130116D01*
G02X605595Y1130192I157J-124D01*
G37*
G36*
G01X749904Y1250416D02*
X749900D01*
G03X749765Y1250409I0J-1304D01*
G01X749720Y1250404D01*
X749635Y1250434D01*
X749383Y1250686D01*
G02X749326Y1250849I142J141D01*
G01Y1250854D01*
G03X749333Y1250979I-1295J135D01*
G01Y1251015D01*
X749332Y1251021D01*
Y1251026D01*
G03X748561Y1252173I-1301J-42D01*
G01X748506Y1252198D01*
X748442Y1252296D01*
Y1253412D01*
X748506Y1253510D01*
X748561Y1253535D01*
G03Y1255913I-530J1189D01*
G01X748506Y1255938D01*
X748442Y1256036D01*
Y1258600D01*
X748446Y1258620D01*
X748456Y1258674D01*
X748462Y1258692D01*
G03X748722Y1260089I-3631J1398D01*
G01Y1266059D01*
X748723Y1266066D01*
X748724Y1266086D01*
Y1266088D01*
G03X748428Y1267577I-3893J0D01*
G01X744560Y1276919D01*
X744559Y1276920D01*
X744544Y1276957D01*
G03X744105Y1277755I-3607J-1465D01*
G01X744104Y1277756D01*
X744099Y1277763D01*
X744096Y1277768D01*
G03X743546Y1278457I-3324J-2089D01*
G01X736508Y1285495D01*
G03X735913Y1285984I-2778J-2774D01*
G01X720106Y1296545D01*
G03X719874Y1296689I-2186J-3262D01*
G03X719776Y1296743I-1944J-3412D01*
G01X719751Y1296756D01*
X719610Y1296831D01*
X719607Y1296834D01*
G03X719465Y1296913I-1963J-3361D01*
G01X706020Y1304107D01*
G02X706007Y1304115I98J174D01*
G01X587905Y1379384D01*
X587856Y1379473D01*
Y1423718D01*
G03X587797Y1423860I-200J0D01*
G01X583140Y1428517D01*
G03X582998Y1428576I-142J-141D01*
G01X565239D01*
G02X565097Y1428635I0J200D01*
G01X548498Y1445234D01*
G02X548481Y1445253I140J143D01*
G02X548459Y1445289I159J122D01*
G01X538781Y1465189D01*
G02X538761Y1465276I180J87D01*
G01Y1548028D01*
G02X538820Y1548170I200J0D01*
G01X540240Y1549590D01*
G02X540382Y1549649I142J-141D01*
G01X607166D01*
G03X607308Y1549708I0J200D01*
G01X608511Y1550911D01*
G03X608570Y1551053I-141J142D01*
G01Y1638971D01*
G02X608627Y1639111I200J0D01*
G01X610209Y1640693D01*
G02X610351Y1640752I142J-141D01*
G01X789334D01*
G02X789367Y1640749I-2J-200D01*
G02X789474Y1640695I-32J-197D01*
G01X792439Y1637730D01*
G03X792581Y1637671I142J141D01*
G01X1072517D01*
G02X1072659Y1637612I0J-200D01*
G01X1073883Y1636388D01*
G02X1073885Y1636386I-140J-142D01*
G02X1073942Y1636246I-143J-140D01*
G01Y1518928D01*
G03X1074001Y1518786I200J0D01*
G01X1082908Y1509879D01*
G03X1083050Y1509820I142J141D01*
G01X1109385D01*
G03X1109527Y1509879I0J200D01*
G01X1115303Y1515655D01*
G03X1115362Y1515797I-141J142D01*
G01Y1642909D01*
G02X1115421Y1643051I200J0D01*
G01X1117872Y1645502D01*
G02X1118014Y1645561I142J-141D01*
G01X1267167D01*
G02X1267200Y1645558I-2J-200D01*
G02X1267307Y1645504I-32J-197D01*
G01X1267793Y1645018D01*
G02X1267836Y1644800I-142J-141D01*
G01X1267813Y1644744D01*
X1267713Y1644677D01*
X1232743D01*
G03X1232543Y1644477I0J-200D01*
G01Y1643223D01*
X1232574D01*
Y1552480D01*
Y1552280D01*
X1270702D01*
G02X1270888Y1552080I-15J-200D01*
G01Y1533941D01*
G02X1270881Y1533891I-200J2D01*
G01X1267458Y1520798D01*
X1267455Y1520785D01*
X1241682Y1455318D01*
X1241653Y1455288D01*
X1211718Y1425353D01*
G03X1211659Y1425211I141J-142D01*
G01Y1346456D01*
G02X1211582Y1346299I-200J1D01*
G01X1211256Y1346045D01*
G02X1211202Y1346015I-123J158D01*
G02X1211187Y1346010I-71J187D01*
G01X1185207Y1338737D01*
X1185202Y1338736D01*
X1171913Y1335667D01*
X1162052D01*
G03X1161993Y1335658I0J-200D01*
G01X1136392Y1327555D01*
X1136381Y1327553D01*
X1108883Y1321800D01*
G03X1106911Y1320733I805J-3843D01*
G01X1085726Y1299548D01*
G03X1085225Y1298935I2774J-2778D01*
G03X1085188Y1298878I3275J-2166D01*
G03X1084874Y1298275I3312J-2108D01*
G01X1079379Y1285009D01*
G03X1079080Y1283506I3628J-1503D01*
G01Y1277946D01*
G02X1079070Y1277884I-200J0D01*
G01X1077461Y1273058D01*
G03X1077260Y1271824I3691J-1235D01*
G01Y1260090D01*
G03X1077513Y1258711I3892J1D01*
G01X1077526Y1258677D01*
X1077536Y1258623D01*
G02X1077540Y1258585I-196J-40D01*
G01Y1256096D01*
G02X1077422Y1255914I-200J0D01*
G01X1077421Y1255913D01*
X1077420D01*
G03Y1253535I533J-1189D01*
G01X1077421D01*
X1077422Y1253534D01*
G02X1077540Y1253352I-82J-182D01*
G01Y1252356D01*
G02X1077423Y1252174I-200J0D01*
G01X1077421Y1252173D01*
X1077420D01*
G03X1076650Y1250994I532J-1189D01*
G01Y1250972D01*
G03X1076657Y1250848I1302J11D01*
G01X1076658Y1250827D01*
G02X1076599Y1250685I-200J0D01*
G01X1076347Y1250434D01*
X1076263Y1250404D01*
X1076217Y1250409D01*
G03X1076080Y1250416I-135J-1296D01*
G03X1075945Y1250409I0J-1305D01*
G01X1075900Y1250404D01*
X1075815Y1250435D01*
X1075564Y1250686D01*
G02X1075517Y1250760I141J142D01*
G01X1075502Y1250803D01*
X1075506Y1250848D01*
G03X1075514Y1250984I-1295J144D01*
G01Y1254724D01*
G03X1072908I-1303J0D01*
G01Y1250984D01*
G03X1074210Y1249682I1302J0D01*
G01X1074212D01*
G03X1074344Y1249688I7J1302D01*
G02X1074508Y1249630I22J-199D01*
G01X1074758Y1249379D01*
X1074788Y1249295D01*
X1074783Y1249249D01*
G03X1074776Y1249115I1297J-135D01*
G01Y1245373D01*
G03X1076079Y1244070I1303J0D01*
G01X1076081D01*
G03X1076209Y1244076I3J1303D01*
G01X1076210D01*
G02X1076363Y1244026I20J-199D01*
G01X1076582Y1243828D01*
G02X1076648Y1243680I-134J-148D01*
G01Y1243503D01*
G03X1077421Y1242313I1302J0D01*
G01X1077476Y1242289D01*
X1077540Y1242190D01*
Y1241135D01*
G02X1077422Y1240953I-200J0D01*
G01X1077421Y1240952D01*
X1077420D01*
G03Y1238574I533J-1189D01*
G01X1077421D01*
X1077422Y1238573D01*
G02X1077540Y1238391I-82J-182D01*
G01Y1237395D01*
G02X1077422Y1237213I-200J0D01*
G01X1077421Y1237212D01*
X1077420D01*
G03Y1234834I533J-1189D01*
G01X1077421D01*
X1077422Y1234833D01*
G02X1077540Y1234651I-82J-182D01*
G01Y1233655D01*
G02X1077422Y1233473I-200J0D01*
G01X1077421Y1233472D01*
X1077420D01*
G03Y1231094I533J-1189D01*
G01X1077421D01*
X1077422Y1231093D01*
G02X1077540Y1230911I-82J-182D01*
G01Y1229856D01*
X1077476Y1229757D01*
X1077421Y1229733D01*
G03X1076648Y1228543I529J-1190D01*
G01Y1228366D01*
G02X1076583Y1228219I-200J1D01*
G01X1076365Y1228020D01*
G02X1076231Y1227968I-135J148D01*
G01X1076209D01*
X1076200Y1227969D01*
G03X1076082Y1227974I-114J-1297D01*
G01X1076023D01*
G03X1074778Y1226673I58J-1302D01*
G01Y1222932D01*
G03X1077384I1303J0D01*
G01Y1223175D01*
G02X1077501Y1223356I200J-1D01*
G01X1077526Y1223367D01*
X1077921Y1223483D01*
X1077955D01*
G02X1078080Y1223436I-4J-200D01*
G01X1078106Y1223414D01*
X1078123Y1223387D01*
G03X1078323Y1223099I3199J2008D01*
G01X1078338Y1223081D01*
X1078340Y1223078D01*
G03X1078436Y1222960I2977J2324D01*
G01X1078437Y1222959D01*
X1078447Y1222947D01*
X1078450Y1222943D01*
X1078451Y1222942D01*
X1078478Y1222911D01*
X1078517Y1222816D01*
X1078520Y1222802D01*
X1078530Y1222763D01*
X1078532Y1222752D01*
G03X1079553Y1221658I1290J180D01*
G01X1079562Y1221656D01*
X1079588Y1221648D01*
X1079614Y1221639D01*
G02X1079686Y1221592I-71J-187D01*
G01X1080380Y1220898D01*
X1080408Y1220846D01*
X1080413Y1220816D01*
G03X1081433Y1219786I1279J246D01*
G01X1081452Y1219782D01*
X1081520Y1219754D01*
X1081535Y1219744D01*
G03X1082095Y1219451I2025J3189D01*
G01X1082101Y1219449D01*
X1082148Y1219426D01*
G02X1082154Y1219423I-86J-180D01*
G02X1082259Y1219270I-94J-177D01*
G01X1082261Y1219253D01*
Y1219243D01*
G03X1082260Y1219192I1300J-51D01*
G01Y1219191D01*
G03X1082267Y1219057I1302J1D01*
G01X1082272Y1219012D01*
X1082242Y1218927D01*
X1081990Y1218675D01*
G02X1081916Y1218628I-142J141D01*
G01X1081873Y1218613D01*
X1081828Y1218617D01*
G03X1081694Y1218624I-135J-1295D01*
G01X1077952D01*
G03Y1216020I0J-1302D01*
G01X1081692D01*
G03X1082994Y1217322I0J1302D01*
G01Y1217324D01*
G03X1082987Y1217456I-1302J-3D01*
G01X1082982Y1217501D01*
X1082998Y1217546D01*
G02X1083045Y1217620I188J-68D01*
G01X1083297Y1217872D01*
X1083382Y1217902D01*
X1083427Y1217897D01*
G03X1083562Y1217890I135J1295D01*
G03X1084864Y1219192I0J1302D01*
G01Y1219229D01*
G02X1084923Y1219371I200J0D01*
G01X1084986Y1219434D01*
X1085022Y1219449D01*
G03X1085616Y1219763I-1461J3483D01*
G03X1085636Y1219776I-2048J3173D01*
G03X1086268Y1220064I-204J1286D01*
G01X1086294Y1220086D01*
X1086392Y1220123D01*
G02X1086463Y1220136I71J-187D01*
G01X1088141D01*
G02X1088212Y1220123I0J-200D01*
G01X1088310Y1220086D01*
X1088336Y1220064D01*
G03X1088969Y1219776I836J998D01*
G03X1088989Y1219763I2068J3160D01*
G03X1089601Y1219442I2053J3170D01*
G01X1089616Y1219435D01*
G02X1089742Y1219250I-74J-186D01*
G01Y1219238D01*
G03X1089741Y1219192I1301J-51D01*
G03X1092345I1302J0D01*
G01Y1219229D01*
G02X1092404Y1219371I200J0D01*
G01X1092467Y1219434D01*
X1092503Y1219449D01*
G03X1093097Y1219763I-1461J3483D01*
G03X1093117Y1219776I-2048J3173D01*
G03X1093749Y1220064I-204J1286D01*
G01X1093775Y1220086D01*
X1093873Y1220123D01*
G02X1093944Y1220136I71J-187D01*
G01X1095622D01*
G02X1095693Y1220123I0J-200D01*
G01X1095791Y1220086D01*
X1095817Y1220064D01*
G03X1096449Y1219776I836J998D01*
G03X1096469Y1219763I2068J3160D01*
G03X1097098Y1219435I2053J3170D01*
G02X1097222Y1219242I-76J-185D01*
G03X1097221Y1219192I1301J-51D01*
G03X1099825I1302J0D01*
G01Y1219229D01*
G02X1099884Y1219371I200J0D01*
G01X1099947Y1219434D01*
X1099983Y1219449D01*
G03X1100577Y1219763I-1461J3483D01*
G03X1100597Y1219776I-2048J3173D01*
G03X1101229Y1220064I-204J1286D01*
G01X1101255Y1220086D01*
X1101353Y1220123D01*
G02X1101424Y1220136I71J-187D01*
G01X1103102D01*
G02X1103173Y1220123I0J-200D01*
G01X1103271Y1220086D01*
X1103297Y1220064D01*
G03X1103929Y1219776I836J998D01*
G03X1103949Y1219763I2068J3160D01*
G03X1104578Y1219435I2053J3170D01*
G02X1104702Y1219242I-76J-185D01*
G03X1104701Y1219192I1301J-51D01*
G03X1105990Y1217890I1302J0D01*
G01X1106003D01*
G03X1106430Y1217962I0J1302D01*
G01X1106447Y1217968D01*
X1106465Y1217971D01*
X1106499Y1217982D01*
X1106594Y1217968D01*
X1106633Y1217940D01*
G02X1106716Y1217777I-117J-162D01*
G01Y1216984D01*
X1106686Y1216910D01*
X1106657Y1216882D01*
X1106643Y1216868D01*
X1106409Y1216676D01*
G02X1106283Y1216631I-126J155D01*
G01X1106248D01*
X1106229Y1216635D01*
G03X1106003Y1216656I-224J-1182D01*
G03X1104799Y1215452I0J-1204D01*
G03X1106002Y1214248I1204J0D01*
G01X1106011D01*
G03X1106241Y1214269I6J1205D01*
G01X1106256Y1214272D01*
X1106271Y1214273D01*
G02X1106411Y1214228I13J-200D01*
G01X1106643Y1214037D01*
G02X1106716Y1213883I-127J-155D01*
G01Y1199925D01*
G02X1106657Y1199783I-200J0D01*
G01X1105825Y1198951D01*
X1105797Y1198922D01*
X1105723Y1198892D01*
X1094274D01*
X1094170Y1198967D01*
X1094149Y1199029D01*
G03X1091677I-1236J-407D01*
G01X1091656Y1198967D01*
X1091552Y1198892D01*
X1090599D01*
G02X1090574Y1198893I-5J200D01*
G02X1090414Y1199015I25J199D01*
G03X1089172Y1199924I-1242J-394D01*
G01X1085432D01*
G03X1084195Y1199029I0J-1302D01*
G01X1084174Y1198967D01*
X1084070Y1198892D01*
X1083053D01*
X1082949Y1198967D01*
X1082928Y1199029D01*
G03X1081692Y1199923I-1236J-407D01*
G01X1081691D01*
G03X1081556Y1199916I0J-1302D01*
G01X1081511Y1199911D01*
X1081426Y1199941D01*
X1081142Y1200225D01*
X1081112Y1200310D01*
X1081117Y1200355D01*
G03X1081124Y1200490I-1295J135D01*
G01Y1200492D01*
G03X1081118Y1200620I-1302J3D01*
G01Y1200621D01*
G02X1081168Y1200774I199J20D01*
G01X1081367Y1200994D01*
G02X1081455Y1201051I149J-134D01*
G01X1081485Y1201060D01*
X1081692D01*
G03Y1203664I0J1302D01*
G01X1077952D01*
G03X1076650Y1202362I0J-1302D01*
G03X1076656Y1202233I1302J-4D01*
G01X1076660Y1202190D01*
X1076634Y1202110D01*
X1076406Y1201860D01*
X1076377Y1201828D01*
X1076300Y1201794D01*
X1076082D01*
G03X1074780Y1200492I0J-1302D01*
G01Y1200490D01*
G03X1074787Y1200355I1303J0D01*
G01X1074792Y1200310D01*
X1074762Y1200225D01*
X1074510Y1199973D01*
G02X1074353Y1199915I-142J142D01*
G01X1074350Y1199916D01*
G03X1074207Y1199923I-135J-1295D01*
G03X1072976Y1199029I5J-1302D01*
G01X1072955Y1198967D01*
X1072851Y1198892D01*
X1071833D01*
X1071729Y1198967D01*
X1071708Y1199029D01*
G03X1070472Y1199923I-1236J-407D01*
G01X1070471D01*
G03X1070336Y1199916I0J-1302D01*
G01X1070291Y1199911D01*
X1070206Y1199941D01*
X1069922Y1200225D01*
X1069892Y1200310D01*
X1069897Y1200355D01*
G03X1069904Y1200490I-1295J135D01*
G01Y1200521D01*
X1069905Y1200529D01*
G03X1069899Y1200620I-1302J-40D01*
G01X1069895Y1200663D01*
X1069921Y1200743D01*
X1070148Y1200994D01*
G02X1070164Y1201010I149J-133D01*
G02X1070296Y1201060I132J-150D01*
G01X1070472D01*
G03Y1203666I0J1303D01*
G01X1066732D01*
G03X1065430Y1202364I0J-1302D01*
G01Y1202363D01*
G03X1065436Y1202235I1302J-3D01*
G01X1065440Y1202192D01*
X1065414Y1202112D01*
X1065186Y1201862D01*
X1065157Y1201830D01*
X1065080Y1201796D01*
X1064862D01*
G03X1063734Y1201145I0J-1303D01*
G03X1063560Y1200493I1128J-650D01*
G03X1063567Y1200356I1303J-2D01*
G01X1063572Y1200311D01*
X1063542Y1200226D01*
X1063290Y1199974D01*
G02X1063216Y1199927I-142J141D01*
G01X1063173Y1199912D01*
X1063128Y1199916D01*
G03X1062991Y1199924I-144J-1295D01*
G01X1059251D01*
G03X1058014Y1199029I0J-1302D01*
G01X1057994Y1198967D01*
X1057890Y1198892D01*
X1056936D01*
G02X1056747Y1199028I1J200D01*
G01Y1199030D01*
G03X1054273I-1237J-409D01*
G01Y1199028D01*
G02X1054084Y1198892I-190J64D01*
G01X1036662D01*
G02X1036520Y1198951I0J200D01*
G01X1033159Y1202312D01*
X1033130Y1202340D01*
X1033100Y1202414D01*
Y1206297D01*
G02X1033245Y1206490I200J1D01*
G03Y1209410I-413J1460D01*
G01X1033181Y1209428D01*
X1033100Y1209535D01*
Y1236614D01*
G03X1033041Y1236756I-200J0D01*
G01X1025078Y1244719D01*
X1025028Y1244768D01*
X1025012Y1244904D01*
X1025249Y1245296D01*
G02X1025478Y1245384I171J-103D01*
G03X1030901Y1244584I5426J18002D01*
G01X1030905D01*
G03Y1282188I0J18802D01*
G01X1030904D01*
G03X1015323Y1273907I2J-18802D01*
G01Y1273906D01*
G02X1015097Y1273828I-165J113D01*
G01X1014877Y1273897D01*
X1014875D01*
X1014733Y1273940D01*
G02X1014591Y1274131I58J191D01*
G01Y1337096D01*
G03X1014532Y1337238I-200J0D01*
G01X1010948Y1340822D01*
G03X1010806Y1340881I-142J-141D01*
G01X901626D01*
G03X901484Y1340822I0J-200D01*
G01X893828Y1333166D01*
G03X893769Y1333024I141J-142D01*
G01Y1287300D01*
G03X893828Y1287158I200J0D01*
G01X899276Y1281710D01*
G03X899418Y1281651I142J141D01*
G01X908845D01*
G02X909001Y1281576I0J-200D01*
G01X909016Y1281557D01*
X909187Y1281263D01*
X909188Y1281262D01*
Y1281261D01*
G02X909208Y1281112I-174J-99D01*
G01X909193Y1281054D01*
X909181Y1281032D01*
G03X908996Y1280310I1319J-723D01*
G01Y1280309D01*
G03X912000I1502J0D01*
G01Y1280310D01*
G03X911815Y1281032I-1504J-1D01*
G01X911803Y1281054D01*
X911789Y1281106D01*
Y1281108D01*
X911779Y1281141D01*
X911788Y1281223D01*
X911977Y1281551D01*
G02X912150Y1281651I173J-100D01*
G01X931435D01*
G03X931577Y1281710I0J200D01*
G01X932338Y1282471D01*
G02X932480Y1282530I142J-141D01*
G01X971271D01*
G02X971304Y1282527I-2J-200D01*
G02X971411Y1282473I-32J-197D01*
G01X982426Y1271458D01*
G02X982485Y1271316I-141J-142D01*
G01Y1197629D01*
G02X982285Y1197429I-200J0D01*
G01X882017D01*
X881943Y1197459D01*
X881915Y1197488D01*
X868488Y1210915D01*
X868459Y1210943D01*
X868429Y1211017D01*
Y1221274D01*
X868436Y1221300D01*
G03X868942Y1225116I-14145J3817D01*
G01Y1225118D01*
G03X854291Y1239769I-14651J0D01*
G03X839659Y1225873I0J-14651D01*
G01X839657Y1225833D01*
X839621Y1225757D01*
G02X839441Y1225643I-181J86D01*
G01X817052D01*
G02X816912Y1225700I0J200D01*
G01X816738Y1225869D01*
X816725Y1225881D01*
X816673Y1225951D01*
X816663Y1225983D01*
X816652Y1226016D01*
X816651Y1226051D01*
G03X816643Y1226173I-1502J-37D01*
G01Y1226174D01*
X816641Y1226194D01*
G03X816627Y1226283I-1490J-189D01*
G01X816618Y1226332D01*
X816647Y1226425D01*
X816769Y1226547D01*
G02X816907Y1226606I142J-141D01*
G01X816964Y1226607D01*
X816988Y1226602D01*
G03X817358Y1226560I372J1624D01*
G01X817360D01*
G03X819026Y1228226I0J1666D01*
G01Y1228230D01*
G03X819010Y1228460I-1666J0D01*
G01X819006Y1228487D01*
Y1228503D01*
G02X819066Y1228646I200J0D01*
G01X819165Y1228743D01*
X819245Y1228772D01*
X819289Y1228768D01*
G03X819419Y1228763I123J1497D01*
G03Y1231767I0J1502D01*
G03X817917Y1230269I0J-1502D01*
G01Y1230265D01*
G03X817921Y1230155I1502J0D01*
G01Y1230135D01*
X817913Y1230093D01*
G02X817858Y1229989I-196J37D01*
G01X817856Y1229987D01*
X817760Y1229892D01*
X817670Y1229863D01*
X817622Y1229871D01*
G03X817363Y1229892I-264J-1645D01*
G01X817360D01*
G03X815694Y1228226I0J-1666D01*
G01Y1228189D01*
G03X815734Y1227825I1669J-1D01*
G01X815739Y1227804D01*
Y1227777D01*
G02X815680Y1227635I-200J0D01*
G01X815598Y1227553D01*
X815570Y1227524D01*
X815496Y1227494D01*
X815417D01*
X815400Y1227497D01*
G03X815149Y1227518I-250J-1481D01*
G01X815119D01*
G03X813647Y1226039I30J-1502D01*
G01X813646Y1225989D01*
X813608Y1225917D01*
X813585Y1225895D01*
X813391Y1225704D01*
G03X813389Y1225702I140J-142D01*
G01X813361Y1225674D01*
X813288Y1225643D01*
X785144D01*
G02X784979Y1225731I1J200D01*
G01X784795Y1226003D01*
X784786Y1226035D01*
G03X784784Y1226041I-187J-59D01*
G01X784773Y1226073D01*
Y1226153D01*
X784780Y1226197D01*
X784787Y1226227D01*
X784791Y1226238D01*
G03X784841Y1226423I-1229J431D01*
G03X784842Y1226425I-172J87D01*
G03X784844Y1226435I-1275J260D01*
G01Y1226438D01*
X784848Y1226460D01*
G03X784866Y1226673I-1285J216D01*
G03X783563Y1227976I-1303J0D01*
G01X783345D01*
X783268Y1228010D01*
X783239Y1228042D01*
X783040Y1228262D01*
G02X782999Y1228333I149J133D01*
G01X782985Y1228374D01*
X782989Y1228417D01*
G03X782996Y1228542I-1295J135D01*
G01Y1228543D01*
G03X781695Y1229844I-1302J-1D01*
G01X777953D01*
G03Y1227240I0J-1302D01*
G01X778171D01*
X778247Y1227206D01*
X778276Y1227174D01*
X778474Y1226956D01*
G02X778526Y1226822I-148J-135D01*
G01Y1226800D01*
X778525Y1226791D01*
G03X778520Y1226673I1298J-114D01*
G01Y1226652D01*
G03X778527Y1226537I1303J22D01*
G01X778532Y1226491D01*
X778502Y1226406D01*
X778469Y1226374D01*
X778217Y1226123D01*
X778133Y1226093D01*
X778088Y1226098D01*
G03X777951Y1226105I-135J-1295D01*
G03X777039Y1225730I2J-1302D01*
G01X777012Y1225704D01*
X776907Y1225659D01*
X776869Y1225643D01*
X775336D01*
G02X775258Y1225659I0J200D01*
G01X775153Y1225704D01*
X775125Y1225731D01*
G03X774212Y1226105I-913J-927D01*
G03X774107Y1226101I-3J-1302D01*
G01X774106D01*
G03X774083Y1226099I101J-1298D01*
G01X774082D01*
G02X773929Y1226150I-19J199D01*
G01X773710Y1226348D01*
G02X773644Y1226496I134J148D01*
G01Y1226672D01*
G03X772342Y1227974I-1302J0D01*
G03X772214Y1227968I-3J-1302D01*
G01X772213D01*
G02X772060Y1228018I-20J199D01*
G01X771840Y1228217D01*
G02X771783Y1228305I134J149D01*
G01X771774Y1228335D01*
Y1228543D01*
G03X769170I-1302J0D01*
G01Y1225843D01*
G02X768970Y1225643I-200J0D01*
G01X767856D01*
G02X767778Y1225659I0J200D01*
G01X767673Y1225704D01*
X767645Y1225731D01*
G03X766732Y1226105I-913J-927D01*
G03X766627Y1226101I-3J-1302D01*
G01X766626D01*
G03X766603Y1226099I101J-1298D01*
G01X766602D01*
G02X766449Y1226150I-19J199D01*
G01X766230Y1226348D01*
G02X766164Y1226496I134J148D01*
G01Y1226672D01*
G03X764862Y1227974I-1302J0D01*
G03X764734Y1227968I-3J-1302D01*
G01X764733D01*
G02X764580Y1228018I-20J199D01*
G01X764360Y1228217D01*
G02X764303Y1228305I134J149D01*
G01X764294Y1228335D01*
Y1228543D01*
G03X761690I-1302J0D01*
G01Y1225843D01*
G02X761490Y1225643I-200J0D01*
G01X760376D01*
G02X760298Y1225659I0J200D01*
G01X760193Y1225704D01*
X760165Y1225731D01*
G03X759252Y1226105I-913J-927D01*
G03X759147Y1226101I-3J-1302D01*
G01X759146D01*
G03X759123Y1226099I101J-1298D01*
G01X759122D01*
G02X758969Y1226150I-19J199D01*
G01X758750Y1226348D01*
G02X758684Y1226496I134J148D01*
G01Y1226672D01*
G03X757382Y1227974I-1302J0D01*
G03X757254Y1227968I-3J-1302D01*
G01X757253D01*
G02X757100Y1228018I-20J199D01*
G01X756880Y1228217D01*
G02X756823Y1228305I134J149D01*
G01X756814Y1228335D01*
Y1228543D01*
G03X754210I-1302J0D01*
G01Y1225843D01*
G02X754010Y1225643I-200J0D01*
G01X752896D01*
G02X752818Y1225659I0J200D01*
G01X752713Y1225704D01*
X752685Y1225731D01*
G03X751772Y1226105I-913J-927D01*
G03X751667Y1226101I-3J-1302D01*
G01X751666D01*
G03X751643Y1226099I101J-1298D01*
G01X751642D01*
G02X751489Y1226150I-19J199D01*
G01X751270Y1226348D01*
G02X751204Y1226496I134J148D01*
G01Y1226672D01*
G03X749902Y1227974I-1302J0D01*
G01X749901D01*
G03X749711Y1227960I0J-1302D01*
G01X749710D01*
X749680Y1227955D01*
G03X749636Y1227947I211J-1285D01*
G03X749581Y1227935I250J-1279D01*
G01X749558Y1227929D01*
X749534D01*
G02X749334Y1228129I0J200D01*
G01Y1228543D01*
G03X748032Y1229846I-1303J0D01*
G03X747671Y1229795I0J-1303D01*
G01X747657Y1229791D01*
X747633Y1229787D01*
G02X747463Y1229843I-29J198D01*
G01X747429Y1229876D01*
X747399Y1229964D01*
X747407Y1230023D01*
G02X747418Y1230068I199J-25D01*
G01X747427Y1230090D01*
X747441Y1230110D01*
G03X747754Y1230655I-3151J2172D01*
G01X747768Y1230685D01*
X747860Y1230780D01*
X747889Y1230795D01*
G03X748185Y1230965I-1731J3356D01*
G01X748198Y1230974D01*
X748260Y1231001D01*
X748281Y1231005D01*
G03X749309Y1232033I-250J1278D01*
G01X749313Y1232054D01*
X749340Y1232116D01*
X749349Y1232129D01*
G03X749636Y1232673I-3186J2028D01*
G01X749648Y1232700D01*
X749683Y1232743D01*
X749790Y1232816D01*
X749903Y1232851D01*
G03X750030Y1232857I2J1302D01*
G01X750031D01*
G02X750184Y1232807I20J-199D01*
G01X750404Y1232608D01*
G02X750461Y1232519I-134J-149D01*
G01X750470Y1232489D01*
Y1232283D01*
G03X753074I1302J0D01*
G01Y1236023D01*
G03X751773Y1237326I-1303J0D01*
G01X751771D01*
G03X751636Y1237318I9J-1303D01*
G01X751591Y1237314D01*
X751548Y1237329D01*
G02X751474Y1237376I68J188D01*
G01X751254Y1237596D01*
G02X751207Y1237670I141J142D01*
G01X751191Y1237713D01*
X751196Y1237759D01*
G03X750583Y1239003I-1296J134D01*
G03X749936Y1239195I-681J-1110D01*
G01X749920Y1239196D01*
X749876Y1239204D01*
X749814Y1239224D01*
G02X749759Y1239252I62J190D01*
G01X749689Y1239302D01*
X749670Y1239330D01*
X749640Y1239371D01*
X749631Y1239391D01*
G03X749347Y1239926I-3468J-1498D01*
G01X749337Y1239942D01*
X749310Y1240010D01*
X749306Y1240028D01*
X749305Y1240031D01*
G03X748561Y1240952I-1274J-268D01*
G01X748560Y1240953D01*
G02X748442Y1241135I82J182D01*
G01Y1242190D01*
X748506Y1242289D01*
X748561Y1242313D01*
G03X749334Y1243503I-529J1190D01*
G01Y1243680D01*
G02X749400Y1243828I200J0D01*
G01X749619Y1244026D01*
G02X749772Y1244076I133J-149D01*
G01X749773D01*
G03X749898Y1244070I125J1298D01*
G01X749902D01*
G03X751206Y1245373I0J1304D01*
G01Y1249115D01*
G03X751199Y1249249I-1303J-1D01*
G01X751194Y1249294D01*
X751224Y1249379D01*
X751508Y1249663D01*
X751593Y1249693D01*
X751638Y1249688D01*
G03X751770Y1249682I125J1296D01*
G01X751772D01*
G03X753074Y1250984I-1J1303D01*
G01Y1254724D01*
G03X750468I-1303J0D01*
G01Y1250984D01*
G03X750476Y1250849I1302J9D01*
G01X750480Y1250804D01*
X750465Y1250761D01*
G02X750418Y1250686I-189J66D01*
G01X750199Y1250467D01*
G02X750037Y1250409I-142J141D01*
G03X749904Y1250416I-135J-1296D01*
G37*
G36*
G01X550913Y658676D02*
G03I-639J0D01*
G37*
G36*
G01X554510Y811298D02*
G03I-639J0D01*
G37*
G36*
G01X549103Y823156D02*
G03I-639J0D01*
G37*
G36*
G01X541446Y816556D02*
G03I-639J0D01*
G37*
G36*
G01X545783Y909025D02*
G03I-639J0D01*
G37*
G36*
G01X562525Y728138D02*
G03I-639J0D01*
G37*
G36*
G01X560264Y739609D02*
G03I-639J0D01*
G37*
G36*
G01X564915Y776701D02*
G03I-639J0D01*
G37*
G36*
G01X571334Y767052D02*
G03I-639J0D01*
G37*
G36*
G01X569825Y787332D02*
G03I-639J0D01*
G37*
G36*
G01X562040Y811242D02*
G03I-639J0D01*
G37*
G36*
G01X570216Y886913D02*
G03I-639J0D01*
G37*
G36*
G01X561453Y901022D02*
G03I-639J0D01*
G37*
G36*
G01X574444Y728301D02*
G03I-639J0D01*
G37*
G36*
G01X575198Y772723D02*
G03I-577J0D01*
G37*
G36*
G01X585263Y781850D02*
G03I-639J0D01*
G37*
G36*
G01X580397Y817753D02*
G03I-639J0D01*
G37*
G36*
G01X698545Y681478D02*
X707962D01*
G02X708104Y681419I0J-200D01*
G01X709051Y680472D01*
G02X709110Y680330I-141J-142D01*
G01Y582069D01*
G02X709051Y581927I-200J0D01*
G01X683200Y556076D01*
G02X683059Y556017I-142J141D01*
G01X682738Y556016D01*
X682666Y556045D01*
X682637Y556073D01*
G03X681586Y556502I-1051J-1073D01*
G03X680084Y555000I0J-1502D01*
G03X680513Y553949I1502J0D01*
G01X680541Y553920D01*
X680570Y553848D01*
X680569Y553527D01*
G02X680510Y553386I-200J1D01*
G01X676919Y549795D01*
G02X676777Y549736I-142J141D01*
G01X644764D01*
G02X644623Y549794I0J200D01*
G01X644394Y550021D01*
X644364Y550093D01*
Y550133D01*
G03X643850Y551254I-1502J-10D01*
G01X643819Y551282D01*
X643783Y551355D01*
X643767Y551727D01*
X643795Y551803D01*
X643824Y551833D01*
G03X644242Y552872I-1084J1040D01*
G03X641238I-1502J0D01*
G03X641752Y551741I1501J0D01*
G01X641783Y551713D01*
X641819Y551640D01*
X641835Y551268D01*
X641807Y551192D01*
X641778Y551162D01*
G03X641360Y550133I1084J-1040D01*
G01Y550093D01*
X641330Y550021D01*
X641101Y549794D01*
G02X640960Y549736I-141J142D01*
G01X611529D01*
G02X611387Y549795I0J200D01*
G01X600247Y560935D01*
G02X600188Y561077I141J142D01*
G01Y623131D01*
G02X600247Y623273I200J0D01*
G01X602867Y625893D01*
G02X603009Y625952I142J-141D01*
G01X647417D01*
G02X647559Y625893I0J-200D01*
G01X652308Y621144D01*
G02X652367Y621002I-141J-142D01*
G01Y611888D01*
G02X652308Y611746I-200J0D01*
G01X649231Y608669D01*
G02X649089Y608610I-142J141D01*
G01X616244D01*
G03X616102Y608551I0J-200D01*
G01X610896Y603345D01*
G03X610837Y603203I141J-142D01*
G01Y574312D01*
G03X610896Y574170I200J0D01*
G01X620209Y564857D01*
G03X620351Y564798I142J141D01*
G01X659332D01*
G02X659508Y564694I1J-200D01*
G03X662144I1318J720D01*
G02X662320Y564798I175J-96D01*
G01X664759D01*
G03X664901Y564857I0J200D01*
G01X695208Y595164D01*
G03X695267Y595306I-141J142D01*
G01Y678200D01*
G02X695326Y678342I200J0D01*
G01X698403Y681419D01*
G02X698545Y681478I142J-141D01*
G37*
G36*
G01X592877Y880612D02*
G03I-639J0D01*
G37*
G36*
G01X602963Y940920D02*
G03I-577J0D01*
G37*
G36*
G01X613067Y941024D02*
G03I-577J0D01*
G37*
G36*
G01X697106Y54588D02*
X725589D01*
X725942Y54235D01*
Y52944D01*
X725589Y52591D01*
X697106D01*
G03X691169Y46654I0J-5937D01*
G01Y7874D01*
G02X685295Y2000I-5874J0D01*
G01X638051D01*
G02X632177Y7874I0J5874D01*
G01Y46391D01*
X634174D01*
Y7874D01*
G03X638049Y3998I3876J0D01*
G01X685295D01*
G03X689172Y7874I0J3877D01*
G01Y46654D01*
G02X697106Y54588I7934J0D01*
G37*
G36*
G01X692243Y1222978D02*
X692294Y1222968D01*
G02X692407Y1222904I-37J-196D01*
G01X692408Y1222903D01*
G03X692456Y1222849I2862J2495D01*
G01X692457Y1222848D01*
G03X692565Y1222733I2821J2541D01*
G01X692583Y1222715D01*
X692609Y1222670D01*
X692616Y1222658D01*
X692636Y1222614D01*
X692640Y1222600D01*
G03X692710Y1222415I1159J333D01*
G02X692444Y1222148I-181J-86D01*
G03X691929Y1222264I-515J-1085D01*
G03Y1219860I0J-1202D01*
G03X692151Y1219881I-2J1202D01*
G01X692200Y1219890D01*
X692293Y1219861D01*
X692598Y1219556D01*
X692627Y1219463D01*
X692618Y1219414D01*
G03X692597Y1219192I1181J-224D01*
G03X693799Y1217990I1202J0D01*
G03X694021Y1218011I-2J1202D01*
G01X694070Y1218020D01*
X694163Y1217991D01*
X694468Y1217686D01*
X694497Y1217593D01*
X694488Y1217544D01*
G03X694467Y1217322I1181J-224D01*
G03X694488Y1217100I1202J2D01*
G01X694497Y1217051D01*
X694468Y1216958D01*
X694163Y1216653D01*
X694070Y1216624D01*
X694021Y1216633D01*
G03X693799Y1216654I-224J-1181D01*
G03X695001Y1215452I0J-1202D01*
G03X694980Y1215674I-1202J-2D01*
G01X694971Y1215723D01*
X695000Y1215816D01*
X695305Y1216121D01*
X695398Y1216150D01*
X695447Y1216141D01*
G03X695669Y1216120I224J1181D01*
G03X695891Y1216141I-2J1202D01*
G01X695940Y1216150D01*
X696033Y1216121D01*
X696338Y1215816D01*
X696367Y1215723D01*
X696358Y1215674D01*
G03X696337Y1215452I1181J-224D01*
G03X698741I1202J0D01*
G03X698720Y1215674I-1202J-2D01*
G01X698711Y1215723D01*
X698740Y1215816D01*
X699045Y1216121D01*
X699138Y1216150D01*
X699187Y1216141D01*
G03X699409Y1216120I224J1181D01*
G03X699631Y1216141I-2J1202D01*
G01X699680Y1216150D01*
X699773Y1216121D01*
X700078Y1215816D01*
X700107Y1215723D01*
X700098Y1215674D01*
G03X700077Y1215452I1181J-224D01*
G03X701279Y1216654I1202J0D01*
G03X701057Y1216633I2J-1202D01*
G01X701008Y1216624D01*
X700915Y1216653D01*
X700610Y1216958D01*
X700581Y1217051D01*
X700590Y1217100D01*
G03X700611Y1217322I-1181J224D01*
G03X700590Y1217544I-1202J-2D01*
G01X700581Y1217593D01*
X700610Y1217686D01*
X700915Y1217991D01*
X701008Y1218020D01*
X701057Y1218011D01*
G03X701279Y1217990I224J1181D01*
G03X702481Y1219192I0J1202D01*
G03X702477Y1219292I-1202J2D01*
G01X702472Y1219348D01*
X702522Y1219447D01*
X702721Y1219572D01*
X702722D01*
X702874Y1219666D01*
G02X702979Y1219696I105J-170D01*
G01X703033D01*
X703082Y1219668D01*
X703084Y1219667D01*
G03X703416Y1219490I1950J3258D01*
G01X703417D01*
X703457Y1219472D01*
G03X703461Y1219470I1700J3394D01*
G03X703631Y1219398I1565J3459D01*
G01X703658Y1219387D01*
X703704Y1219352D01*
X703799Y1219217D01*
X703817Y1219165D01*
X703818Y1219135D01*
G03X706220Y1219134I1201J58D01*
G01X706221Y1219163D01*
X706230Y1219190D01*
X706239Y1219218D01*
X706312Y1219323D01*
X706329Y1219348D01*
X706376Y1219385D01*
X706407Y1219397D01*
G03X706959Y1219668I-1392J3533D01*
G02X707168Y1219665I102J-172D01*
G01X707238Y1219621D01*
X707240D01*
X707515Y1219446D01*
X707565Y1219348D01*
X707561Y1219293D01*
G03X707558Y1219215I1200J-85D01*
G01Y1219188D01*
G03X709962I1202J4D01*
G01Y1219215D01*
G03X709958Y1219290I-1202J-26D01*
G01X709953Y1219347D01*
X710003Y1219446D01*
X710202Y1219571D01*
X710352Y1219665D01*
X710354D01*
X710399Y1219694D01*
X710505Y1219698D01*
X710568Y1219665D01*
X710574Y1219661D01*
G03X710868Y1219504I1934J3267D01*
G01X710869D01*
X710910Y1219485D01*
G03X711117Y1219394I1631J3428D01*
G01X711118D01*
X711120Y1219393D01*
G02X711210Y1219319I-76J-185D01*
G01X711248Y1219262D01*
G02X711281Y1219158I-167J-110D01*
G03X712500Y1217973I1219J34D01*
G03X713719Y1219158I0J1219D01*
G01Y1219159D01*
X713721Y1219215D01*
X713771Y1219293D01*
G02X713773Y1219295I142J-140D01*
G01X713788Y1219318D01*
G02X713829Y1219363I167J-111D01*
G01X713852Y1219382D01*
X713881Y1219394D01*
G03X714417Y1219655I-1389J3534D01*
G01X714439Y1219668D01*
X714490Y1219682D01*
G02X714545Y1219690I56J-192D01*
G01X714551D01*
G02X714658Y1219659I0J-200D01*
G01X714718Y1219621D01*
X714720D01*
X714949Y1219475D01*
G02X715041Y1219307I-108J-168D01*
G01Y1219290D01*
X715040Y1219283D01*
Y1219253D01*
G03X715037Y1219193I1199J-90D01*
G01Y1219191D01*
G03X716240Y1217989I1203J1D01*
G03X717443Y1219192I0J1203D01*
G03X717439Y1219292I-1203J2D01*
G01X717434Y1219348D01*
X717484Y1219447D01*
X717625Y1219536D01*
X717626D01*
X717882Y1219695D01*
X717993Y1219696D01*
X718042Y1219667D01*
G03X718648Y1219377I1935J3266D01*
G02X718778Y1219190I-70J-187D01*
G03X721182I1202J2D01*
G02X721312Y1219377I200J0D01*
G03X721903Y1219658I-1329J3557D01*
G01X721928Y1219673D01*
X721977Y1219686D01*
G02X722134Y1219661I50J-194D01*
G01X722427Y1219478D01*
G02X722519Y1219338I-106J-170D01*
G01X722521Y1219323D01*
Y1219296D01*
X722520Y1219289D01*
G03X722517Y1219194I1200J-85D01*
G01Y1219192D01*
G03X724923I1203J0D01*
G03X724919Y1219292I-1203J2D01*
G01X724914Y1219348D01*
X724964Y1219447D01*
X725105Y1219536D01*
X725106D01*
X725362Y1219695D01*
X725473Y1219696D01*
X725522Y1219668D01*
G03X726129Y1219377I1938J3264D01*
G02X726259Y1219190I-70J-187D01*
G03X727461Y1217990I1202J2D01*
G03X728663Y1219191I0J1202D01*
G01Y1219254D01*
X728733Y1219355D01*
X728793Y1219378D01*
G03X729378Y1219656I-1331J3555D01*
G01X729400Y1219669D01*
X729454Y1219684D01*
G02X729614Y1219661I54J-192D01*
G01X729957Y1219448D01*
X730007Y1219349D01*
X730002Y1219292D01*
G03X729998Y1219195I1199J-98D01*
G01Y1219192D01*
G03X732404I1203J0D01*
G03X732400Y1219292I-1203J2D01*
G01X732395Y1219348D01*
X732445Y1219447D01*
X732586Y1219536D01*
X732587D01*
X732843Y1219695D01*
X732954Y1219696D01*
X733003Y1219667D01*
G03X733609Y1219377I1935J3266D01*
G02X733739Y1219190I-70J-187D01*
G03X736143I1202J2D01*
G02X736273Y1219377I200J0D01*
G03X736864Y1219658I-1329J3557D01*
G01X736889Y1219673D01*
X736938Y1219686D01*
G02X737095Y1219661I50J-194D01*
G01X737388Y1219478D01*
G02X737480Y1219338I-106J-170D01*
G01X737482Y1219323D01*
Y1219296D01*
X737481Y1219289D01*
G03X737478Y1219194I1200J-85D01*
G01Y1219192D01*
G03X739884I1203J0D01*
G03X739880Y1219292I-1203J2D01*
G01X739875Y1219348D01*
X739925Y1219447D01*
X740066Y1219536D01*
X740067D01*
X740323Y1219695D01*
X740434Y1219696D01*
X740483Y1219667D01*
G03X741089Y1219377I1935J3266D01*
G02X741219Y1219190I-70J-187D01*
G03X743623I1202J2D01*
G02X743753Y1219377I200J0D01*
G03X744344Y1219658I-1329J3557D01*
G01X744369Y1219673D01*
X744418Y1219686D01*
G02X744575Y1219661I50J-194D01*
G01X744868Y1219478D01*
G02X744960Y1219338I-106J-170D01*
G01X744962Y1219323D01*
Y1219296D01*
X744961Y1219289D01*
G03X744958Y1219194I1200J-85D01*
G01Y1219192D01*
G03X746161Y1217989I1203J0D01*
G03X746383Y1218010I-2J1203D01*
G01X746432Y1218019D01*
X746525Y1217990D01*
X746830Y1217685D01*
X746859Y1217593D01*
X746849Y1217543D01*
G03X746829Y1217322I1182J-218D01*
G03X748031Y1218524I1202J0D01*
G03X747810Y1218504I-3J-1202D01*
G01X747760Y1218494D01*
X747668Y1218523D01*
X747363Y1218828D01*
X747334Y1218921D01*
X747343Y1218970D01*
G03X747364Y1219192I-1182J224D01*
G03X747343Y1219414I-1203J-2D01*
G01X747334Y1219463D01*
X747363Y1219556D01*
X747668Y1219861D01*
X747760Y1219890D01*
X747810Y1219880D01*
G03X748031Y1219860I218J1182D01*
G03X749233Y1221062I0J1202D01*
G03X749225Y1221204I-1202J3D01*
G01X749219Y1221251D01*
X749250Y1221339D01*
X749551Y1221626D01*
X749640Y1221653D01*
X749688Y1221645D01*
G03X749771Y1221634I213J1286D01*
G01X749792D01*
X749811Y1221631D01*
G03X750116Y1221645I93J1301D01*
G01X750163Y1221653D01*
X750252Y1221626D01*
X750553Y1221339D01*
X750584Y1221251D01*
X750578Y1221204D01*
G03X750570Y1221062I1194J-139D01*
G03X752974I1202J0D01*
G03X752954Y1221283I-1202J3D01*
G01X752944Y1221332D01*
X752973Y1221425D01*
X753278Y1221730D01*
X753371Y1221758D01*
X753420Y1221749D01*
G03X753864I222J1183D01*
G01X753913Y1221758D01*
X754006Y1221730D01*
X754311Y1221425D01*
X754340Y1221332D01*
X754330Y1221283D01*
G03X754310Y1221062I1182J-218D01*
G03X756714I1202J0D01*
G03X756706Y1221203I-1202J3D01*
G01X756700Y1221251D01*
X756732Y1221339D01*
X757032Y1221626D01*
X757121Y1221653D01*
X757168Y1221645D01*
G03X757251Y1221634I213J1286D01*
G01X757272D01*
X757291Y1221631D01*
G03X757596Y1221645I93J1301D01*
G01X757643Y1221653D01*
X757732Y1221626D01*
X758033Y1221339D01*
X758064Y1221251D01*
X758058Y1221204D01*
G03X758050Y1221062I1194J-139D01*
G03X760454I1202J0D01*
G03X760434Y1221283I-1202J3D01*
G01X760424Y1221332D01*
X760453Y1221425D01*
X760758Y1221730D01*
X760851Y1221758D01*
X760900Y1221749D01*
G03X761344I222J1183D01*
G01X761393Y1221758D01*
X761486Y1221730D01*
X761791Y1221425D01*
X761820Y1221332D01*
X761810Y1221283D01*
G03X761790Y1221062I1182J-218D01*
G03X764194I1202J0D01*
G03X764186Y1221203I-1202J3D01*
G01X764180Y1221251D01*
X764212Y1221339D01*
X764512Y1221626D01*
X764601Y1221653D01*
X764648Y1221645D01*
G03X764731Y1221634I213J1286D01*
G01X764752D01*
X764771Y1221631D01*
G03X765076Y1221645I93J1301D01*
G01X765123Y1221653D01*
X765212Y1221626D01*
X765513Y1221339D01*
X765544Y1221251D01*
X765538Y1221204D01*
G03X765530Y1221062I1194J-139D01*
G03X767934I1202J0D01*
G03X767914Y1221283I-1202J3D01*
G01X767904Y1221332D01*
X767933Y1221425D01*
X768238Y1221730D01*
X768331Y1221758D01*
X768380Y1221749D01*
G03X768824I222J1183D01*
G01X768873Y1221758D01*
X768966Y1221730D01*
X769271Y1221425D01*
X769300Y1221332D01*
X769290Y1221283D01*
G03X769270Y1221062I1182J-218D01*
G03X771674I1202J0D01*
G03X771666Y1221203I-1202J3D01*
G01X771660Y1221251D01*
X771692Y1221339D01*
X771992Y1221626D01*
X772081Y1221653D01*
X772128Y1221645D01*
G03X772211Y1221634I213J1286D01*
G01X772232D01*
X772251Y1221631D01*
G03X772556Y1221645I93J1301D01*
G01X772603Y1221653D01*
X772692Y1221626D01*
X772993Y1221339D01*
X773024Y1221251D01*
X773018Y1221204D01*
G03X773010Y1221062I1194J-139D01*
G03X775414I1202J0D01*
G03X775394Y1221283I-1202J3D01*
G01X775384Y1221332D01*
X775413Y1221425D01*
X775718Y1221730D01*
X775811Y1221759D01*
X775861Y1221749D01*
G03X776238Y1221739I220J1183D01*
G01X776285Y1221745D01*
X776374Y1221713D01*
X776663Y1221413D01*
X776691Y1221323D01*
X776683Y1221276D01*
G03X776666Y1221062I1270J-209D01*
G03X779240I1287J0D01*
G03X779222Y1221277I-1287J1D01*
G01X779214Y1221325D01*
X779242Y1221415D01*
X779531Y1221716D01*
X779621Y1221747D01*
X779668Y1221741D01*
G03X779978I155J1192D01*
G01X780025Y1221747D01*
X780115Y1221716D01*
X780404Y1221415D01*
X780432Y1221325D01*
X780424Y1221277D01*
G03X780406Y1221062I1269J-214D01*
G03X782980I1287J0D01*
G03X782962Y1221277I-1287J1D01*
G01X782954Y1221325D01*
X782982Y1221415D01*
X783271Y1221716D01*
X783361Y1221747D01*
X783408Y1221741D01*
G03X783786Y1221752I154J1192D01*
G01X783834Y1221761D01*
X783929Y1221732D01*
X784233Y1221428D01*
X784262Y1221333D01*
X784253Y1221285D01*
G03X784232Y1221062I1181J-224D01*
G03X785434Y1222264I1202J0D01*
G03X785212Y1222243I2J-1202D01*
G01X785163Y1222234D01*
X785068Y1222263D01*
X784765Y1222567D01*
X784735Y1222662D01*
X784745Y1222710D01*
G03X784758Y1222800I-1183J217D01*
G01Y1222801D01*
G02X784957Y1222978I199J-23D01*
G01X810643D01*
G02X810830Y1222848I0J-200D01*
G01X810837Y1222828D01*
X810840Y1222817D01*
G03X812027Y1221692I1462J354D01*
G03X813765Y1222824I275J1479D01*
G01X813781Y1222892D01*
X813889Y1222978D01*
X840920D01*
G02X841047Y1222933I1J-200D01*
G01X841137Y1222859D01*
X841173Y1222798D01*
X841179Y1222763D01*
G03X854291Y1211796I13112J2355D01*
G03X862546Y1214662I0J13322D01*
G01X862606Y1214710D01*
X862757Y1214701D01*
X881370Y1196088D01*
G03X881512Y1196029I142J141D01*
G01X893090D01*
G02X893230Y1195972I0J-200D01*
G01X893231Y1195971D01*
X896848Y1192354D01*
G02X896907Y1192212I-141J-142D01*
G01Y1146811D01*
X896896Y1146763D01*
X896887Y1146721D01*
X896838Y1146655D01*
X896508Y1146466D01*
G02X896409Y1146439I-100J173D01*
G01X896352D01*
X896306Y1146466D01*
G03X896300Y1146469I-92J-177D01*
G01X896262Y1146490D01*
G03X895548Y1146671I-715J-1321D01*
G01X895525D01*
G03X894045Y1145169I22J-1502D01*
G03X895547Y1143667I1502J0D01*
G01X895548D01*
G03X896306Y1143872I0J1502D01*
G01X896353Y1143900D01*
X896459D01*
X896784Y1143714D01*
G02X896826Y1143682I-99J-174D01*
G01X896848Y1143660D01*
G02X896907Y1143518I-141J-142D01*
G01Y1137041D01*
X896892Y1137004D01*
G03X896776Y1136426I1386J-579D01*
G03X896892Y1135848I1502J1D01*
G01X896907Y1135811D01*
Y1134319D01*
G02X896791Y1134137I-200J0D01*
G01X896408Y1133961D01*
X896293Y1133976D01*
X896248Y1134014D01*
G03X895275Y1134372I-973J-1143D01*
G03X894209Y1133928I0J-1502D01*
G02X894144Y1133885I-141J142D01*
G01X894107Y1133869D01*
X893783D01*
G02X893706Y1133885I1J200D01*
G01X893668Y1133901D01*
G03X892575Y1134372I-1092J-1031D01*
G03Y1131368I0J-1502D01*
G03X893641Y1131812I0J1502D01*
G01X893669Y1131840D01*
X893743Y1131871D01*
X894107D01*
X894181Y1131840D01*
X894209Y1131812D01*
G03X895275Y1131368I1066J1058D01*
G03X896248Y1131726I0J1501D01*
G01X896293Y1131764D01*
X896408Y1131780D01*
X896676Y1131656D01*
X896789Y1131605D01*
G02X896830Y1131579I-86J-181D01*
G02X896893Y1131493I-124J-157D01*
G01X896907Y1131457D01*
Y1110831D01*
X896877Y1110757D01*
X896848Y1110729D01*
X890691Y1104572D01*
G03X890632Y1104445I141J-143D01*
G01X890629Y1104405D01*
X890599Y1104341D01*
X890572Y1104315D01*
X890522Y1104266D01*
G03X890520Y1104264I140J-142D01*
G01X890360Y1104104D01*
X890359Y1104103D01*
G03X890354Y1104098I139J-144D01*
G01X890351Y1104094D01*
X890337Y1104080D01*
X890322Y1104044D01*
G03X890306Y1103966I184J-78D01*
G01Y1096819D01*
X890257Y1096725D01*
G02X890232Y1096688I-177J93D01*
G01X890185Y1096633D01*
X890167Y1096619D01*
G03X889553Y1095407I889J-1212D01*
G03X889979Y1094359I1502J0D01*
G01X889995Y1094343D01*
X890018Y1094304D01*
X890025Y1094282D01*
G02X890033Y1094191I-190J-63D01*
G01X889980Y1093829D01*
X889928Y1093754D01*
X889887Y1093731D01*
G03X889359Y1093236I733J-1311D01*
G01X889338Y1093203D01*
X889275Y1093159D01*
X888965Y1093086D01*
G02X888888Y1093084I-44J195D01*
G01X888847Y1093090D01*
X888814Y1093111D01*
G03X888033Y1093330I-781J-1283D01*
G03Y1090326I0J-1502D01*
G03X889297Y1091014I0J1505D01*
G01X889319Y1091047D01*
X889381Y1091091D01*
X889688Y1091163D01*
G02X889754Y1091167I45J-195D01*
G01X889802Y1091162D01*
X889841Y1091138D01*
G03X890622Y1090919I781J1283D01*
G01X890632D01*
G03X891046Y1090980I-10J1502D01*
G02X891244Y1090930I57J-192D01*
G01X896903Y1085271D01*
G02X896941Y1085218I-141J-141D01*
G01X896942Y1085217D01*
G02X896962Y1085129I-180J-87D01*
G01Y1084050D01*
G03X896984Y1083959I200J0D01*
G01X897016Y1083896D01*
Y1083855D01*
X897019Y1083823D01*
Y1079422D01*
G02X896936Y1079260I-200J0D01*
G03Y1076824I879J-1218D01*
G02X897019Y1076662I-117J-162D01*
G01Y1072598D01*
G03X897078Y1072456I200J0D01*
G01X900939Y1068595D01*
G02X900977Y1068542I-141J-141D01*
G01X900978Y1068541D01*
G02X900998Y1068453I-180J-87D01*
G01Y1028528D01*
G02X900912Y1028364I-200J0D01*
G01X900820Y1028300D01*
X900818D01*
X900596Y1028147D01*
X900497Y1028136D01*
X900450Y1028155D01*
G03X899888Y1028264I-562J-1395D01*
G01X899887D01*
G03Y1025260I0J-1502D01*
G03X900449Y1025369I0J1503D01*
G01X900496Y1025388D01*
X900594Y1025377D01*
X900819Y1025224D01*
X900910Y1025163D01*
G02X900985Y1025068I-112J-166D01*
G01X900998Y1025033D01*
Y1024974D01*
G02X900912Y1024810I-200J0D01*
G01X900820Y1024746D01*
X900818D01*
X900596Y1024593D01*
X900497Y1024582D01*
X900450Y1024601D01*
G03X899888Y1024710I-562J-1395D01*
G01X899887D01*
G03Y1021706I0J-1502D01*
G03X900449Y1021815I0J1503D01*
G01X900496Y1021834D01*
X900594Y1021823D01*
X900819Y1021670D01*
X900910Y1021609D01*
G02X900985Y1021514I-112J-166D01*
G01X900998Y1021479D01*
Y1019696D01*
X900970Y1019626D01*
X900944Y1019599D01*
X900936Y1019589D01*
X898930Y1017583D01*
G02X898788Y1017524I-142J141D01*
G01X880496D01*
G02X880326Y1017618I0J200D01*
G01X880118Y1017949D01*
X880113Y1018051D01*
X880136Y1018098D01*
G03X880285Y1018751I-1353J652D01*
G03X877281I-1502J0D01*
G03X877430Y1018098I1502J-1D01*
G01X877453Y1018051D01*
X877448Y1017949D01*
X877240Y1017618D01*
G02X877070Y1017524I-170J106D01*
G01X874421D01*
G02X874245Y1017630I1J200D01*
G01X874053Y1017992D01*
X874059Y1018101D01*
X874090Y1018148D01*
G03X874347Y1018988I-1244J840D01*
G03X871343I-1502J0D01*
G03X871600Y1018148I1501J0D01*
G01X871631Y1018101D01*
X871637Y1017992D01*
X871445Y1017630D01*
G02X871269Y1017524I-177J94D01*
G01X868619D01*
G02X868449Y1017618I0J200D01*
G01X868241Y1017949D01*
X868236Y1018051D01*
X868259Y1018098D01*
G03X868408Y1018751I-1353J652D01*
G03X865404I-1502J0D01*
G03X865553Y1018098I1502J-1D01*
G01X865576Y1018051D01*
X865571Y1017949D01*
X865363Y1017618D01*
G02X865193Y1017524I-170J106D01*
G01X862674D01*
G02X862500Y1017626I0J200D01*
G01X862302Y1017977D01*
X862303Y1018084D01*
X862332Y1018131D01*
G03X862549Y1018909I-1286J778D01*
G03X859545I-1502J0D01*
G03X859552Y1018767I1502J3D01*
G01X859558Y1018704D01*
X859495Y1018594D01*
X859097Y1018407D01*
G02X858871Y1018446I-85J181D01*
G01X856789Y1020528D01*
G03X856647Y1020587I-142J-141D01*
G01X849543D01*
G02X849362Y1020701I0J200D01*
G01X849183Y1021081D01*
X849196Y1021195D01*
X849233Y1021240D01*
G03X849572Y1022190I-1162J950D01*
G03X846568I-1502J0D01*
G03X846907Y1021240I1501J0D01*
G01X846944Y1021195D01*
X846957Y1021081D01*
X846778Y1020701D01*
G02X846597Y1020587I-181J86D01*
G01X826039D01*
G03X825897Y1020528I0J-200D01*
G01X822234Y1016865D01*
G02X822093Y1016806I-142J141D01*
G01X671213D01*
G02X671072Y1016865I1J200D01*
G01X650723Y1037214D01*
G02X650721Y1037242I198J28D01*
G01Y1060284D01*
G02X650780Y1060425I200J-1D01*
G01X650802Y1060447D01*
Y1073885D01*
X650897Y1073997D01*
X650971Y1074008D01*
G03Y1076384I-184J1188D01*
G01X650897Y1076395D01*
X650802Y1076507D01*
Y1077625D01*
X650897Y1077737D01*
X650971Y1077748D01*
G03Y1080124I-184J1188D01*
G01X650897Y1080135D01*
X650802Y1080247D01*
Y1081280D01*
X650898Y1081392D01*
X650973Y1081403D01*
G03Y1083951I-187J1274D01*
G01X650898Y1083962D01*
X650802Y1084074D01*
Y1085020D01*
X650898Y1085132D01*
X650973Y1085143D01*
G03Y1087691I-187J1274D01*
G01X650898Y1087702D01*
X650802Y1087814D01*
Y1088846D01*
X650897Y1088958D01*
X650971Y1088969D01*
G03Y1091345I-184J1188D01*
G01X650897Y1091356D01*
X650802Y1091468D01*
Y1092586D01*
X650897Y1092698D01*
X650971Y1092709D01*
G03Y1095085I-184J1188D01*
G01X650897Y1095096D01*
X650802Y1095208D01*
Y1096326D01*
X650897Y1096438D01*
X650971Y1096449D01*
G03Y1098825I-184J1188D01*
G01X650897Y1098836D01*
X650802Y1098948D01*
Y1099979D01*
X650898Y1100091D01*
X650973Y1100102D01*
G03Y1102650I-187J1274D01*
G01X650898Y1102661D01*
X650802Y1102773D01*
Y1103720D01*
X650898Y1103832D01*
X650973Y1103843D01*
G03Y1106391I-187J1274D01*
G01X650898Y1106402D01*
X650802Y1106514D01*
Y1107547D01*
X650897Y1107659D01*
X650971Y1107670D01*
G03Y1110046I-184J1188D01*
G01X650897Y1110057D01*
X650802Y1110169D01*
Y1129375D01*
G03X650743Y1129516I-200J-1D01*
G01X650721Y1129538D01*
Y1134500D01*
G03X650722Y1134544I-1201J49D01*
G01Y1135549D01*
G02X650781Y1135691I200J0D01*
G01X651136Y1136046D01*
G03X651165Y1136074I-820J879D01*
G01X651168Y1136077D01*
X651181Y1136089D01*
X651197Y1136105D01*
G02X651339Y1136164I142J-141D01*
G01X651344D01*
X651630Y1136158D01*
G02X651765Y1136102I-4J-200D01*
G01X651769Y1136098D01*
X651799Y1136066D01*
G03X652656Y1135707I857J844D01*
G01X652657D01*
G03X653857Y1136834I0J1202D01*
G01X653859Y1136878D01*
G03X653860Y1136907I-1201J56D01*
G01Y1136912D01*
G03X653472Y1137797I-1204J0D01*
G01X653441Y1137825D01*
X653408Y1137899D01*
X653407Y1137948D01*
Y1137956D01*
X653406Y1138019D01*
X653405Y1138078D01*
Y1138080D01*
X653404Y1138127D01*
Y1138140D01*
X653402Y1138205D01*
Y1138228D01*
G02X653461Y1138370I200J0D01*
G01X653475Y1138384D01*
X653482Y1138390D01*
X653507Y1138415D01*
X653580Y1138445D01*
X653999D01*
G03X654044Y1138444I49J1201D01*
G01X655332D01*
X655433Y1138374D01*
X655456Y1138315D01*
G03X655458Y1138310I186J72D01*
G01X655538Y1138127D01*
X655535Y1138125D01*
X655578Y1138021D01*
X655552Y1137901D01*
X655506Y1137857D01*
G03X655096Y1136909I891J-948D01*
G03X657700I1302J0D01*
G03X657397Y1137744I-1302J0D01*
G01X657375Y1137771D01*
X657345Y1137849D01*
G02X657332Y1137922I187J71D01*
G01X657333Y1137955D01*
G03X657318Y1138034I-200J3D01*
G01X657302Y1138071D01*
G02X657303Y1138225I185J76D01*
G01X657318Y1138262D01*
G02X657388Y1138348I184J-78D01*
G01Y1138349D01*
X657474Y1138408D01*
G02X657546Y1138440I116J-163D01*
G01X657567Y1138444D01*
X659072D01*
X659173Y1138374D01*
X659196Y1138315D01*
G03X659198Y1138310I186J72D01*
G01X659278Y1138127D01*
X659275Y1138125D01*
X659318Y1138021D01*
X659292Y1137901D01*
X659246Y1137857D01*
G03X658836Y1136909I891J-948D01*
G03X661440I1302J0D01*
G03X661137Y1137744I-1302J0D01*
G01X661115Y1137771D01*
X661085Y1137849D01*
G02X661072Y1137922I187J71D01*
G01X661073Y1137955D01*
G03X661058Y1138034I-200J3D01*
G01X661042Y1138071D01*
G02X661043Y1138225I185J76D01*
G01X661058Y1138262D01*
G02X661128Y1138348I184J-78D01*
G01Y1138349D01*
X661214Y1138408D01*
G02X661286Y1138440I116J-163D01*
G01X661307Y1138444D01*
X662812D01*
X662913Y1138374D01*
X662936Y1138315D01*
G03X662938Y1138310I186J72D01*
G01X663018Y1138127D01*
X663015Y1138125D01*
X663058Y1138021D01*
X663032Y1137901D01*
X662986Y1137857D01*
G03X662576Y1136909I891J-948D01*
G03X665180I1302J0D01*
G03X664877Y1137744I-1302J0D01*
G01X664855Y1137771D01*
X664825Y1137849D01*
G02X664812Y1137922I187J71D01*
G01X664813Y1137955D01*
G03X664798Y1138034I-200J3D01*
G01X664782Y1138071D01*
G02X664783Y1138225I185J76D01*
G01X664798Y1138262D01*
G02X664868Y1138348I184J-78D01*
G01Y1138349D01*
X664954Y1138408D01*
G02X665026Y1138440I116J-163D01*
G01X665047Y1138444D01*
X666552D01*
X666653Y1138374D01*
X666676Y1138315D01*
G03X666678Y1138310I186J72D01*
G01X666758Y1138127D01*
X666755Y1138125D01*
X666798Y1138021D01*
X666772Y1137901D01*
X666726Y1137857D01*
G03X666316Y1136909I891J-948D01*
G03X668920I1302J0D01*
G03X668617Y1137744I-1302J0D01*
G01X668595Y1137771D01*
X668565Y1137849D01*
G02X668552Y1137922I187J71D01*
G01X668553Y1137955D01*
G03X668538Y1138034I-200J3D01*
G01X668522Y1138071D01*
G02X668523Y1138225I185J76D01*
G01X668538Y1138262D01*
G02X668608Y1138348I184J-78D01*
G01Y1138349D01*
X668694Y1138408D01*
G02X668766Y1138440I116J-163D01*
G01X668787Y1138444D01*
X670292D01*
X670393Y1138374D01*
X670416Y1138315D01*
G03X670418Y1138310I186J72D01*
G01X670498Y1138127D01*
X670495Y1138125D01*
X670538Y1138021D01*
X670512Y1137901D01*
X670466Y1137857D01*
G03X670056Y1136909I891J-948D01*
G03X672660I1302J0D01*
G03X672357Y1137744I-1302J0D01*
G01X672335Y1137771D01*
X672305Y1137849D01*
G02X672292Y1137922I187J71D01*
G01X672293Y1137955D01*
G03X672278Y1138034I-200J3D01*
G01X672262Y1138071D01*
G02X672263Y1138225I185J76D01*
G01X672278Y1138262D01*
G02X672348Y1138348I184J-78D01*
G01Y1138349D01*
X672434Y1138408D01*
G02X672506Y1138440I116J-163D01*
G01X672527Y1138444D01*
X674032D01*
X674133Y1138374D01*
X674156Y1138315D01*
G03X674158Y1138310I186J72D01*
G01X674238Y1138127D01*
X674235Y1138125D01*
X674278Y1138021D01*
X674252Y1137901D01*
X674206Y1137857D01*
G03X673796Y1136909I891J-948D01*
G03X676400I1302J0D01*
G03X676097Y1137744I-1302J0D01*
G01X676075Y1137771D01*
X676045Y1137849D01*
G02X676032Y1137922I187J71D01*
G01X676033Y1137955D01*
G03X676018Y1138034I-200J3D01*
G01X676002Y1138071D01*
G02X676003Y1138225I185J76D01*
G01X676018Y1138262D01*
G02X676088Y1138348I184J-78D01*
G01Y1138349D01*
X676174Y1138408D01*
G02X676246Y1138440I116J-163D01*
G01X676267Y1138444D01*
X677772D01*
X677873Y1138374D01*
X677896Y1138315D01*
G03X677898Y1138310I186J72D01*
G01X677978Y1138127D01*
X677975Y1138125D01*
X678018Y1138021D01*
X677992Y1137901D01*
X677946Y1137857D01*
G03X677536Y1136909I891J-948D01*
G03X680140I1302J0D01*
G03X679837Y1137744I-1302J0D01*
G01X679815Y1137771D01*
X679785Y1137849D01*
G02X679772Y1137922I187J71D01*
G01X679773Y1137955D01*
G03X679758Y1138034I-200J3D01*
G01X679742Y1138071D01*
G02X679743Y1138225I185J76D01*
G01X679758Y1138262D01*
G02X679828Y1138348I184J-78D01*
G01Y1138349D01*
X679914Y1138408D01*
G02X679986Y1138440I116J-163D01*
G01X680007Y1138444D01*
X681513D01*
X681614Y1138374D01*
X681637Y1138315D01*
G03X681639Y1138310I186J72D01*
G01X681719Y1138127D01*
X681716Y1138125D01*
X681759Y1138021D01*
X681733Y1137901D01*
X681687Y1137857D01*
G03X681277Y1136909I891J-948D01*
G03X683881I1302J0D01*
G03X683578Y1137744I-1302J0D01*
G01X683556Y1137771D01*
X683526Y1137849D01*
G02X683513Y1137922I187J71D01*
G01X683514Y1137955D01*
G03X683499Y1138034I-200J3D01*
G01X683483Y1138071D01*
G02X683484Y1138225I185J76D01*
G01X683499Y1138262D01*
G02X683569Y1138348I184J-78D01*
G01Y1138349D01*
X683655Y1138408D01*
G02X683727Y1138440I116J-163D01*
G01X683748Y1138444D01*
X685253D01*
X685354Y1138374D01*
X685377Y1138315D01*
G03X685379Y1138310I186J72D01*
G01X685459Y1138127D01*
X685456Y1138125D01*
X685499Y1138021D01*
X685473Y1137901D01*
X685427Y1137857D01*
G03X685017Y1136909I891J-948D01*
G03X687621I1302J0D01*
G03X687318Y1137744I-1302J0D01*
G01X687296Y1137771D01*
X687266Y1137849D01*
G02X687253Y1137922I187J71D01*
G01X687254Y1137955D01*
G03X687239Y1138034I-200J3D01*
G01X687223Y1138071D01*
G02X687224Y1138225I185J76D01*
G01X687239Y1138262D01*
G02X687309Y1138348I184J-78D01*
G01Y1138349D01*
X687395Y1138408D01*
G02X687467Y1138440I116J-163D01*
G01X687488Y1138444D01*
X692733D01*
X692834Y1138374D01*
X692857Y1138315D01*
G03X692859Y1138310I186J72D01*
G01X692939Y1138127D01*
X692936Y1138125D01*
X692979Y1138021D01*
X692953Y1137901D01*
X692907Y1137857D01*
G03X692497Y1136909I891J-948D01*
G03X695101I1302J0D01*
G03X694798Y1137744I-1302J0D01*
G01X694776Y1137771D01*
X694746Y1137849D01*
G02X694733Y1137922I187J71D01*
G01X694734Y1137955D01*
G03X694719Y1138034I-200J3D01*
G01X694703Y1138071D01*
G02X694704Y1138225I185J76D01*
G01X694719Y1138262D01*
G02X694789Y1138348I184J-78D01*
G01Y1138349D01*
X694875Y1138408D01*
G02X694947Y1138440I116J-163D01*
G01X694968Y1138444D01*
X696473D01*
X696574Y1138374D01*
X696597Y1138315D01*
G03X696599Y1138310I186J72D01*
G01X696679Y1138127D01*
X696676Y1138125D01*
X696719Y1138021D01*
X696693Y1137901D01*
X696647Y1137857D01*
G03X696237Y1136909I891J-948D01*
G03X698841I1302J0D01*
G03X698538Y1137744I-1302J0D01*
G01X698516Y1137771D01*
X698486Y1137849D01*
G02X698473Y1137922I187J71D01*
G01X698474Y1137955D01*
G03X698459Y1138034I-200J3D01*
G01X698443Y1138071D01*
G02X698444Y1138225I185J76D01*
G01X698459Y1138262D01*
G02X698529Y1138348I184J-78D01*
G01Y1138349D01*
X698615Y1138408D01*
G02X698687Y1138440I116J-163D01*
G01X698708Y1138444D01*
X700213D01*
X700314Y1138374D01*
X700337Y1138315D01*
G03X700339Y1138310I186J72D01*
G01X700419Y1138127D01*
X700416Y1138125D01*
X700459Y1138021D01*
X700433Y1137901D01*
X700387Y1137857D01*
G03X699977Y1136909I891J-948D01*
G03X702581I1302J0D01*
G03X702278Y1137744I-1302J0D01*
G01X702256Y1137771D01*
X702226Y1137849D01*
G02X702213Y1137922I187J71D01*
G01X702214Y1137955D01*
G03X702199Y1138034I-200J3D01*
G01X702183Y1138071D01*
G02X702184Y1138225I185J76D01*
G01X702199Y1138262D01*
G02X702269Y1138348I184J-78D01*
G01Y1138349D01*
X702355Y1138408D01*
G02X702427Y1138440I116J-163D01*
G01X702448Y1138444D01*
X703954D01*
X704055Y1138374D01*
X704078Y1138315D01*
G03X704080Y1138310I186J72D01*
G01X704160Y1138127D01*
X704157Y1138125D01*
X704200Y1138021D01*
X704174Y1137901D01*
X704128Y1137857D01*
G03X703718Y1136909I891J-948D01*
G03X706322I1302J0D01*
G03X706019Y1137744I-1302J0D01*
G01X705997Y1137771D01*
X705967Y1137849D01*
G02X705954Y1137922I187J71D01*
G01X705955Y1137955D01*
G03X705940Y1138034I-200J3D01*
G01X705924Y1138071D01*
G02X705925Y1138225I185J76D01*
G01X705940Y1138262D01*
G02X706010Y1138348I184J-78D01*
G01Y1138349D01*
X706096Y1138408D01*
G02X706168Y1138440I116J-163D01*
G01X706189Y1138444D01*
X707694D01*
X707795Y1138374D01*
X707818Y1138315D01*
G03X707820Y1138310I186J72D01*
G01X707900Y1138127D01*
X707897Y1138125D01*
X707940Y1138021D01*
X707914Y1137901D01*
X707868Y1137857D01*
G03X707458Y1136909I891J-948D01*
G03X710062I1302J0D01*
G03X709759Y1137744I-1302J0D01*
G01X709737Y1137771D01*
X709707Y1137849D01*
G02X709694Y1137922I187J71D01*
G01X709695Y1137955D01*
G03X709680Y1138034I-200J3D01*
G01X709664Y1138071D01*
G02X709665Y1138225I185J76D01*
G01X709680Y1138262D01*
G02X709750Y1138348I184J-78D01*
G01Y1138349D01*
X709836Y1138408D01*
G02X709908Y1138440I116J-163D01*
G01X709929Y1138444D01*
X711434D01*
X711535Y1138374D01*
X711558Y1138315D01*
G03X711560Y1138310I186J72D01*
G01X711640Y1138127D01*
X711637Y1138125D01*
X711680Y1138021D01*
X711654Y1137901D01*
X711608Y1137857D01*
G03X711198Y1136909I891J-948D01*
G03X713802I1302J0D01*
G03X713499Y1137744I-1302J0D01*
G01X713477Y1137771D01*
X713447Y1137849D01*
G02X713434Y1137922I187J71D01*
G01X713435Y1137955D01*
G03X713420Y1138034I-200J3D01*
G01X713404Y1138071D01*
G02X713405Y1138225I185J76D01*
G01X713420Y1138262D01*
G02X713490Y1138348I184J-78D01*
G01Y1138349D01*
X713576Y1138408D01*
G02X713648Y1138440I116J-163D01*
G01X713669Y1138444D01*
X715174D01*
X715275Y1138374D01*
X715298Y1138315D01*
G03X715300Y1138310I186J72D01*
G01X715380Y1138127D01*
X715377Y1138125D01*
X715420Y1138021D01*
X715394Y1137901D01*
X715348Y1137857D01*
G03X714938Y1136909I891J-948D01*
G03X717542I1302J0D01*
G03X717239Y1137744I-1302J0D01*
G01X717217Y1137771D01*
X717187Y1137849D01*
G02X717174Y1137922I187J71D01*
G01X717175Y1137955D01*
G03X717160Y1138034I-200J3D01*
G01X717144Y1138071D01*
G02X717145Y1138225I185J76D01*
G01X717160Y1138262D01*
G02X717230Y1138348I184J-78D01*
G01Y1138349D01*
X717316Y1138408D01*
G02X717388Y1138440I116J-163D01*
G01X717409Y1138444D01*
X718914D01*
X719015Y1138374D01*
X719038Y1138315D01*
G03X719040Y1138310I186J72D01*
G01X719120Y1138127D01*
X719117Y1138125D01*
X719160Y1138021D01*
X719134Y1137901D01*
X719088Y1137857D01*
G03X718678Y1136909I891J-948D01*
G03X721282I1302J0D01*
G03X720979Y1137744I-1302J0D01*
G01X720957Y1137771D01*
X720927Y1137849D01*
G02X720914Y1137922I187J71D01*
G01X720915Y1137955D01*
G03X720900Y1138034I-200J3D01*
G01X720884Y1138071D01*
G02X720885Y1138225I185J76D01*
G01X720900Y1138262D01*
G02X720970Y1138348I184J-78D01*
G01Y1138349D01*
X721056Y1138408D01*
G02X721128Y1138440I116J-163D01*
G01X721149Y1138444D01*
X722654D01*
X722755Y1138374D01*
X722778Y1138315D01*
G03X722780Y1138310I186J72D01*
G01X722860Y1138127D01*
X722857Y1138125D01*
X722900Y1138021D01*
X722874Y1137901D01*
X722828Y1137857D01*
G03X722418Y1136909I891J-948D01*
G03X725022I1302J0D01*
G03X724719Y1137744I-1302J0D01*
G01X724697Y1137771D01*
X724667Y1137849D01*
G02X724654Y1137922I187J71D01*
G01X724655Y1137955D01*
G03X724640Y1138034I-200J3D01*
G01X724624Y1138071D01*
G02X724625Y1138225I185J76D01*
G01X724640Y1138262D01*
G02X724710Y1138348I184J-78D01*
G01Y1138349D01*
X724796Y1138408D01*
G02X724868Y1138440I116J-163D01*
G01X724889Y1138444D01*
X726457D01*
X726460D01*
X726468Y1138445D01*
X726872D01*
G03X727014Y1138504I0J200D01*
G01X727291Y1138781D01*
X727294Y1138783D01*
G03X727307Y1138796I-843J856D01*
G01X727549Y1139038D01*
Y1139039D01*
X728283Y1139773D01*
X728286Y1139775D01*
G03X728332Y1139821I-827J873D01*
G01X728334Y1139824D01*
X729321Y1140811D01*
G02X729420Y1140865I141J-141D01*
G02X729533Y1140857I43J-195D01*
G01X729817Y1140750D01*
G02X729905Y1140686I-69J-188D01*
G01X729906Y1140685D01*
X729984Y1140581D01*
X730004Y1140531D01*
X730007Y1140505D01*
G03X731191Y1139447I1194J145D01*
G01X731201D01*
G03X732403Y1140649I0J1202D01*
G03X731210Y1141851I-1202J0D01*
G01X731198D01*
G03X730780Y1141776I0J-1202D01*
G02X730597Y1141798I-70J187D01*
G01X730449Y1141900D01*
X730447D01*
X730323Y1141987D01*
X730298Y1142012D01*
X730269Y1142040D01*
X730239Y1142114D01*
Y1142888D01*
G02X730325Y1143052I200J0D01*
G01X730407Y1143109D01*
X730595Y1143238D01*
G02X730778Y1143260I113J-165D01*
G03X731199Y1143184I421J1129D01*
G01X731201D01*
G03Y1145594I0J1205D01*
G01X731199D01*
G03X730778Y1145518I0J-1205D01*
G02X730684Y1145507I-70J187D01*
G01X730635Y1145513D01*
X730408Y1145669D01*
X730406D01*
X730325Y1145726D01*
G02X730239Y1145890I114J164D01*
G01Y1146628D01*
G02X730325Y1146792I200J0D01*
G01X730407Y1146849D01*
X730595Y1146978D01*
G02X730778Y1147000I113J-165D01*
G03X731199Y1146924I421J1129D01*
G01X731201D01*
G03Y1149334I0J1205D01*
G01X731199D01*
G03X730778Y1149258I0J-1205D01*
G02X730684Y1149247I-70J187D01*
G01X730635Y1149253D01*
X730408Y1149409D01*
X730406D01*
X730325Y1149466D01*
G02X730239Y1149630I114J164D01*
G01Y1150368D01*
G02X730325Y1150532I200J0D01*
G01X730407Y1150589D01*
X730595Y1150718D01*
G02X730778Y1150740I113J-165D01*
G03X731199Y1150664I421J1129D01*
G01X731201D01*
G03Y1153074I0J1205D01*
G01X731199D01*
G03X730778Y1152998I0J-1205D01*
G02X730684Y1152987I-70J187D01*
G01X730635Y1152993D01*
X730408Y1153149D01*
X730406D01*
X730325Y1153206D01*
G02X730239Y1153370I114J164D01*
G01Y1154109D01*
G02X730325Y1154273I200J0D01*
G01X730407Y1154330D01*
X730595Y1154459D01*
G02X730778Y1154481I113J-165D01*
G03X731199Y1154405I421J1129D01*
G01X731201D01*
G03Y1156815I0J1205D01*
G01X731199D01*
G03X730778Y1156739I0J-1205D01*
G02X730684Y1156728I-70J187D01*
G01X730635Y1156734D01*
X730408Y1156890D01*
X730406D01*
X730325Y1156947D01*
G02X730239Y1157111I114J164D01*
G01Y1157849D01*
G02X730325Y1158013I200J0D01*
G01X730407Y1158070D01*
X730595Y1158199D01*
G02X730778Y1158221I113J-165D01*
G03X731199Y1158145I421J1129D01*
G01X731201D01*
G03Y1160555I0J1205D01*
G01X731199D01*
G03X730778Y1160479I0J-1205D01*
G02X730684Y1160468I-70J187D01*
G01X730635Y1160474D01*
X730408Y1160630D01*
X730406D01*
X730325Y1160687D01*
G02X730239Y1160851I114J164D01*
G01Y1165329D01*
G02X730325Y1165493I200J0D01*
G01X730407Y1165550D01*
X730595Y1165679D01*
G02X730778Y1165701I113J-165D01*
G03X731199Y1165625I421J1129D01*
G01X731201D01*
G03Y1168035I0J1205D01*
G01X731199D01*
G03X730778Y1167959I0J-1205D01*
G02X730684Y1167948I-70J187D01*
G01X730635Y1167954D01*
X730408Y1168110D01*
X730406D01*
X730325Y1168167D01*
G02X730239Y1168331I114J164D01*
G01Y1169069D01*
G02X730325Y1169233I200J0D01*
G01X730407Y1169290D01*
X730595Y1169419D01*
G02X730778Y1169441I113J-165D01*
G03X731199Y1169365I421J1129D01*
G01X731201D01*
G03Y1171775I0J1205D01*
G01X731199D01*
G03X730778Y1171699I0J-1205D01*
G02X730684Y1171688I-70J187D01*
G01X730635Y1171694D01*
X730408Y1171850D01*
X730406D01*
X730325Y1171907D01*
G02X730239Y1172071I114J164D01*
G01Y1172809D01*
G02X730325Y1172973I200J0D01*
G01X730407Y1173030D01*
X730595Y1173159D01*
G02X730778Y1173181I113J-165D01*
G03X731199Y1173105I421J1129D01*
G01X731201D01*
G03Y1175515I0J1205D01*
G03X730177Y1174946I0J-1206D01*
G03X730175Y1174944I140J-142D01*
G01X730167Y1174928D01*
X730133Y1174893D01*
G02X730015Y1174834I-143J139D01*
G01X729720Y1174797D01*
G02X729694Y1174795I-28J198D01*
G01X729687D01*
G02X729545Y1174854I0J200D01*
G01X728003Y1176396D01*
G02X727946Y1176563I141J141D01*
G01X727956Y1176642D01*
Y1176644D01*
X727983Y1176872D01*
G02X727984Y1176881I199J-18D01*
G02X728079Y1177020I197J-33D01*
G03X728662Y1178051I-620J1031D01*
G03X727460Y1179253I-1202J0D01*
G03X726258Y1178058I0J-1202D01*
G01Y1178050D01*
G03X726267Y1177908I1202J5D01*
G01X726268Y1177896D01*
Y1177879D01*
G02X726068Y1177679I-200J0D01*
G01X726051D01*
X726015Y1177664D01*
G03X725950Y1177621I76J-185D01*
G01X725910Y1177581D01*
G02X725768Y1177522I-142J141D01*
G01X725318D01*
G02X725298Y1177523I0J200D01*
G02X725237Y1177539I20J199D01*
G01X725196Y1177558D01*
X724942Y1177834D01*
X724915Y1177912D01*
X724918Y1177954D01*
G03X724922Y1178051I-1198J98D01*
G03X722518I-1202J0D01*
G03X722522Y1177954I1202J1D01*
G01X722525Y1177912D01*
X722498Y1177834D01*
X722370Y1177695D01*
X722275Y1177593D01*
G02X722239Y1177562I-147J135D01*
G01X722230Y1177556D01*
G02X722119Y1177522I-112J166D01*
G01X721578D01*
G02X721558Y1177523I0J200D01*
G02X721497Y1177539I20J199D01*
G01X721456Y1177558D01*
X721202Y1177834D01*
X721175Y1177912D01*
X721178Y1177954D01*
G03X721182Y1178051I-1198J98D01*
G03X718778I-1202J0D01*
G03X718782Y1177954I1202J1D01*
G01X718785Y1177912D01*
X718758Y1177834D01*
X718630Y1177695D01*
X718535Y1177593D01*
G02X718499Y1177562I-147J135D01*
G01X718490Y1177556D01*
G02X718379Y1177522I-112J166D01*
G01X717838D01*
G02X717818Y1177523I0J200D01*
G02X717757Y1177539I20J199D01*
G01X717716Y1177558D01*
X717462Y1177834D01*
X717435Y1177912D01*
X717438Y1177954D01*
G03X717442Y1178051I-1198J98D01*
G03X715038I-1202J0D01*
G03X715042Y1177954I1202J1D01*
G01X715045Y1177912D01*
X715018Y1177834D01*
X714890Y1177695D01*
X714795Y1177593D01*
G02X714759Y1177562I-147J135D01*
G01X714750Y1177556D01*
G02X714639Y1177522I-112J166D01*
G01X714098D01*
G02X714078Y1177523I0J200D01*
G02X714017Y1177539I20J199D01*
G01X713976Y1177558D01*
X713722Y1177834D01*
X713695Y1177912D01*
X713698Y1177954D01*
G03X713702Y1178051I-1198J98D01*
G03X711298I-1202J0D01*
G03X711302Y1177954I1202J1D01*
G01X711305Y1177912D01*
X711278Y1177834D01*
X711150Y1177695D01*
X711055Y1177593D01*
G02X711019Y1177562I-147J135D01*
G01X711010Y1177556D01*
G02X710899Y1177522I-112J166D01*
G01X710358D01*
G02X710338Y1177523I0J200D01*
G02X710277Y1177539I20J199D01*
G01X710236Y1177558D01*
X709982Y1177834D01*
X709955Y1177912D01*
X709958Y1177954D01*
G03X709962Y1178051I-1198J98D01*
G03X707558I-1202J0D01*
G03X707562Y1177954I1202J1D01*
G01X707565Y1177912D01*
X707538Y1177834D01*
X707410Y1177695D01*
X707315Y1177593D01*
G02X707279Y1177562I-147J135D01*
G01X707270Y1177556D01*
G02X707159Y1177522I-112J166D01*
G01X706618D01*
G02X706598Y1177523I0J200D01*
G02X706537Y1177539I20J199D01*
G01X706496Y1177558D01*
X706242Y1177834D01*
X706215Y1177912D01*
X706218Y1177954D01*
G03X706222Y1178051I-1198J98D01*
G03X703818I-1202J0D01*
G03X703822Y1177954I1202J1D01*
G01X703825Y1177912D01*
X703798Y1177834D01*
X703670Y1177695D01*
X703575Y1177593D01*
G02X703539Y1177562I-147J135D01*
G01X703530Y1177556D01*
G02X703419Y1177522I-112J166D01*
G01X702877D01*
G02X702857Y1177523I0J200D01*
G02X702796Y1177539I20J199D01*
G01X702755Y1177558D01*
X702501Y1177834D01*
X702474Y1177912D01*
X702477Y1177954D01*
G03X702481Y1178051I-1198J98D01*
G03X700077I-1202J0D01*
G03X700081Y1177954I1202J1D01*
G01X700084Y1177912D01*
X700057Y1177834D01*
X699929Y1177695D01*
X699834Y1177593D01*
G02X699798Y1177562I-147J135D01*
G01X699789Y1177556D01*
G02X699678Y1177522I-112J166D01*
G01X699137D01*
G02X699117Y1177523I0J200D01*
G02X699056Y1177539I20J199D01*
G01X699015Y1177558D01*
X698761Y1177834D01*
X698734Y1177912D01*
X698737Y1177954D01*
G03X698741Y1178051I-1198J98D01*
G03X696337I-1202J0D01*
G03X696341Y1177954I1202J1D01*
G01X696344Y1177912D01*
X696317Y1177834D01*
X696189Y1177695D01*
X696094Y1177593D01*
G02X696058Y1177562I-147J135D01*
G01X696049Y1177556D01*
G02X695938Y1177522I-112J166D01*
G01X695397D01*
G02X695377Y1177523I0J200D01*
G02X695316Y1177539I20J199D01*
G01X695275Y1177558D01*
X695021Y1177834D01*
X694994Y1177912D01*
X694997Y1177954D01*
G03X695001Y1178051I-1198J98D01*
G03X692597I-1202J0D01*
G03X692601Y1177954I1202J1D01*
G01X692604Y1177912D01*
X692577Y1177834D01*
X692449Y1177695D01*
X692354Y1177593D01*
G02X692318Y1177562I-147J135D01*
G01X692309Y1177556D01*
G02X692198Y1177522I-112J166D01*
G01X687917D01*
G02X687897Y1177523I0J200D01*
G02X687836Y1177539I20J199D01*
G01X687795Y1177558D01*
X687541Y1177834D01*
X687514Y1177912D01*
X687517Y1177954D01*
G03X687521Y1178051I-1198J98D01*
G03X685117I-1202J0D01*
G03X685121Y1177954I1202J1D01*
G01X685124Y1177912D01*
X685097Y1177834D01*
X684969Y1177695D01*
X684874Y1177593D01*
G02X684838Y1177562I-147J135D01*
G01X684829Y1177556D01*
G02X684718Y1177522I-112J166D01*
G01X684177D01*
G02X684157Y1177523I0J200D01*
G02X684096Y1177539I20J199D01*
G01X684055Y1177558D01*
X683801Y1177834D01*
X683774Y1177912D01*
X683777Y1177954D01*
G03X683781Y1178051I-1198J98D01*
G03X681377I-1202J0D01*
G03X681381Y1177954I1202J1D01*
G01X681384Y1177912D01*
X681357Y1177834D01*
X681229Y1177695D01*
X681134Y1177593D01*
G02X681098Y1177562I-147J135D01*
G01X681089Y1177556D01*
G02X680978Y1177522I-112J166D01*
G01X680436D01*
G02X680416Y1177523I0J200D01*
G02X680355Y1177539I20J199D01*
G01X680314Y1177558D01*
X680060Y1177834D01*
X680033Y1177912D01*
X680036Y1177954D01*
G03X680040Y1178051I-1198J98D01*
G03X677636I-1202J0D01*
G03X677640Y1177954I1202J1D01*
G01X677643Y1177912D01*
X677616Y1177834D01*
X677488Y1177695D01*
X677393Y1177593D01*
G02X677357Y1177562I-147J135D01*
G01X677348Y1177556D01*
G02X677237Y1177522I-112J166D01*
G01X676696D01*
G02X676676Y1177523I0J200D01*
G02X676615Y1177539I20J199D01*
G01X676574Y1177558D01*
X676320Y1177834D01*
X676293Y1177912D01*
X676296Y1177954D01*
G03X676300Y1178051I-1198J98D01*
G03X673896I-1202J0D01*
G03X673900Y1177954I1202J1D01*
G01X673903Y1177912D01*
X673876Y1177834D01*
X673748Y1177695D01*
X673653Y1177593D01*
G02X673617Y1177562I-147J135D01*
G01X673608Y1177556D01*
G02X673497Y1177522I-112J166D01*
G01X672956D01*
G02X672936Y1177523I0J200D01*
G02X672875Y1177539I20J199D01*
G01X672834Y1177558D01*
X672580Y1177834D01*
X672553Y1177912D01*
X672556Y1177954D01*
G03X672560Y1178051I-1198J98D01*
G03X670156I-1202J0D01*
G03X670160Y1177954I1202J1D01*
G01X670163Y1177912D01*
X670136Y1177834D01*
X670008Y1177695D01*
X669913Y1177593D01*
G02X669877Y1177562I-147J135D01*
G01X669868Y1177556D01*
G02X669757Y1177522I-112J166D01*
G01X669216D01*
G02X669196Y1177523I0J200D01*
G02X669135Y1177539I20J199D01*
G01X669094Y1177558D01*
X668840Y1177834D01*
X668813Y1177912D01*
X668816Y1177954D01*
G03X668820Y1178051I-1198J98D01*
G03X666416I-1202J0D01*
G03X666420Y1177954I1202J1D01*
G01X666423Y1177912D01*
X666396Y1177834D01*
X666268Y1177695D01*
X666173Y1177593D01*
G02X666137Y1177562I-147J135D01*
G01X666128Y1177556D01*
G02X666017Y1177522I-112J166D01*
G01X665476D01*
G02X665456Y1177523I0J200D01*
G02X665395Y1177539I20J199D01*
G01X665354Y1177558D01*
X665100Y1177834D01*
X665073Y1177912D01*
X665076Y1177954D01*
G03X665080Y1178051I-1198J98D01*
G03X662676I-1202J0D01*
G03X662680Y1177954I1202J1D01*
G01X662683Y1177912D01*
X662656Y1177834D01*
X662528Y1177695D01*
X662433Y1177593D01*
G02X662397Y1177562I-147J135D01*
G01X662388Y1177556D01*
G02X662277Y1177522I-112J166D01*
G01X661736D01*
G02X661716Y1177523I0J200D01*
G02X661655Y1177539I20J199D01*
G01X661614Y1177558D01*
X661360Y1177834D01*
X661333Y1177912D01*
X661336Y1177954D01*
G03X661340Y1178051I-1198J98D01*
G03X658936I-1202J0D01*
G03X658940Y1177954I1202J1D01*
G01X658943Y1177912D01*
X658916Y1177834D01*
X658788Y1177695D01*
X658693Y1177593D01*
G02X658657Y1177562I-147J135D01*
G01X658648Y1177556D01*
G02X658537Y1177522I-112J166D01*
G01X657996D01*
G02X657976Y1177523I0J200D01*
G02X657915Y1177539I20J199D01*
G01X657874Y1177558D01*
X657620Y1177834D01*
X657593Y1177912D01*
X657596Y1177954D01*
G03X657600Y1178051I-1198J98D01*
G03X656398Y1179253I-1202J0D01*
G03X655619Y1178967I0J-1204D01*
G01X655617Y1178965D01*
X655551Y1178911D01*
G02X655424Y1178866I-126J155D01*
G01X655418D01*
X655149Y1178870D01*
G02X655011Y1178929I4J200D01*
G01X654900Y1179040D01*
G03X654888Y1179052I-855J-843D01*
G01X654108Y1179832D01*
G02X654054Y1179933I142J141D01*
G01X654048Y1179961D01*
Y1184042D01*
G03X654047Y1184085I-1202J-6D01*
G01Y1186977D01*
G03X654048Y1187021I-1201J49D01*
G01Y1187782D01*
G03X654047Y1187825I-1202J-6D01*
G01Y1192272D01*
G03X654032Y1192348I-200J0D01*
G01X654020Y1192377D01*
G02X654005Y1192453I185J76D01*
G01Y1219465D01*
G02X654069Y1219611I200J-1D01*
G01X654315Y1219840D01*
X654393Y1219867D01*
X654435Y1219863D01*
G03X654527Y1219860I85J1199D01*
G03X655729Y1221062I0J1202D01*
G03X655721Y1221204I-1202J3D01*
G01X655715Y1221251D01*
X655746Y1221339D01*
X656047Y1221626D01*
X656136Y1221653D01*
X656183Y1221646D01*
G03X656397Y1221628I216J1285D01*
G03X656611Y1221646I-2J1304D01*
G01X656659Y1221654D01*
X656748Y1221626D01*
X657049Y1221339D01*
X657080Y1221252D01*
X657074Y1221204D01*
G03X657066Y1221062I1194J-139D01*
G03X659470I1202J0D01*
G03X659450Y1221283I-1202J3D01*
G01X659440Y1221332D01*
X659469Y1221425D01*
X659774Y1221730D01*
X659867Y1221758D01*
X659916Y1221749D01*
G03X660360I222J1183D01*
G01X660409Y1221758D01*
X660502Y1221730D01*
X660807Y1221425D01*
X660836Y1221332D01*
X660826Y1221283D01*
G03X660806Y1221062I1182J-218D01*
G03X663210I1202J0D01*
G03X663202Y1221203I-1202J3D01*
G01X663196Y1221251D01*
X663228Y1221338D01*
X663528Y1221625D01*
X663617Y1221653D01*
X663664Y1221645D01*
G03X663746Y1221634I214J1285D01*
G01X663767D01*
X663786Y1221631D01*
G03X664091Y1221646I89J1301D01*
G01X664139Y1221653D01*
X664228Y1221626D01*
X664529Y1221339D01*
X664560Y1221252D01*
X664554Y1221204D01*
G03X664546Y1221062I1194J-139D01*
G03X666950I1202J0D01*
G03X666930Y1221283I-1202J3D01*
G01X666920Y1221332D01*
X666949Y1221425D01*
X667254Y1221730D01*
X667347Y1221758D01*
X667396Y1221749D01*
G03X667840I222J1183D01*
G01X667889Y1221758D01*
X667982Y1221730D01*
X668287Y1221425D01*
X668316Y1221332D01*
X668306Y1221283D01*
G03X668286Y1221062I1182J-218D01*
G03X670690I1202J0D01*
G03X670682Y1221203I-1202J3D01*
G01X670676Y1221251D01*
X670708Y1221338D01*
X671008Y1221625D01*
X671097Y1221653D01*
X671144Y1221645D01*
G03X671226Y1221634I214J1285D01*
G01X671247D01*
X671266Y1221631D01*
G03X671571Y1221646I89J1301D01*
G01X671619Y1221653D01*
X671708Y1221626D01*
X672009Y1221339D01*
X672040Y1221252D01*
X672034Y1221204D01*
G03X672026Y1221062I1194J-139D01*
G03X674430I1202J0D01*
G03X674410Y1221283I-1202J3D01*
G01X674400Y1221332D01*
X674429Y1221425D01*
X674734Y1221730D01*
X674827Y1221758D01*
X674876Y1221749D01*
G03X675320I222J1183D01*
G01X675369Y1221758D01*
X675462Y1221730D01*
X675767Y1221425D01*
X675796Y1221332D01*
X675786Y1221283D01*
G03X675766Y1221062I1182J-218D01*
G03X676968Y1219860I1202J0D01*
G03X677190Y1219881I-2J1202D01*
G01X677239Y1219890D01*
X677332Y1219861D01*
X677637Y1219556D01*
X677666Y1219463D01*
X677657Y1219414D01*
G03X677636Y1219192I1181J-224D01*
G03X680040I1202J0D01*
G03X680019Y1219414I-1202J-2D01*
G01X680010Y1219463D01*
X680039Y1219557D01*
X680343Y1219861D01*
X680438Y1219890D01*
X680486Y1219881D01*
G03X680709Y1219860I224J1181D01*
G03X680931Y1219881I-2J1202D01*
G01X680980Y1219890D01*
X681073Y1219861D01*
X681378Y1219556D01*
X681407Y1219463D01*
X681398Y1219414D01*
G03X681377Y1219192I1181J-224D01*
G03X682579Y1217990I1202J0D01*
G03X683781Y1219188I0J1202D01*
G01Y1219206D01*
G03X683778Y1219294I-1202J3D01*
G01X683774Y1219350D01*
X683824Y1219448D01*
X683931Y1219515D01*
X683932D01*
X684165Y1219660D01*
G02X684257Y1219690I106J-170D01*
G02X684324Y1219683I13J-200D01*
G01X684355Y1219674D01*
G02X684401Y1219654I-56J-192D01*
G03X684623Y1219535I1904J3285D01*
G03X684768Y1219466I1703J3393D01*
G01X684807Y1219449D01*
G03X684928Y1219399I1510J3483D01*
G01X684951Y1219389D01*
X684974Y1219373D01*
X685007Y1219352D01*
X685115Y1219192D01*
X685118Y1219136D01*
G03X685721Y1218148I1201J55D01*
G01X685726Y1218146D01*
X685730Y1218143D01*
G03X686122Y1218006I587J1050D01*
G03X686205Y1217995I199J1186D01*
G01X686206D01*
X686215Y1217994D01*
G03X686227Y1217993I106J1198D01*
G01X686322Y1217989D01*
G03X686398Y1217992I-9J1203D01*
G01X686433Y1217995D01*
G03X687520Y1219134I-114J1197D01*
G01X687523Y1219190D01*
X687579Y1219274D01*
G02X687599Y1219303I174J-99D01*
G01X687618Y1219329D01*
G02X687657Y1219369I161J-118D01*
G01X687680Y1219387D01*
X687707Y1219398D01*
G03X688680Y1219959I-1389J3534D01*
G02X688716Y1219982I125J-156D01*
G03X689270Y1220535I-526J1081D01*
G02X689293Y1220572I180J-86D01*
G03X690112Y1222786I-2975J2359D01*
G01X690115Y1222867D01*
X690230Y1222978D01*
X692243D01*
G37*
G36*
G01X668244Y518759D02*
G03I-577J0D01*
G37*
G36*
G01X665744D02*
G03I-577J0D01*
G37*
G36*
G01X668244Y511672D02*
G03I-577J0D01*
G37*
G36*
G01Y532932D02*
G03I-577J0D01*
G37*
G36*
G01X665744D02*
G03I-577J0D01*
G37*
G36*
G01Y525845D02*
G03I-577J0D01*
G37*
G36*
G01X668244D02*
G03I-577J0D01*
G37*
G36*
G01X665744Y540019D02*
G03I-577J0D01*
G37*
G36*
G01X673044Y518759D02*
G03I-577J0D01*
G37*
G36*
G01Y511672D02*
G03I-577J0D01*
G37*
G36*
G01Y525845D02*
G03I-577J0D01*
G37*
G36*
G01Y532932D02*
G03I-577J0D01*
G37*
G36*
G01X711969Y566752D02*
G03I-577J0D01*
G37*
G36*
G01X716769D02*
G03I-577J0D01*
G37*
G36*
G01X711969Y573839D02*
G03I-577J0D01*
G37*
G36*
G01X716769D02*
G03I-577J0D01*
G37*
G36*
G01X711969Y588012D02*
G03I-577J0D01*
G37*
G36*
G01X716769D02*
G03I-577J0D01*
G37*
G36*
G01Y580925D02*
G03I-577J0D01*
G37*
G36*
G01X711969D02*
G03I-577J0D01*
G37*
G36*
G01X716769Y602185D02*
G03I-577J0D01*
G37*
G36*
G01X711969D02*
G03I-577J0D01*
G37*
G36*
G01Y595098D02*
G03I-577J0D01*
G37*
G36*
G01X716769D02*
G03I-577J0D01*
G37*
G36*
G01X711969Y609271D02*
G03I-577J0D01*
G37*
G36*
G01X716769D02*
G03I-577J0D01*
G37*
G36*
G01Y616358D02*
G03I-577J0D01*
G37*
G36*
G01X711969D02*
G03I-577J0D01*
G37*
G36*
G01X719269Y559665D02*
G03I-577J0D01*
G37*
G36*
G01Y566752D02*
G03I-577J0D01*
G37*
G36*
G01Y573838D02*
G03I-577J0D01*
G37*
G36*
G01Y588011D02*
G03I-577J0D01*
G37*
G36*
G01Y580925D02*
G03I-577J0D01*
G37*
G36*
G01Y602184D02*
G03I-577J0D01*
G37*
G36*
G01Y595098D02*
G03I-577J0D01*
G37*
G36*
G01Y609271D02*
G03I-577J0D01*
G37*
G36*
G01X799468Y54588D02*
X827614D01*
X827756Y54446D01*
Y52733D01*
X827614Y52591D01*
X799468D01*
G03X793531Y46654I0J-5937D01*
G01Y7874D01*
G02X787657Y2000I-5874J0D01*
G01X740413D01*
G02X734539Y7874I0J5874D01*
G01Y45924D01*
X736536D01*
Y7874D01*
G03X740411Y3998I3876J0D01*
G01X787657D01*
G03X791534Y7874I0J3877D01*
G01Y46654D01*
G02X799468Y54588I7934J0D01*
G37*
G36*
G01X739346Y987952D02*
G03I-639J0D01*
G37*
G36*
G01X746312Y1007009D02*
G03I-639J0D01*
G37*
G36*
G01X813300Y810032D02*
G03I-639J0D01*
G37*
G36*
G01X813389Y908161D02*
G03I-577J0D01*
G37*
G36*
G01X816594Y838035D02*
G03I-577J0D01*
G37*
G36*
G01X823040Y915094D02*
G03I-577J0D01*
G37*
G36*
G01X826085Y913869D02*
G03I-577J0D01*
G37*
G36*
G01X818986Y939610D02*
G03I-639J0D01*
G37*
G36*
G01X828771Y949323D02*
G03I-577J0D01*
G37*
G36*
G01X949468Y54588D02*
X978644D01*
X978785Y54447D01*
Y52732D01*
X978644Y52591D01*
X949468D01*
G03X943531Y46654I0J-5937D01*
G01Y7874D01*
G02X937657Y2000I-5874J0D01*
G01X842776D01*
G02X836902Y7874I0J5874D01*
G01Y46539D01*
X838900D01*
Y7874D01*
G03X842776Y3998I3876J0D01*
G01X937657D01*
G03X941534Y7874I0J3877D01*
G01Y46654D01*
G02X949468Y54588I7934J0D01*
G37*
G36*
G01X846232Y895436D02*
G03I-577J0D01*
G37*
G36*
G01X839700Y939654D02*
G03I-577J0D01*
G37*
G36*
G01X849727Y951081D02*
G03I-639J0D01*
G37*
G36*
G01X878194Y749483D02*
G03I-577J0D01*
G37*
G36*
G01X869547Y933640D02*
G03I-639J0D01*
G37*
G36*
G01X867838Y949372D02*
G03I-639J0D01*
G37*
G36*
G01X889184Y785528D02*
G03I-639J0D01*
G37*
G36*
G01X889153Y797602D02*
G03I-639J0D01*
G37*
G36*
G01X901532Y1338290D02*
X1010163D01*
G02X1010305Y1338231I0J-200D01*
G01X1012655Y1335881D01*
G02X1012714Y1335739I-141J-142D01*
G01Y1268142D01*
X1012708Y1268116D01*
G03X1012229Y1265567I18195J-4739D01*
G03X1012102Y1263386I18676J-2182D01*
G03X1012149Y1262065I18802J8D01*
G03X1012708Y1258656I18755J1325D01*
G01X1012714Y1258631D01*
Y1250290D01*
G03X1012773Y1250148I200J0D01*
G01X1027902Y1235019D01*
G02X1027961Y1234877I-141J-142D01*
G01Y1225556D01*
G02X1027878Y1225394I-200J0D01*
G01X1027576Y1225175D01*
X1027483Y1225161D01*
X1027436Y1225176D01*
G03X1026968Y1225251I-469J-1427D01*
G03Y1222247I0J-1502D01*
G03X1027421Y1222317I0J1501D01*
G01X1027436Y1222322D01*
X1027471Y1222327D01*
G02X1027620Y1222291I31J-197D01*
G01X1027878Y1222104D01*
G02X1027961Y1221942I-117J-162D01*
G01Y1221416D01*
X1027955Y1221392D01*
G03X1027896Y1220921I1842J-470D01*
G01Y1215784D01*
G02X1027834Y1215640I-200J1D01*
G01X1027808Y1215615D01*
X1027453Y1215456D01*
G02X1027282Y1215460I-81J183D01*
G01X1027229Y1215486D01*
X1027209Y1215504D01*
G03X1026221Y1215874I-987J-1132D01*
G03Y1212870I0J-1502D01*
G03X1027209Y1213240I1J1502D01*
G01X1027229Y1213258D01*
X1027284Y1213285D01*
G02X1027453Y1213288I88J-180D01*
G01X1027777Y1213143D01*
G02X1027896Y1212960I-81J-183D01*
G01Y1179372D01*
G02X1027799Y1179201I-200J1D01*
G01X1027460Y1178997D01*
X1027356Y1178994D01*
X1027309Y1179019D01*
G03X1026608Y1179193I-702J-1329D01*
G01X1026606D01*
G03X1025104Y1177691I0J-1502D01*
G03X1026549Y1176190I1502J0D01*
G01X1026608Y1176188D01*
G03X1027289Y1176352I-2J1503D01*
G01X1027310Y1176363D01*
X1027360Y1176376D01*
G02X1027512Y1176353I48J-194D01*
G01X1027799Y1176181D01*
G02X1027896Y1176010I-103J-172D01*
G01Y1166772D01*
G02X1027799Y1166601I-200J1D01*
G01X1027460Y1166397D01*
X1027356Y1166394D01*
X1027309Y1166419D01*
G03X1026608Y1166593I-702J-1329D01*
G01X1026606D01*
G03X1025104Y1165091I0J-1502D01*
G03X1026549Y1163590I1502J0D01*
G01X1026608Y1163588D01*
G03X1027289Y1163752I-2J1503D01*
G01X1027310Y1163763D01*
X1027360Y1163776D01*
G02X1027512Y1163753I48J-194D01*
G01X1027799Y1163581D01*
G02X1027896Y1163410I-103J-172D01*
G01Y1154172D01*
G02X1027799Y1154001I-200J1D01*
G01X1027460Y1153797D01*
X1027356Y1153794D01*
X1027309Y1153819D01*
G03X1026608Y1153993I-702J-1329D01*
G01X1026606D01*
G03X1025104Y1152491I0J-1502D01*
G03X1026549Y1150990I1502J0D01*
G01X1026608Y1150988D01*
G03X1027289Y1151152I-2J1503D01*
G01X1027310Y1151163D01*
X1027360Y1151176D01*
G02X1027512Y1151153I48J-194D01*
G01X1027799Y1150981D01*
G02X1027896Y1150810I-103J-172D01*
G01Y1141572D01*
G02X1027799Y1141401I-200J1D01*
G01X1027460Y1141197D01*
X1027356Y1141194D01*
X1027309Y1141219D01*
G03X1026608Y1141393I-702J-1329D01*
G01X1026606D01*
G03X1025104Y1139891I0J-1502D01*
G03X1026549Y1138390I1502J0D01*
G01X1026608Y1138388D01*
G03X1027289Y1138552I-2J1503D01*
G01X1027310Y1138563D01*
X1027360Y1138576D01*
G02X1027512Y1138553I48J-194D01*
G01X1027799Y1138381D01*
G02X1027896Y1138210I-103J-172D01*
G01Y1128972D01*
G02X1027799Y1128801I-200J1D01*
G01X1027460Y1128597D01*
X1027356Y1128594D01*
X1027309Y1128619D01*
G03X1026608Y1128793I-702J-1329D01*
G01X1026606D01*
G03X1025104Y1127291I0J-1502D01*
G03X1026549Y1125790I1502J0D01*
G01X1026608Y1125788D01*
G03X1027289Y1125952I-2J1503D01*
G01X1027310Y1125963D01*
X1027360Y1125976D01*
G02X1027512Y1125953I48J-194D01*
G01X1027799Y1125781D01*
G02X1027896Y1125610I-103J-172D01*
G01Y1119271D01*
G02X1027837Y1119130I-200J1D01*
G01X1024455Y1115748D01*
G02X1024173I-141J142D01*
G01X1024172Y1115749D01*
G03X1023106Y1116193I-1066J-1058D01*
G03X1021604Y1114691I0J-1502D01*
G03X1022048Y1113625I1502J0D01*
G01X1022049Y1113624D01*
G02Y1113342I-142J-141D01*
G01X1019113Y1110406D01*
G02X1019110Y1110403I-143J140D01*
G02X1018999Y1110349I-139J144D01*
G02X1018956Y1110348I-26J198D01*
G01X1018610Y1110375D01*
X1018534Y1110417D01*
X1018508Y1110453D01*
G03X1017297Y1111066I-1211J-890D01*
G03X1015795Y1109564I0J-1502D01*
G03X1016408Y1108353I1503J0D01*
G01X1016444Y1108327D01*
X1016486Y1108251D01*
X1016513Y1107905D01*
G02X1016512Y1107862I-199J-17D01*
G02X1016458Y1107751I-198J28D01*
G02X1016455Y1107748I-143J140D01*
G01X982007Y1073300D01*
X981979Y1073271D01*
X981905Y1073241D01*
X956354D01*
X956272Y1073281D01*
X956243Y1073318D01*
X956050Y1073566D01*
G02X956013Y1073735I157J123D01*
G01Y1073738D01*
G03X956058Y1074102I-1457J365D01*
G01Y1074104D01*
G03X954556Y1075606I-1502J0D01*
G03X953529Y1075200I0J-1502D01*
G01X953501Y1075173D01*
X953431Y1075146D01*
X953081D01*
X953011Y1075173D01*
X952983Y1075200D01*
G03X950929I-1027J-1096D01*
G01X950901Y1075173D01*
X950831Y1075146D01*
X950481D01*
X950411Y1075173D01*
X950383Y1075200D01*
G03X948329I-1027J-1096D01*
G01X948301Y1075173D01*
X948231Y1075146D01*
X947881D01*
X947811Y1075173D01*
X947783Y1075200D01*
G03X945729I-1027J-1096D01*
G01X945701Y1075173D01*
X945631Y1075146D01*
X945281D01*
X945211Y1075173D01*
X945183Y1075200D01*
G03X944156Y1075606I-1027J-1096D01*
G03X942654Y1074104I0J-1502D01*
G01Y1074102D01*
G03X942699Y1073738I1502J1D01*
G01Y1073735D01*
G02X942662Y1073566I-194J-46D01*
G01X942469Y1073318D01*
G02X942311Y1073241I-158J123D01*
G01X941912D01*
G02X941752Y1073321I0J200D01*
G01X941532Y1073617D01*
X941515Y1073708D01*
X941529Y1073755D01*
G03X941591Y1074182I-1439J427D01*
G03X940089Y1075684I-1502J0D01*
G03X939062Y1075278I0J-1502D01*
G01X939034Y1075252D01*
X938965Y1075224D01*
X938613D01*
X938544Y1075252D01*
X938516Y1075278D01*
G03X936462I-1027J-1096D01*
G01X936434Y1075252D01*
X936365Y1075224D01*
X936013D01*
X935944Y1075252D01*
X935916Y1075278D01*
G03X933862I-1027J-1096D01*
G01X933834Y1075252D01*
X933765Y1075224D01*
X933413D01*
X933344Y1075252D01*
X933316Y1075278D01*
G03X932289Y1075684I-1027J-1096D01*
G03X930787Y1074182I0J-1502D01*
G03X930849Y1073755I1501J0D01*
G01X930863Y1073708D01*
X930846Y1073617D01*
X930626Y1073321D01*
G02X930466Y1073241I-160J120D01*
G01X899252D01*
G02X899110Y1073300I0J200D01*
G01X898408Y1074002D01*
G02X898349Y1074144I141J142D01*
G01Y1076564D01*
X898410Y1076662D01*
X898463Y1076687D01*
G03Y1079397I-648J1355D01*
G01X898410Y1079422D01*
X898349Y1079520D01*
Y1086765D01*
G03X898290Y1086907I-200J0D01*
G01X891721Y1093476D01*
G02X891664Y1093644I141J142D01*
G01X891705Y1093948D01*
G02X891762Y1094063I198J-27D01*
G01X891803Y1094104D01*
X891825Y1094117D01*
G03X892557Y1095407I-771J1290D01*
G03X891455Y1096855I-1502J0D01*
G01X891389Y1096873D01*
X891308Y1096980D01*
Y1103552D01*
G02X891367Y1103694I200J0D01*
G01X893582Y1105909D01*
G02X893724Y1105968I142J-141D01*
G01X900906D01*
G02X900922Y1105967I-4J-200D01*
G02X901081Y1105865I-16J-199D01*
G02X901088Y1105852I-172J-101D01*
G01X901240Y1105522D01*
G02X901210Y1105308I-182J-84D01*
G03X900851Y1104333I1143J-975D01*
G01Y1104301D01*
G03X903855I1502J32D01*
G01Y1104324D01*
Y1104333D01*
G03X903496Y1105308I-1502J0D01*
G02X903466Y1105522I152J130D01*
G01X903618Y1105852D01*
G02X903625Y1105865I179J-88D01*
G02X903784Y1105967I175J-97D01*
G02X903800Y1105968I20J-199D01*
G01X915078D01*
G02X915250Y1105870I0J-200D01*
G01X915453Y1105528D01*
X915455Y1105424D01*
X915429Y1105377D01*
G03X915247Y1104659I1322J-717D01*
G03X915369Y1104063I1502J-3D01*
G03X915876Y1103436I1379J597D01*
G01X915896Y1103421D01*
X915928Y1103384D01*
X915939Y1103361D01*
G02X915958Y1103299I-179J-89D01*
G01X916001Y1102969D01*
X915978Y1102890D01*
X915951Y1102857D01*
G03X915608Y1101902I1158J-955D01*
G01Y1101882D01*
G03X915804Y1101161I1502J21D01*
G03X916238Y1100679I1307J741D01*
G01X916251Y1100669D01*
X916277Y1100643D01*
G02X916335Y1100515I-142J-141D01*
G02Y1100487I-200J-14D01*
G01X916307Y1100096D01*
X916249Y1100009D01*
X916201Y1099985D01*
G03X915373Y1098643I674J-1342D01*
G03X918377I1502J0D01*
G03X917747Y1099866I-1502J0D01*
G01X917734Y1099876D01*
X917708Y1099902D01*
G02X917650Y1100030I142J141D01*
G02Y1100058I200J14D01*
G01X917678Y1100449D01*
X917736Y1100536D01*
X917784Y1100560D01*
G03X918612Y1101902I-674J1342D01*
G03X918490Y1102498I-1502J3D01*
G03X917983Y1103125I-1379J-597D01*
G01X917963Y1103140D01*
X917931Y1103177D01*
X917920Y1103200D01*
G02X917901Y1103262I179J89D01*
G01X917858Y1103592D01*
X917881Y1103671D01*
X917908Y1103704D01*
G03X918251Y1104659I-1158J955D01*
G01Y1104679D01*
G03X918146Y1105211I-1502J-20D01*
G03X918069Y1105377I-1399J-548D01*
G02X918072Y1105574I175J96D01*
G01X918248Y1105870D01*
G02X918420Y1105968I172J-102D01*
G01X964883D01*
G02X964899Y1105967I-4J-200D01*
G02X965058Y1105865I-16J-199D01*
G02X965065Y1105852I-172J-101D01*
G01X965217Y1105522D01*
G02X965187Y1105308I-182J-84D01*
G03X964828Y1104333I1143J-975D01*
G01Y1104301D01*
G03X967832I1502J32D01*
G01Y1104324D01*
Y1104333D01*
G03X967473Y1105308I-1502J0D01*
G02X967443Y1105522I152J130D01*
G01X967595Y1105852D01*
G02X967602Y1105865I179J-88D01*
G02X967761Y1105967I175J-97D01*
G02X967777Y1105968I20J-199D01*
G01X971414D01*
G03X971556Y1106027I0J200D01*
G01X973177Y1107648D01*
G02X973220Y1107680I140J-143D01*
G01X973242Y1107693D01*
X973268Y1107700D01*
G03X973838Y1108040I-307J1162D01*
G02X973842Y1108044I143J-139D01*
G01X983103Y1117305D01*
G02X983107Y1117309I143J-139D01*
G03X983447Y1117879I-822J877D01*
G01X983454Y1117905D01*
X983467Y1117927D01*
G02X983499Y1117970I175J-97D01*
G01X986419Y1120889D01*
G03X986478Y1121031I-141J142D01*
G01Y1129958D01*
G02X986577Y1130130I200J-1D01*
G01X986920Y1130332D01*
X987026Y1130333D01*
X987073Y1130307D01*
G03X987804Y1130117I731J1311D01*
G03Y1133121I0J1502D01*
G03X987073Y1132931I0J-1501D01*
G01X987026Y1132905D01*
X986920Y1132906D01*
X986577Y1133108D01*
G02X986478Y1133280I101J173D01*
G01Y1136327D01*
G02X986594Y1136508I200J0D01*
G01X986977Y1136685D01*
X987093Y1136669D01*
X987137Y1136631D01*
G03X988112Y1136272I975J1143D01*
G03Y1139276I0J1502D01*
G03X987137Y1138917I0J-1502D01*
G01X987093Y1138879D01*
X986977Y1138863D01*
X986594Y1139040D01*
G02X986478Y1139221I84J181D01*
G01Y1157844D01*
G02X986537Y1157986I200J0D01*
G01X987397Y1158846D01*
X987523Y1158866D01*
X987581Y1158837D01*
G03X993504Y1157446I5922J11911D01*
G03X1002147Y1160636I1J13302D01*
G03X993513Y1184058I-8634J10120D01*
G03X988402Y1183037I0J-13303D01*
G01X988355Y1183017D01*
X988256Y1183027D01*
X987937Y1183240D01*
G02X987848Y1183406I111J166D01*
G01Y1270219D01*
G03X987789Y1270361I-200J0D01*
G01X972893Y1285257D01*
G03X972751Y1285316I-142J-141D01*
G01X900192D01*
G02X900050Y1285375I0J200D01*
G01X896883Y1288542D01*
G02X896824Y1288684I141J142D01*
G01Y1333582D01*
G02X896883Y1333724I200J0D01*
G01X901390Y1338231D01*
G02X901532Y1338290I142J-141D01*
G37*
G36*
G01X909308Y619120D02*
G03I-577J0D01*
G37*
G36*
G01X900476Y619040D02*
G03I-577J0D01*
G37*
G36*
G01X905432D02*
G03I-577J0D01*
G37*
G36*
G01X911392Y715864D02*
G03I-639J0D01*
G37*
G36*
G01X911994Y944909D02*
G03I-639J0D01*
G37*
G36*
G01X914264Y619120D02*
G03I-577J0D01*
G37*
G36*
G01X915772Y666670D02*
G03I-577J0D01*
G37*
G36*
G01X917925Y679625D02*
G03I-639J0D01*
G37*
G36*
G01X933934Y861994D02*
X937417D01*
G02X937559Y861935I0J-200D01*
G01X938491Y861003D01*
G02X938550Y860861I-141J-142D01*
G01Y857917D01*
G02X938491Y857775I-200J0D01*
G01X928070Y847354D01*
G02X927928Y847295I-142J141D01*
G01X924534D01*
G02X924392Y847354I0J200D01*
G01X923110Y848636D01*
G02X923051Y848778I141J142D01*
G01Y850419D01*
G02X923126Y850575I200J0D01*
G03Y852609I-813J1017D01*
G02X923051Y852765I125J156D01*
G01Y853569D01*
G02X923126Y853725I200J0D01*
G03Y855759I-813J1017D01*
G02X923051Y855915I125J156D01*
G01Y856062D01*
G02X923110Y856204I200J0D01*
G01X923857Y856951D01*
G02X924002Y857009I141J-142D01*
G01X924331Y857003D01*
X924405Y856970D01*
X924433Y856939D01*
G03X925462Y856490I1028J952D01*
G03X926453Y856900I1J1401D01*
G01X926839Y857286D01*
G02X926981Y857345I142J-141D01*
G01X929119D01*
G03X929261Y857404I0J200D01*
G01X929266Y857409D01*
X929370Y857390D01*
G03X929611Y857367I244J1279D01*
G03X930913Y858669I0J1302D01*
G03X930890Y858910I-1302J-3D01*
G01X930881Y858959D01*
X930911Y859054D01*
X933792Y861935D01*
G02X933934Y861994I142J-141D01*
G37*
G36*
G01X925126Y951244D02*
G03I-639J0D01*
G37*
G36*
G01X939976Y809054D02*
X943297D01*
X943412Y808947D01*
X943417Y808867D01*
G03X944916Y807463I1499J98D01*
G03X946224Y808226I0J1503D01*
G01X946247Y808267D01*
X946324Y808320D01*
X946686Y808369D01*
G02X946855Y808312I27J-198D01*
G01X947521Y807646D01*
G02X947580Y807505I-141J-142D01*
G01Y805914D01*
G03X947979Y804616I2306J-1D01*
G02X948014Y804504I-165J-113D01*
G01Y788902D01*
G02X947955Y788760I-200J0D01*
G01X947414Y788219D01*
X947386Y788190D01*
X947312Y788160D01*
X944434D01*
G02X944268Y788249I0J200D01*
G01X944055Y788567D01*
X944045Y788666D01*
X944064Y788713D01*
G03X944178Y789286I-1388J574D01*
G03X941174I-1502J0D01*
G03X941288Y788713I1502J1D01*
G01X941307Y788666D01*
X941297Y788567D01*
X941084Y788249D01*
G02X940918Y788160I-166J111D01*
G01X936247D01*
G02X936105Y788219I0J200D01*
G01X934459Y789865D01*
G02X934400Y790007I141J142D01*
G01Y797297D01*
G02X934409Y797357I200J1D01*
G01X934436Y797441D01*
X934451Y797465D01*
G03Y799129I-1250J832D01*
G01X934436Y799153D01*
X934409Y799237D01*
G02X934400Y799297I191J59D01*
G01Y807157D01*
G02X934459Y807299I200J0D01*
G01X934659Y807499D01*
X934884Y807724D01*
G02X934948Y807767I141J-141D01*
G01X936488Y808405D01*
G02X936636Y808407I77J-185D01*
G01X936929Y808295D01*
X936985Y808243D01*
X937002Y808208D01*
G03X938357Y807354I1355J648D01*
G03X939859Y808855I0J1502D01*
G01Y808938D01*
X939976Y809054D01*
G37*
G36*
G01X943212Y886520D02*
G03I-577J0D01*
G37*
G36*
G01X951834Y727165D02*
G03I-639J0D01*
G37*
G36*
G01X956962Y748412D02*
G03I-639J0D01*
G37*
G36*
G01X953320Y735256D02*
G03I-639J0D01*
G37*
G36*
G01X958113Y764426D02*
G03I-639J0D01*
G37*
G36*
G01X955725Y779798D02*
G03I-639J0D01*
G37*
G36*
G01X956690Y793937D02*
G03I-639J0D01*
G37*
G36*
G01X1097316Y907042D02*
X1194903D01*
G02X1195044Y906983I-1J-200D01*
G01X1195781Y906246D01*
G02X1195840Y906104I-141J-142D01*
G01Y901961D01*
G02X1195781Y901819I-200J0D01*
G01X1192881Y898919D01*
G02X1192739Y898860I-142J141D01*
G01X1189457D01*
G02X1189315Y898919I0J200D01*
G01X1187277Y900957D01*
G03X1187135Y901016I-142J-141D01*
G01X1102174D01*
G03X1102032Y900957I0J-200D01*
G01X1100628Y899553D01*
X1100625Y899551D01*
G03X1100588Y899515I893J-954D01*
G01X1068958Y867885D01*
G02X1068816Y867826I-142J141D01*
G01X1032238D01*
G03X1032096Y867767I0J-200D01*
G01X1014649Y850320D01*
G02X1014507Y850261I-142J141D01*
G01X1007993D01*
G02X1007851Y850320I0J200D01*
G01X1006460Y851711D01*
G03X1006318Y851770I-142J-141D01*
G01X992355D01*
G02X992218Y851824I0J200D01*
G01X991990Y852037D01*
X991958Y852104D01*
X991956Y852143D01*
G03X988958I-1499J-100D01*
G01X988956Y852104D01*
X988924Y852037D01*
X988696Y851824D01*
G02X988559Y851770I-137J146D01*
G01X982396D01*
G03X982254Y851711I0J-200D01*
G01X980771Y850228D01*
G02X980629Y850169I-142J141D01*
G01X975614D01*
G02X975476Y850225I1J200D01*
G03X974437Y850642I-1039J-1086D01*
G03X973836Y850516I1J-1502D01*
G01X973785Y850494D01*
X973674Y850509D01*
X973311Y850799D01*
X973272Y850904D01*
X973283Y850958D01*
G03X973310Y851242I-1475J284D01*
G03X972028Y852728I-1502J0D01*
G01X971983Y852735D01*
X971909Y852784D01*
X971703Y853129D01*
X971695Y853217D01*
X971711Y853260D01*
G03X971801Y853773I-1412J512D01*
G03X968797I-1502J0D01*
G03X970079Y852287I1502J0D01*
G01X970124Y852280D01*
X970198Y852231D01*
X970404Y851886D01*
X970412Y851798D01*
X970396Y851755D01*
G03X970306Y851242I1412J-512D01*
G03X971808Y849740I1502J0D01*
G03X972828Y850140I-1J1502D01*
G02X973137Y849893I136J-147D01*
G03X973068Y849757I1303J-747D01*
G01X973052Y849723D01*
X969502Y846173D01*
G02X969361Y846114I-142J141D01*
G01X969250D01*
G03X968326Y845732I-1J-1306D01*
G01X967211Y844617D01*
G03X966828Y843693I923J-924D01*
G01Y843617D01*
G02X966770Y843476I-200J0D01*
G01X964701Y841407D01*
G03X964554Y841231I925J-922D01*
G01X964543Y841216D01*
X964435Y841108D01*
G03X964399Y841071I918J-930D01*
G02X964394Y841065I-156J125D01*
G01X964113Y840784D01*
G03X964054Y840642I141J-142D01*
G01Y840242D01*
G03X964052Y840184I1304J-74D01*
G01Y838302D01*
G02X963994Y838161I-200J0D01*
G01X959290Y833457D01*
G03X959231Y833315I141J-142D01*
G01Y832400D01*
X959227Y832380D01*
G03X959202Y832123I1281J-254D01*
G01Y827066D01*
G02X959143Y826925I-200J1D01*
G01X958509Y826291D01*
G02X958367Y826232I-142J141D01*
G01X951392D01*
G02X951250Y826291I0J200D01*
G01X950859Y826682D01*
G02X950800Y826824I141J142D01*
G01Y831624D01*
G02X950859Y831766I200J0D01*
G01X952471Y833378D01*
G03X953146Y835009I-1631J1630D01*
G01Y836188D01*
G02X953258Y836367I200J-1D01*
G01X953630Y836551D01*
X953744Y836540D01*
X953789Y836506D01*
G03X954700Y836198I911J1193D01*
G03X956202Y837700I0J1502D01*
G03X955448Y839003I-1503J0D01*
G01X955407Y839026D01*
X955355Y839103D01*
X955307Y839464D01*
G02X955364Y839632I198J26D01*
G01X956192Y840460D01*
G03X956251Y840602I-141J142D01*
G01Y844169D01*
G02X956310Y844311I200J0D01*
G01X956834Y844835D01*
G02X956975Y844894I142J-141D01*
G01X957500D01*
G03X958982Y845433I0J2307D01*
G02X959227Y845443I129J-153D01*
G03X960100Y845163I873J1221D01*
G03X961602Y846665I0J1502D01*
G03X961327Y847531I-1501J0D01*
G01X961285Y847591D01*
X961297Y847736D01*
X975163Y861601D01*
G02X975304Y861660I142J-141D01*
G01X1004266D01*
G03X1005897Y862335I1J2306D01*
G01X1006460Y862898D01*
G02X1006602Y862957I142J-141D01*
G01X1018800D01*
G03X1018942Y863016I0J200D01*
G01X1023745Y867819D01*
G02X1023886Y867878I142J-141D01*
G01X1024384D01*
G03X1026015Y868553I1J2306D01*
G01X1032397Y874935D01*
G02X1032538Y874994I142J-141D01*
G01X1036801D01*
X1036907Y874915D01*
X1036926Y874852D01*
G03X1039800I1437J436D01*
G01X1039819Y874915D01*
X1039925Y874994D01*
X1061500D01*
G03X1062310Y875140I2J2306D01*
G01X1062344Y875153D01*
X1065262D01*
G03X1065404Y875212I0J200D01*
G01X1088493Y898301D01*
G02X1088655Y898358I141J-142D01*
G01X1089010Y898320D01*
X1089087Y898273D01*
X1089112Y898234D01*
G03X1090375Y897545I1263J813D01*
G03X1091877Y899047I0J1502D01*
G03X1091188Y900310I-1502J0D01*
G01X1091149Y900335D01*
X1091102Y900412D01*
X1091064Y900767D01*
G02X1091121Y900929I199J21D01*
G01X1097175Y906983D01*
G02X1097316Y907042I142J-141D01*
G37*
G36*
G01X953316Y886624D02*
G03I-577J0D01*
G37*
G36*
G01X947220Y991360D02*
G03I-577J0D01*
G37*
G36*
G01X963765Y667620D02*
G03I-577J0D01*
G37*
G36*
G01X973716Y667621D02*
G03I-577J0D01*
G37*
G36*
G01X977403Y786563D02*
G03I-639J0D01*
G37*
G36*
G01X977857Y802178D02*
G03I-639J0D01*
G37*
G36*
G01X968958Y826191D02*
G03I-639J0D01*
G37*
G36*
G01X1051831Y54588D02*
X1080886D01*
X1081101Y54373D01*
Y52806D01*
X1080886Y52591D01*
X1051831D01*
G03X1045894Y46654I0J-5937D01*
G01Y7874D01*
G02X1040020Y2000I-5874J0D01*
G01X992776D01*
G02X986902Y7874I0J5874D01*
G01Y46164D01*
X988900D01*
Y7874D01*
G03X992776Y3998I3876J0D01*
G01X1040020D01*
G03X1043896Y7874I0J3876D01*
G01Y46654D01*
G02X1051831Y54588I7935J-1D01*
G37*
G36*
G01X978637Y747437D02*
G03I-577J0D01*
G37*
G36*
G01X984946Y748432D02*
G03I-639J0D01*
G37*
G36*
G01X985531Y868720D02*
G03I-639J0D01*
G37*
G36*
G01X988429Y896596D02*
G03I-639J0D01*
G37*
G36*
G01X989100Y1013841D02*
G03I-639J0D01*
G37*
G36*
G01X1174536Y804430D02*
X1176266D01*
G02X1176407Y804372I0J-200D01*
G01X1181678Y799101D01*
G02X1181737Y798959I-141J-142D01*
G01Y787800D01*
G02X1181678Y787658I-200J0D01*
G01X1176967Y782947D01*
G02X1176825Y782888I-142J141D01*
G01X1103216D01*
G03X1103074Y782829I0J-200D01*
G01X1102702Y782457D01*
X1102663Y782442D01*
G03X1102209Y782147I469J-1219D01*
G01X1046887Y726825D01*
G02X1046745Y726766I-142J141D01*
G01X1028942D01*
G03X1028800Y726707I0J-200D01*
G01X1026528Y724435D01*
G02X1026387Y724376I-142J141D01*
G01X1025456D01*
G03X1024532Y723994I-1J-1306D01*
G01X1015539Y715001D01*
G02X1015397Y714942I-142J141D01*
G01X1013621D01*
G02X1013479Y715001I0J200D01*
G01X1008101Y720379D01*
G02X1008042Y720521I141J142D01*
G01Y723852D01*
G02X1008101Y723994I200J0D01*
G01X1022131Y738024D01*
G02X1022272Y738082I141J-142D01*
G01X1039128D01*
G03X1040759Y738758I-1J2307D01*
G01X1106373Y804372D01*
G02X1106514Y804430I141J-142D01*
G01X1153458D01*
G02X1153636Y804320I0J-200D01*
G01X1153823Y803950D01*
X1153813Y803838D01*
X1153779Y803792D01*
G03X1153483Y802897I1205J-895D01*
G03X1156487I1502J0D01*
G03X1156191Y803792I-1501J0D01*
G01X1156157Y803838D01*
X1156147Y803950D01*
X1156334Y804320D01*
G02X1156512Y804430I178J-90D01*
G01X1171708D01*
G02X1171890Y804312I0J-200D01*
G01X1172063Y803924D01*
X1172045Y803808D01*
X1172005Y803763D01*
G03X1171620Y802759I1117J-1004D01*
G03X1174624I1502J0D01*
G03X1174239Y803763I-1502J0D01*
G01X1174199Y803808D01*
X1174181Y803924D01*
X1174354Y804312D01*
G02X1174536Y804430I182J-82D01*
G37*
G36*
G01X1008981Y761735D02*
G03I-639J0D01*
G37*
G36*
G01X1004178Y762632D02*
G03I-639J0D01*
G37*
G36*
G01X1003473Y777394D02*
G03I-639J0D01*
G37*
G36*
G01X995772Y888503D02*
G03I-639J0D01*
G37*
G36*
G01X1092392Y1136597D02*
X1093434D01*
X1093537Y1136525D01*
X1093559Y1136465D01*
G03X1094783Y1135607I1224J444D01*
G03X1095955Y1136341I0J1303D01*
G01X1095980Y1136394D01*
X1096076Y1136454D01*
X1097340D01*
X1097434Y1136397D01*
X1097460Y1136347D01*
G03X1098523Y1135707I1063J563D01*
G03X1098817Y1135744I-2J1202D01*
G01X1098869Y1135757D01*
X1098970Y1135729D01*
X1099611Y1135088D01*
G02X1099670Y1134946I-141J-142D01*
G01Y1115885D01*
G02X1099573Y1115714I-200J0D01*
G01X1099235Y1115510D01*
X1099130Y1115507D01*
X1099084Y1115531D01*
G03X1098523Y1115670I-561J-1063D01*
G03Y1113266I0J-1202D01*
G03X1099084Y1113405I0J1202D01*
G01X1099130Y1113429D01*
X1099235Y1113426D01*
X1099573Y1113222D01*
G02X1099670Y1113051I-103J-171D01*
G01Y1110043D01*
G02X1099593Y1109885I-200J0D01*
G03Y1107831I800J-1027D01*
G02X1099670Y1107673I-123J-158D01*
G01Y1106284D01*
G02X1099594Y1106127I-200J0D01*
G03X1099106Y1105117I799J-1009D01*
G03X1099594Y1104107I1287J-1D01*
G02X1099670Y1103950I-124J-157D01*
G01Y1102543D01*
G02X1099594Y1102386I-200J0D01*
G03X1099106Y1101376I799J-1009D01*
G03X1099594Y1100366I1287J-1D01*
G02X1099670Y1100209I-124J-157D01*
G01Y1098822D01*
G02X1099593Y1098664I-200J0D01*
G03Y1096610I800J-1027D01*
G02X1099670Y1096452I-123J-158D01*
G01Y1095082D01*
G02X1099593Y1094924I-200J0D01*
G03Y1092870I800J-1027D01*
G02X1099670Y1092712I-123J-158D01*
G01Y1091342D01*
G02X1099593Y1091184I-200J0D01*
G03Y1089130I800J-1027D01*
G02X1099670Y1088972I-123J-158D01*
G01Y1087584D01*
G02X1099594Y1087427I-200J0D01*
G03X1099106Y1086417I799J-1009D01*
G03X1099594Y1085407I1287J-1D01*
G02X1099670Y1085250I-124J-157D01*
G01Y1083844D01*
G02X1099594Y1083687I-200J0D01*
G03X1099106Y1082677I799J-1009D01*
G03X1099594Y1081667I1287J-1D01*
G02X1099670Y1081510I-124J-157D01*
G01Y1080121D01*
G02X1099593Y1079963I-200J0D01*
G03Y1077909I800J-1027D01*
G02X1099670Y1077751I-123J-158D01*
G01Y1076750D01*
G02X1099611Y1076608I-200J0D01*
G01X1098514Y1075511D01*
G02X1098330Y1075457I-141J141D01*
G01X1097951Y1075538D01*
X1097875Y1075604D01*
X1097857Y1075652D01*
G03X1096653Y1076484I-1204J-455D01*
G03X1095366Y1075196I0J-1287D01*
G03X1096197Y1073992I1288J0D01*
G01X1096245Y1073974D01*
X1096311Y1073898D01*
X1096392Y1073519D01*
G02X1096338Y1073335I-195J-43D01*
G01X1095462Y1072459D01*
G02X1095320Y1072400I-142J141D01*
G01X1090143D01*
G02X1090014Y1072448I1J200D01*
G03X1089171Y1072757I-842J-993D01*
G03X1088328Y1072448I-1J-1302D01*
G02X1088199Y1072400I-130J152D01*
G01X1081335D01*
G02X1081172Y1072484I0J200D01*
G01X1080955Y1072790D01*
X1080941Y1072885D01*
X1080957Y1072931D01*
G03X1081024Y1073326I-1135J396D01*
G03X1078620I-1202J0D01*
G03X1078687Y1072931I1202J1D01*
G01X1078703Y1072885D01*
X1078689Y1072790D01*
X1078472Y1072484D01*
G02X1078309Y1072400I-163J116D01*
G01X1073855D01*
G02X1073692Y1072484I0J200D01*
G01X1073475Y1072790D01*
X1073461Y1072885D01*
X1073477Y1072931D01*
G03X1073544Y1073326I-1135J396D01*
G03X1071140I-1202J0D01*
G03X1071207Y1072931I1202J1D01*
G01X1071223Y1072885D01*
X1071209Y1072790D01*
X1070992Y1072484D01*
G02X1070829Y1072400I-163J116D01*
G01X1068852D01*
G03X1068710Y1072341I0J-200D01*
G01X1043623Y1047254D01*
G02X1043481Y1047195I-142J141D01*
G01X994401D01*
G02X994201Y1047395I0J200D01*
G01Y1080400D01*
G02X994260Y1080542I200J0D01*
G01X1022080Y1108362D01*
X1022224Y1108375D01*
X1022284Y1108333D01*
G03X1023144Y1108062I861J1231D01*
G03X1024646Y1109564I0J1502D01*
G03X1024375Y1110424I-1502J-1D01*
G01X1024333Y1110484D01*
X1024346Y1110628D01*
X1026926Y1113208D01*
X1026971Y1113234D01*
X1026996Y1113241D01*
G03X1027308Y1113363I-388J1451D01*
G01X1027355Y1113388D01*
X1027460Y1113385D01*
X1027799Y1113181D01*
G02X1027896Y1113010I-103J-172D01*
G01Y1103461D01*
G03X1028452Y1102116I1902J-1D01*
G01X1033155Y1097413D01*
G03X1034500Y1096856I1345J1345D01*
G01X1039499D01*
G03X1041400Y1098758I0J1901D01*
G03X1040339Y1100464I-1902J0D01*
G01X1040296Y1100485D01*
X1040240Y1100559D01*
X1040161Y1100964D01*
X1040186Y1101054D01*
X1040217Y1101090D01*
G03X1040600Y1102091I-1119J1002D01*
G03X1040003Y1103289I-1502J-1D01*
G01X1039966Y1103318D01*
X1039925Y1103399D01*
X1039919Y1103808D01*
X1039958Y1103891D01*
X1039994Y1103920D01*
G03X1040555Y1105091I-942J1171D01*
G03X1037551I-1502J0D01*
G03X1038148Y1103893I1502J1D01*
G01X1038185Y1103864D01*
X1038226Y1103783D01*
X1038232Y1103374D01*
X1038193Y1103291D01*
X1038157Y1103262D01*
G03X1037596Y1102091I942J-1171D01*
G03X1037836Y1101276I1502J0D01*
G01X1037866Y1101230D01*
X1037870Y1101121D01*
X1037676Y1100764D01*
G02X1037500Y1100660I-175J96D01*
G01X1035370D01*
G02X1035229Y1100718I0J200D01*
G01X1031757Y1104190D01*
G02X1031698Y1104331I141J142D01*
G01Y1113701D01*
G02X1031898Y1113901I200J0D01*
G01X1037714D01*
G02X1037876Y1113817I-1J-200D01*
G03X1040320I1222J875D01*
G02X1040482Y1113901I163J-116D01*
G01X1056207D01*
G02X1056375Y1113810I0J-200D01*
G03X1058387I1006J658D01*
G02X1058555Y1113901I168J-109D01*
G01X1059947D01*
G02X1060115Y1113810I0J-200D01*
G03X1062127I1006J658D01*
G02X1062295Y1113901I168J-109D01*
G01X1062752D01*
G03X1062894Y1113960I0J200D01*
G01X1066831Y1117897D01*
G02X1067013Y1117952I142J-141D01*
G01X1067390Y1117874D01*
X1067467Y1117810D01*
X1067486Y1117763D01*
G03X1068602Y1117006I1116J444D01*
G03X1069804Y1118208I0J1202D01*
G03X1069047Y1119324I-1201J0D01*
G01X1069000Y1119343D01*
X1068936Y1119420D01*
X1068858Y1119797D01*
G02X1068913Y1119979I196J40D01*
G01X1085472Y1136538D01*
G02X1085614Y1136597I142J-141D01*
G01X1085953D01*
X1086056Y1136525D01*
X1086078Y1136465D01*
G03X1088526I1224J444D01*
G01X1088548Y1136525D01*
X1088651Y1136597D01*
X1089694D01*
X1089797Y1136525D01*
X1089819Y1136465D01*
G03X1092267I1224J444D01*
G01X1092289Y1136525D01*
X1092392Y1136597D01*
G37*
G36*
G01X1018815Y678648D02*
G03I-577J0D01*
G37*
G36*
G01X1018732Y684133D02*
G03I-577J0D01*
G37*
G36*
G01X1016443Y760454D02*
G03I-639J0D01*
G37*
G36*
G01X1026729Y770943D02*
G03I-639J0D01*
G37*
G36*
G01X1039435Y763272D02*
G03I-639J0D01*
G37*
G36*
G01X1101180Y1149508D02*
X1103459D01*
G02X1103601Y1149449I0J-200D01*
G01X1103952Y1149098D01*
G02X1104011Y1148956I-141J-142D01*
G01Y1141220D01*
G02X1103952Y1141078I-200J0D01*
G01X1103836Y1140962D01*
G02X1103553I-142J141D01*
G01X1103536Y1140980D01*
X1103512Y1141019D01*
X1103504Y1141043D01*
G03X1102263Y1141951I-1241J-394D01*
G03X1100961Y1140649I0J-1302D01*
G03X1101646Y1139502I1303J0D01*
G01X1101648D01*
Y1139501D01*
G02X1101750Y1139355I-96J-175D01*
G01X1101797Y1139037D01*
G02X1101741Y1138867I-198J-29D01*
G01X1101260Y1138386D01*
X1101232Y1138357D01*
X1101158Y1138327D01*
X1085478D01*
G03X1085336Y1138268I0J-200D01*
G01X1084971Y1137903D01*
X1084944Y1137875D01*
X1084874Y1137845D01*
X1084835Y1137844D01*
X1084562Y1137835D01*
G02X1084488Y1137847I-6J200D01*
G01X1084452Y1137860D01*
X1084423Y1137885D01*
G03X1083562Y1138211I-862J-976D01*
G03X1082260Y1136909I0J-1302D01*
G03X1082585Y1136049I1302J1D01*
G01X1082586Y1136048D01*
X1082611Y1136019D01*
X1082624Y1135983D01*
G02X1082636Y1135909I-188J-68D01*
G01X1082627Y1135636D01*
X1082626Y1135597D01*
X1082596Y1135527D01*
X1082568Y1135500D01*
X1077491Y1130423D01*
X1077464Y1130395D01*
X1077394Y1130365D01*
X1077355Y1130364D01*
X1077082Y1130355D01*
G02X1077008Y1130367I-6J200D01*
G01X1076972Y1130380D01*
X1076943Y1130405D01*
G03X1076082Y1130731I-862J-976D01*
G03X1074780Y1129429I0J-1302D01*
G03X1075105Y1128569I1302J1D01*
G01X1075106Y1128568D01*
X1075131Y1128539D01*
X1075144Y1128503D01*
G02X1075156Y1128429I-188J-68D01*
G01X1075147Y1128156D01*
X1075146Y1128117D01*
X1075116Y1128047D01*
X1075088Y1128020D01*
X1073750Y1126682D01*
G02X1073615Y1126624I-141J142D01*
G01X1073303Y1126614D01*
X1073232Y1126640D01*
X1073203Y1126665D01*
G03X1072342Y1126990I-861J-978D01*
G03X1071040Y1125688I0J-1302D01*
G03X1071365Y1124827I1303J0D01*
G01X1071390Y1124798D01*
X1071416Y1124727D01*
X1071406Y1124415D01*
G02X1071348Y1124280I-200J6D01*
G01X1070010Y1122942D01*
G02X1069875Y1122884I-141J142D01*
G01X1069563Y1122874D01*
X1069492Y1122900D01*
X1069463Y1122925D01*
G03X1068602Y1123250I-861J-978D01*
G03X1067300Y1121948I0J-1302D01*
G03X1067625Y1121087I1303J0D01*
G01X1067650Y1121058D01*
X1067676Y1120987D01*
X1067666Y1120675D01*
G02X1067608Y1120540I-200J6D01*
G01X1066270Y1119202D01*
G02X1066135Y1119144I-141J142D01*
G01X1065823Y1119134D01*
X1065752Y1119160D01*
X1065723Y1119185D01*
G03X1064862Y1119510I-861J-978D01*
G03X1063560Y1118208I0J-1302D01*
G03X1063885Y1117347I1303J0D01*
G01X1063910Y1117318D01*
X1063936Y1117247D01*
X1063926Y1116935D01*
G02X1063868Y1116800I-200J6D01*
G01X1062740Y1115672D01*
X1062712Y1115643D01*
X1062638Y1115613D01*
X1061766D01*
X1061723Y1115623D01*
X1061701Y1115634D01*
G03X1061122Y1115770I-579J-1166D01*
G01X1061120D01*
G03X1060541Y1115634I0J-1302D01*
G01X1060519Y1115623D01*
X1060476Y1115613D01*
X1058026D01*
X1057983Y1115623D01*
X1057961Y1115634D01*
G03X1057382Y1115770I-579J-1166D01*
G01X1057380D01*
G03X1056801Y1115634I0J-1302D01*
G01X1056779Y1115623D01*
X1056736Y1115613D01*
X1040378D01*
G02X1040227Y1115681I-1J200D01*
G03X1039098Y1116193I-1129J-989D01*
G03X1038827Y1116168I2J-1502D01*
G01X1038778Y1116159D01*
X1038685Y1116188D01*
X1037958Y1116915D01*
G02X1037899Y1117057I141J142D01*
G01Y1124622D01*
G02X1037958Y1124764I200J0D01*
G01X1038954Y1125760D01*
X1039029Y1125790D01*
X1039070Y1125789D01*
G03X1040528Y1126831I28J1502D01*
G01X1040548Y1126894D01*
X1040653Y1126970D01*
X1055926D01*
G02X1056100Y1126868I0J-200D01*
G01X1056271Y1126566D01*
G02X1056267Y1126364I-175J-98D01*
G03X1056079Y1125690I1114J-674D01*
G01Y1125688D01*
G03X1058683I1302J0D01*
G03X1058002Y1126832I-1301J0D01*
G01X1057959Y1126855D01*
X1057906Y1126931D01*
X1057853Y1127296D01*
G02X1057910Y1127467I198J29D01*
G01X1058284Y1127841D01*
G02X1058425Y1127900I142J-141D01*
G01X1058448D01*
G03X1058589Y1127958I0J200D01*
G01X1059413Y1128782D01*
G02X1059575Y1128839I141J-142D01*
G01X1059884Y1128807D01*
G02X1059968Y1128778I-22J-199D01*
G02X1060031Y1128718I-103J-171D01*
G01Y1128717D01*
G03X1061121Y1128127I1090J712D01*
G03X1062423Y1129429I0J1302D01*
G03X1061833Y1130519I-1302J0D01*
G01X1061832D01*
G02X1061772Y1130582I111J166D01*
G02X1061743Y1130666I170J106D01*
G01X1061711Y1130975D01*
X1061706Y1131020D01*
X1061736Y1131105D01*
X1063154Y1132522D01*
G02X1063317Y1132580I142J-141D01*
G01X1063669Y1132543D01*
X1063746Y1132496D01*
X1063771Y1132458D01*
G03X1064862Y1131867I1091J712D01*
G03X1066164Y1133169I0J1302D01*
G03X1065573Y1134260I-1303J0D01*
G01X1065535Y1134285D01*
X1065488Y1134362D01*
X1065451Y1134714D01*
G02X1065509Y1134877I199J21D01*
G01X1066894Y1136262D01*
G02X1067057Y1136320I142J-141D01*
G01X1067409Y1136283D01*
X1067486Y1136236D01*
X1067511Y1136198D01*
G03X1068602Y1135607I1091J712D01*
G03X1069904Y1136909I0J1302D01*
G03X1069313Y1138000I-1303J0D01*
G01X1069275Y1138025D01*
X1069228Y1138102D01*
X1069191Y1138454D01*
G02X1069249Y1138617I199J21D01*
G01X1070634Y1140002D01*
G02X1070797Y1140060I142J-141D01*
G01X1071149Y1140023D01*
X1071226Y1139976D01*
X1071251Y1139938D01*
G03X1072342Y1139347I1091J712D01*
G03X1073644Y1140649I0J1302D01*
G03X1073053Y1141740I-1303J0D01*
G01X1073015Y1141765D01*
X1072968Y1141842D01*
X1072931Y1142194D01*
G02X1072989Y1142357I199J21D01*
G01X1074374Y1143742D01*
G02X1074537Y1143800I142J-141D01*
G01X1074889Y1143763D01*
X1074966Y1143716D01*
X1074991Y1143678D01*
G03X1076082Y1143087I1091J712D01*
G03X1077384Y1144389I0J1302D01*
G03X1076793Y1145480I-1303J0D01*
G01X1076755Y1145505D01*
X1076708Y1145582D01*
X1076671Y1145934D01*
G02X1076729Y1146097I199J21D01*
G01X1078114Y1147482D01*
G02X1078277Y1147540I142J-141D01*
G01X1078629Y1147503D01*
X1078706Y1147456D01*
X1078731Y1147418D01*
G03X1079822Y1146827I1091J712D01*
G03X1081041Y1147672I0J1302D01*
G01X1081051Y1147701D01*
X1081089Y1147749D01*
X1081115Y1147767D01*
G02X1081228Y1147802I113J-165D01*
G01X1082156D01*
G02X1082269Y1147767I0J-200D01*
G01X1082295Y1147749D01*
X1082333Y1147701D01*
X1082343Y1147672D01*
G03X1084781I1219J456D01*
G01X1084791Y1147701D01*
X1084829Y1147749D01*
X1084855Y1147767D01*
G02X1084968Y1147802I113J-165D01*
G01X1085896D01*
G02X1086009Y1147767I0J-200D01*
G01X1086035Y1147749D01*
X1086073Y1147701D01*
X1086083Y1147672D01*
G03X1088521I1219J456D01*
G01X1088531Y1147701D01*
X1088569Y1147749D01*
X1088595Y1147767D01*
G02X1088708Y1147802I113J-165D01*
G01X1089637D01*
G02X1089750Y1147767I0J-200D01*
G01X1089776Y1147749D01*
X1089814Y1147701D01*
X1089824Y1147672D01*
G03X1092262I1219J456D01*
G01X1092272Y1147701D01*
X1092310Y1147749D01*
X1092336Y1147767D01*
G02X1092449Y1147802I113J-165D01*
G01X1093377D01*
G02X1093490Y1147767I0J-200D01*
G01X1093516Y1147749D01*
X1093554Y1147701D01*
X1093564Y1147672D01*
G03X1096002I1219J456D01*
G01X1096012Y1147701D01*
X1096050Y1147749D01*
X1096076Y1147767D01*
G02X1096189Y1147802I113J-165D01*
G01X1097117D01*
G02X1097230Y1147767I0J-200D01*
G01X1097256Y1147749D01*
X1097294Y1147701D01*
X1097304Y1147672D01*
G03X1098523Y1146827I1219J457D01*
G03X1099825Y1148129I0J1302D01*
G01Y1148150D01*
X1099824Y1148190D01*
X1099854Y1148265D01*
X1101038Y1149449D01*
G02X1101180Y1149508I142J-141D01*
G37*
G36*
G01X1100183Y1150025D02*
G02X1100147Y1149975I-178J90D01*
G01X1099444Y1149272D01*
G02X1099198Y1149242I-142J141D01*
G03X1098523Y1149431I-676J-1113D01*
G03X1097465Y1148888I0J-1302D01*
G02X1097447Y1148866I-163J115D01*
G02X1097313Y1148804I-145J138D01*
G01X1096004D01*
G02X1095859Y1148866I0J200D01*
G02X1095841Y1148888I145J137D01*
G03X1093725I-1058J-758D01*
G02X1093707Y1148866I-163J115D01*
G02X1093573Y1148804I-145J138D01*
G01X1092264D01*
G02X1092119Y1148866I0J200D01*
G02X1092101Y1148888I145J137D01*
G03X1089985I-1058J-758D01*
G02X1089967Y1148866I-163J115D01*
G02X1089833Y1148804I-145J138D01*
G01X1088523D01*
G02X1088378Y1148866I0J200D01*
G02X1088360Y1148888I145J137D01*
G03X1086244I-1058J-758D01*
G02X1086226Y1148866I-163J115D01*
G02X1086092Y1148804I-145J138D01*
G01X1084783D01*
G02X1084638Y1148866I0J200D01*
G02X1084620Y1148888I145J137D01*
G03X1082504I-1058J-758D01*
G02X1082486Y1148866I-163J115D01*
G02X1082352Y1148804I-145J138D01*
G01X1081043D01*
G02X1080898Y1148866I0J200D01*
G02X1080880Y1148888I145J137D01*
G03X1078764I-1058J-758D01*
G02X1078746Y1148866I-163J115D01*
G02X1078612Y1148804I-145J138D01*
G01X1078102D01*
G03X1077960Y1148745I0J-200D01*
G01X1077865Y1148650D01*
G02X1077694Y1148594I-141J142D01*
G01X1077377Y1148641D01*
G02X1077291Y1148675I29J198D01*
G02X1077231Y1148743I116J163D01*
G01X1077230Y1148744D01*
G03X1076082Y1149431I-1148J-616D01*
G03X1074780Y1148129I0J-1302D01*
G03X1075466Y1146981I1304J0D01*
G01X1075468D01*
Y1146980D01*
G02X1075536Y1146920I-95J-176D01*
G02X1075570Y1146834I-164J-115D01*
G01X1075617Y1146517D01*
G02X1075561Y1146346I-198J-30D01*
G01X1070385Y1141170D01*
G02X1070214Y1141114I-141J142D01*
G01X1069897Y1141161D01*
G02X1069811Y1141195I29J198D01*
G02X1069751Y1141263I116J163D01*
G01X1069750Y1141264D01*
G03X1068602Y1141951I-1148J-616D01*
G03X1067300Y1140649I0J-1302D01*
G03X1067986Y1139501I1304J0D01*
G01X1067988D01*
Y1139500D01*
G02X1068056Y1139440I-95J-176D01*
G02X1068090Y1139354I-164J-115D01*
G01X1068137Y1139037D01*
G02X1068081Y1138866I-198J-30D01*
G01X1066645Y1137430D01*
G02X1066474Y1137374I-141J142D01*
G01X1066157Y1137421D01*
G02X1066071Y1137455I29J198D01*
G02X1066011Y1137523I116J163D01*
G01X1066010Y1137524D01*
G03X1064862Y1138211I-1148J-616D01*
G03X1063560Y1136909I0J-1302D01*
G03X1064246Y1135761I1304J0D01*
G01X1064248D01*
Y1135760D01*
G02X1064316Y1135700I-95J-176D01*
G02X1064350Y1135614I-164J-115D01*
G01X1064397Y1135297D01*
G02X1064341Y1135126I-198J-30D01*
G01X1062904Y1133689D01*
G02X1062734Y1133633I-141J142D01*
G01X1062476Y1133671D01*
X1062415Y1133680D01*
G02X1062331Y1133713I29J198D01*
G01X1062313Y1133726D01*
X1062280Y1133762D01*
X1062269Y1133784D01*
G03X1061121Y1134471I-1148J-616D01*
G03X1059819Y1133169I0J-1302D01*
G03X1060506Y1132021I1303J0D01*
G02X1060578Y1131957I-93J-177D01*
G01X1060590Y1131940D01*
X1060606Y1131898D01*
X1060619Y1131814D01*
X1060657Y1131556D01*
G02X1060601Y1131386I-198J-29D01*
G01X1059164Y1129949D01*
G02X1058994Y1129893I-141J142D01*
G01X1058736Y1129931D01*
X1058675Y1129940D01*
G02X1058591Y1129973I29J198D01*
G01X1058573Y1129986D01*
X1058540Y1130022D01*
X1058529Y1130044D01*
G03X1057381Y1130731I-1148J-616D01*
G03X1056079Y1129429I0J-1302D01*
G03X1056084Y1129315I1302J0D01*
G01X1056086Y1129289D01*
X1056073Y1129251D01*
G02X1056031Y1129181I-189J66D01*
G01X1055822Y1128957D01*
G02X1055684Y1128901I-139J144D01*
G01X1049667D01*
G02X1049493Y1129003I0J200D01*
G01X1049407Y1129154D01*
Y1129156D01*
X1049321Y1129309D01*
G02X1049296Y1129410I175J97D01*
G01X1049297Y1129461D01*
X1049326Y1129509D01*
G03X1049545Y1130289I-1283J781D01*
G01Y1130291D01*
G03X1046541I-1502J0D01*
G01Y1130289D01*
G03X1046760Y1129509I1502J1D01*
G01X1046761Y1129507D01*
G02X1046790Y1129407I-171J-104D01*
G01X1046791Y1129356D01*
X1046679Y1129156D01*
Y1129154D01*
X1046593Y1129003D01*
G02X1046419Y1128901I-174J98D01*
G01X1038177D01*
G02X1038035Y1128960I0J200D01*
G01X1037819Y1129176D01*
G02X1037760Y1129318I141J142D01*
G01Y1136867D01*
G02X1037819Y1137009I200J0D01*
G01X1038504Y1137694D01*
G02X1038646Y1137753I142J-141D01*
G01X1040611D01*
G02X1040645Y1137750I-1J-200D01*
G03X1040842Y1137732I209J1204D01*
G01X1053607D01*
X1053609D01*
G03X1053799Y1137746I5J1222D01*
G01X1053803D01*
G03X1053839Y1137753I-215J1203D01*
G01X1054825D01*
G03X1054967Y1137812I0J200D01*
G01X1056591Y1139436D01*
G02X1056698Y1139492I142J-141D01*
G01X1056728Y1139497D01*
X1056789Y1139489D01*
X1056819Y1139475D01*
G03X1057381Y1139347I563J1174D01*
G03X1058683Y1140649I0J1302D01*
G03X1058555Y1141211I-1302J-1D01*
G01X1058554Y1141212D01*
G02X1058538Y1141333I181J85D01*
G01X1058543Y1141362D01*
X1058572Y1141417D01*
X1060331Y1143176D01*
G02X1060438Y1143232I142J-141D01*
G01X1060468Y1143237D01*
X1060529Y1143229D01*
X1060559Y1143215D01*
G03X1061121Y1143087I563J1174D01*
G03X1062423Y1144389I0J1302D01*
G03X1062295Y1144951I-1302J-1D01*
G01X1062294Y1144952D01*
G02X1062278Y1145073I181J85D01*
G01X1062283Y1145102D01*
X1062312Y1145157D01*
X1064071Y1146916D01*
G02X1064178Y1146972I142J-141D01*
G01X1064208Y1146977D01*
X1064271Y1146969D01*
X1064299Y1146955D01*
G03X1064862Y1146827I563J1174D01*
G03X1066164Y1148129I0J1302D01*
G03X1066036Y1148692I-1302J0D01*
G01X1066022Y1148720D01*
X1066014Y1148783D01*
X1066019Y1148813D01*
G02X1066075Y1148920I197J-35D01*
G01X1067811Y1150656D01*
G02X1067918Y1150712I142J-141D01*
G01X1067948Y1150717D01*
X1068011Y1150709D01*
X1068039Y1150695D01*
G03X1068602Y1150567I563J1174D01*
G03X1069904Y1151869I0J1302D01*
G03X1069776Y1152432I-1302J0D01*
G01X1069762Y1152460D01*
X1069754Y1152523D01*
X1069759Y1152553D01*
G02X1069815Y1152660I197J-35D01*
G01X1071552Y1154397D01*
G02X1071659Y1154453I142J-141D01*
G01X1071689Y1154458D01*
X1071750Y1154450D01*
X1071780Y1154436D01*
G03X1072342Y1154308I563J1174D01*
G03X1073644Y1155592I0J1302D01*
G01X1073645Y1155675D01*
X1073670Y1155700D01*
X1073701Y1155703D01*
X1073712Y1155713D01*
G02X1073851Y1155770I140J-143D01*
G01X1074573D01*
G02X1074712Y1155713I-1J-200D01*
G01X1074723Y1155703D01*
X1074754Y1155700D01*
X1074779Y1155675D01*
X1074780Y1155592D01*
G03X1077384I1302J18D01*
G01X1077385Y1155675D01*
X1077410Y1155700D01*
X1077441Y1155703D01*
X1077452Y1155713D01*
G02X1077591Y1155770I140J-143D01*
G01X1078313D01*
G02X1078452Y1155713I-1J-200D01*
G01X1078463Y1155703D01*
X1078494Y1155700D01*
X1078519Y1155675D01*
X1078520Y1155592D01*
G03X1081124I1302J18D01*
G01X1081125Y1155675D01*
X1081150Y1155700D01*
X1081181Y1155703D01*
X1081192Y1155713D01*
G02X1081331Y1155770I140J-143D01*
G01X1081881D01*
G02X1082021Y1155712I-1J-200D01*
G01X1082029Y1155705D01*
X1082060Y1155633D01*
Y1155592D01*
G03X1085064I1502J18D01*
G01Y1155593D01*
G02X1085123Y1155733I200J-2D01*
G01X1085131Y1155740D01*
X1085203Y1155770D01*
X1085793D01*
G02X1085932Y1155713I-1J-200D01*
G01X1085943Y1155703D01*
X1085974Y1155700D01*
X1085999Y1155675D01*
X1086000Y1155592D01*
G03X1088604I1302J18D01*
G01X1088605Y1155675D01*
X1088630Y1155700D01*
X1088661Y1155703D01*
X1088672Y1155713D01*
G02X1088811Y1155770I140J-143D01*
G01X1093274D01*
G02X1093413Y1155713I-1J-200D01*
G01X1093424Y1155703D01*
X1093455Y1155700D01*
X1093480Y1155675D01*
X1093481Y1155592D01*
G03X1096085I1302J18D01*
G01X1096086Y1155675D01*
X1096111Y1155700D01*
X1096142Y1155703D01*
X1096153Y1155713D01*
G02X1096292Y1155770I140J-143D01*
G01X1097014D01*
G02X1097153Y1155713I-1J-200D01*
G01X1097164Y1155703D01*
X1097195Y1155700D01*
X1097220Y1155675D01*
X1097221Y1155592D01*
G03X1098523Y1154308I1302J18D01*
G03X1099525Y1154779I0J1301D01*
G01X1099552Y1154811D01*
X1099589Y1154830D01*
G02X1099670Y1154851I90J-179D01*
G01X1099964Y1154865D01*
X1099986D01*
G02X1100116Y1154806I-12J-200D01*
G01X1100147Y1154775D01*
G02X1100183Y1154725I-142J-140D01*
G02X1100205Y1154634I-178J-91D01*
G01Y1150116D01*
G02X1100183Y1150025I-200J0D01*
G37*
G36*
G01X1096935Y1164911D02*
X1098795D01*
G02X1098937Y1164852I0J-200D01*
G01X1099876Y1163913D01*
G02X1099935Y1163771I-141J-142D01*
G01Y1157461D01*
G02X1099876Y1157319I-200J0D01*
G01X1099358Y1156801D01*
G02X1099125Y1156765I-141J141D01*
G01X1099124D01*
G03X1098523Y1156912I-601J-1155D01*
G01X1098522D01*
G03X1097821Y1156707I0J-1302D01*
G01X1097762Y1156669D01*
X1097623Y1156683D01*
X1097571Y1156734D01*
G03X1097431Y1156792I-141J-142D01*
G01X1095875D01*
G03X1095735Y1156734I1J-200D01*
G01X1095683Y1156683D01*
X1095544Y1156669D01*
X1095485Y1156707D01*
G03X1094784Y1156912I-701J-1097D01*
G01X1094782D01*
G03X1094081Y1156707I0J-1302D01*
G01X1094022Y1156669D01*
X1093883Y1156683D01*
X1093831Y1156734D01*
G03X1093691Y1156792I-141J-142D01*
G01X1088394D01*
G03X1088254Y1156734I1J-200D01*
G01X1088202Y1156683D01*
X1088063Y1156669D01*
X1088004Y1156707D01*
G03X1087303Y1156912I-701J-1097D01*
G01X1087301D01*
G03X1086600Y1156707I0J-1302D01*
G01X1086541Y1156669D01*
X1086402Y1156683D01*
X1086350Y1156734D01*
G03X1086210Y1156792I-141J-142D01*
G01X1084586D01*
G02X1084525Y1156801I-2J200D01*
G01X1084440Y1156829D01*
X1084415Y1156846D01*
G03X1083562Y1157112I-853J-1236D01*
G03X1082709Y1156846I0J-1502D01*
G01X1082684Y1156829D01*
X1082599Y1156801D01*
G02X1082538Y1156792I-59J191D01*
G01X1080914D01*
G03X1080774Y1156734I1J-200D01*
G01X1080722Y1156683D01*
X1080583Y1156669D01*
X1080524Y1156707D01*
G03X1079823Y1156912I-701J-1097D01*
G01X1079821D01*
G03X1079120Y1156707I0J-1302D01*
G01X1079061Y1156669D01*
X1078922Y1156683D01*
X1078870Y1156734D01*
G03X1078730Y1156792I-141J-142D01*
G01X1077174D01*
G03X1077034Y1156734I1J-200D01*
G01X1076982Y1156683D01*
X1076843Y1156669D01*
X1076784Y1156707D01*
G03X1076083Y1156912I-701J-1097D01*
G01X1076081D01*
G03X1075380Y1156707I0J-1302D01*
G01X1075321Y1156669D01*
X1075182Y1156683D01*
X1075130Y1156734D01*
G03X1074990Y1156792I-141J-142D01*
G01X1073434D01*
G03X1073294Y1156734I1J-200D01*
G01X1073242Y1156683D01*
X1073103Y1156669D01*
X1073044Y1156707D01*
G03X1072343Y1156912I-701J-1097D01*
G01X1072342D01*
G03X1071242Y1156307I0J-1303D01*
G02X1071214Y1156272I-169J107D01*
G01X1070562Y1155620D01*
X1070522Y1155580D01*
X1070414Y1155553D01*
X1069968Y1155694D01*
X1069895Y1155777D01*
X1069885Y1155833D01*
G03X1068602Y1156912I-1283J-223D01*
G03X1067300Y1155610I0J-1302D01*
G03X1068379Y1154327I1302J0D01*
G01X1068435Y1154317D01*
X1068518Y1154244D01*
X1068642Y1153852D01*
G02X1068592Y1153650I-191J-60D01*
G01X1067944Y1153002D01*
G02X1067927Y1152987I-141J142D01*
G01X1067902Y1152967D01*
X1067894Y1152962D01*
G03X1067509Y1152577I708J-1093D01*
G01X1067504Y1152569D01*
X1067484Y1152544D01*
G02X1067469Y1152527I-157J124D01*
G01X1066822Y1151880D01*
X1066782Y1151840D01*
X1066674Y1151813D01*
X1066228Y1151954D01*
X1066155Y1152037D01*
X1066145Y1152093D01*
G03X1064862Y1153172I-1283J-223D01*
G03X1063560Y1151870I0J-1302D01*
G03X1064639Y1150587I1302J0D01*
G01X1064695Y1150577D01*
X1064778Y1150504D01*
X1064902Y1150112D01*
G02X1064852Y1149910I-191J-60D01*
G01X1064204Y1149262D01*
G02X1064187Y1149247I-141J142D01*
G01X1064162Y1149227D01*
X1064154Y1149222D01*
G03X1063769Y1148837I708J-1093D01*
G01X1063764Y1148829D01*
X1063744Y1148804D01*
G02X1063729Y1148787I-157J124D01*
G01X1063081Y1148139D01*
X1063041Y1148099D01*
X1062933Y1148072D01*
X1062487Y1148213D01*
X1062414Y1148296D01*
X1062404Y1148352D01*
G03X1061121Y1149431I-1283J-223D01*
G03X1059819Y1148129I0J-1302D01*
G03X1060898Y1146846I1302J0D01*
G01X1060954Y1146836D01*
X1061037Y1146763D01*
X1061161Y1146371D01*
G02X1061111Y1146169I-191J-60D01*
G01X1060459Y1145517D01*
G02X1060424Y1145489I-142J141D01*
G03X1060021Y1145086I697J-1100D01*
G02X1059993Y1145051I-169J107D01*
G01X1059341Y1144399D01*
X1059301Y1144359D01*
X1059193Y1144332D01*
X1058747Y1144473D01*
X1058674Y1144556D01*
X1058664Y1144612D01*
G03X1057381Y1145691I-1283J-223D01*
G03X1056079Y1144389I0J-1302D01*
G03X1057158Y1143106I1302J0D01*
G01X1057214Y1143096D01*
X1057297Y1143023D01*
X1057421Y1142631D01*
G02X1057371Y1142429I-191J-60D01*
G01X1056719Y1141777D01*
G02X1056684Y1141749I-142J141D01*
G03X1056286Y1141354I697J-1100D01*
G01X1056281Y1141346D01*
X1056261Y1141321D01*
G02X1056246Y1141304I-157J124D01*
G01X1053755Y1138813D01*
G02X1053645Y1138756I-143J141D01*
G02X1053613Y1138754I-28J198D01*
G01X1040852D01*
X1040848D01*
G02X1040685Y1138844I4J200D01*
G01X1040501Y1139121D01*
G02X1040483Y1139309I166J111D01*
G01Y1139310D01*
G03X1040600Y1139887I-1385J581D01*
G01Y1139909D01*
G03X1039098Y1141393I-1502J-18D01*
G03X1037916Y1140818I0J-1502D01*
G01X1037876Y1140767D01*
X1037754Y1140731D01*
X1037336Y1140875D01*
G02X1037201Y1141064I65J189D01*
G01Y1150272D01*
G02X1037260Y1150414I200J0D01*
G01X1037531Y1150685D01*
G02X1037673Y1150744I142J-141D01*
G01X1048857D01*
G03X1048999Y1150803I0J200D01*
G01X1056425Y1158229D01*
G02X1056675Y1158256I142J-141D01*
G03X1057381Y1158048I706J1094D01*
G03X1058683Y1159350I0J1302D01*
G03X1058475Y1160056I-1302J0D01*
G02X1058502Y1160306I168J108D01*
G01X1061899Y1163703D01*
G03X1061956Y1163816I-141J142D01*
G01X1061961Y1163848D01*
X1061990Y1163906D01*
X1062936Y1164852D01*
G02X1063077Y1164910I141J-142D01*
G01X1063239D01*
G03X1063271Y1164911I-22J1202D01*
G01X1066451D01*
G03X1066483Y1164910I54J1201D01*
G01X1066980D01*
G03X1067012Y1164911I-22J1202D01*
G01X1070192D01*
G03X1070224Y1164910I54J1201D01*
G01X1070720D01*
G03X1070752Y1164911I-22J1202D01*
G01X1073932D01*
G03X1073964Y1164910I54J1201D01*
G01X1078200D01*
G03X1078232Y1164911I-22J1202D01*
G01X1081412D01*
G03X1081444Y1164910I54J1201D01*
G01X1085680D01*
G03X1085712Y1164911I-22J1202D01*
G01X1088892D01*
G03X1088924Y1164910I54J1201D01*
G01X1089421D01*
G03X1089453Y1164911I-22J1202D01*
G01X1092633D01*
G03X1092665Y1164910I54J1201D01*
G01X1093161D01*
G03X1093193Y1164911I-22J1202D01*
G01X1096373D01*
G03X1096405Y1164910I54J1201D01*
G01X1096901D01*
G03X1096933Y1164911I-22J1202D01*
G01X1096935D01*
G37*
G36*
G01X1096202Y1174388D02*
X1097104D01*
X1097219Y1174282D01*
X1097225Y1174204D01*
G03X1098523Y1173008I1298J106D01*
G03X1099186Y1173190I-1J1302D01*
G01X1099233Y1173217D01*
X1099340Y1173218D01*
X1099689Y1173019D01*
G02X1099790Y1172845I-99J-174D01*
G01Y1168295D01*
G02X1099689Y1168121I-200J0D01*
G01X1099340Y1167922D01*
X1099232Y1167923D01*
X1099186Y1167950D01*
G03X1098523Y1168132I-664J-1120D01*
G03X1097221Y1166830I0J-1302D01*
G03X1097283Y1166435I1302J2D01*
G01X1097298Y1166389D01*
X1097283Y1166295D01*
X1097063Y1165995D01*
G02X1096911Y1165912I-163J117D01*
G01X1096405D01*
X1096395D01*
G02X1096243Y1165995I11J200D01*
G01X1096062Y1166243D01*
G02X1096023Y1166361I161J119D01*
G01Y1166434D01*
X1096031Y1166462D01*
G03X1096085Y1166830I-1248J371D01*
G03X1093481I-1302J0D01*
G03X1093543Y1166435I1302J2D01*
G01X1093558Y1166389D01*
X1093543Y1166295D01*
X1093323Y1165995D01*
G02X1093171Y1165912I-163J117D01*
G01X1092665D01*
X1092655D01*
G02X1092503Y1165995I11J200D01*
G01X1092322Y1166243D01*
G02X1092283Y1166361I161J119D01*
G01Y1166434D01*
X1092291Y1166462D01*
G03X1092345Y1166830I-1248J371D01*
G03X1089741I-1302J0D01*
G03X1089803Y1166435I1302J2D01*
G01X1089818Y1166389D01*
X1089803Y1166295D01*
X1089583Y1165995D01*
G02X1089431Y1165912I-163J117D01*
G01X1088924D01*
X1088914D01*
G02X1088762Y1165995I11J200D01*
G01X1088581Y1166243D01*
G02X1088542Y1166361I161J119D01*
G01Y1166434D01*
X1088550Y1166462D01*
G03X1088604Y1166830I-1248J371D01*
G03X1086000I-1302J0D01*
G03X1086062Y1166435I1302J2D01*
G01X1086077Y1166389D01*
X1086062Y1166295D01*
X1085842Y1165995D01*
G02X1085690Y1165912I-163J117D01*
G01X1081444D01*
X1081434D01*
G02X1081282Y1165995I11J200D01*
G01X1081101Y1166243D01*
G02X1081062Y1166361I161J119D01*
G01Y1166434D01*
X1081070Y1166462D01*
G03X1081124Y1166830I-1248J371D01*
G03X1078520I-1302J0D01*
G03X1078582Y1166435I1302J2D01*
G01X1078597Y1166389D01*
X1078582Y1166295D01*
X1078362Y1165995D01*
G02X1078210Y1165912I-163J117D01*
G01X1073964D01*
X1073954D01*
G02X1073802Y1165995I11J200D01*
G01X1073621Y1166243D01*
G02X1073582Y1166361I161J119D01*
G01Y1166434D01*
X1073590Y1166462D01*
G03X1073644Y1166830I-1248J371D01*
G03X1071040I-1302J0D01*
G03X1071102Y1166435I1302J2D01*
G01X1071117Y1166389D01*
X1071102Y1166295D01*
X1070882Y1165995D01*
G02X1070730Y1165912I-163J117D01*
G01X1070224D01*
X1070214D01*
G02X1070062Y1165995I11J200D01*
G01X1069881Y1166243D01*
G02X1069842Y1166361I161J119D01*
G01Y1166434D01*
X1069850Y1166462D01*
G03X1069904Y1166830I-1248J371D01*
G03X1067300I-1302J0D01*
G03X1067362Y1166435I1302J2D01*
G01X1067377Y1166389D01*
X1067362Y1166295D01*
X1067142Y1165995D01*
G02X1066990Y1165912I-163J117D01*
G01X1066483D01*
X1066473D01*
G02X1066321Y1165995I11J200D01*
G01X1066140Y1166243D01*
G02X1066101Y1166361I161J119D01*
G01Y1166434D01*
X1066109Y1166462D01*
G03X1066163Y1166830I-1248J371D01*
G03X1063559I-1302J0D01*
G03X1063621Y1166435I1302J2D01*
G01X1063636Y1166389D01*
X1063621Y1166295D01*
X1063401Y1165995D01*
G02X1063249Y1165912I-163J117D01*
G01X1062662D01*
G03X1062579Y1165894I0J-200D01*
G01X1062526Y1165869D01*
X1062412Y1165885D01*
X1062316Y1165966D01*
G02X1062245Y1166099I128J154D01*
G01X1062242Y1166129D01*
X1062254Y1166187D01*
X1062268Y1166214D01*
G03X1062423Y1166830I-1147J616D01*
G03X1059819I-1302J0D01*
G03X1061077Y1165529I1302J0D01*
G01X1061137Y1165527D01*
X1061234Y1165459D01*
X1061391Y1165061D01*
G02X1061368Y1164872I-186J-73D01*
G01X1061357Y1164857D01*
X1057148Y1160648D01*
X1057101Y1160622D01*
X1057074Y1160615D01*
G03X1056108Y1159625I307J-1265D01*
G01X1056102Y1159596D01*
X1056075Y1159546D01*
X1048444Y1151916D01*
G02X1048302Y1151857I-142J141D01*
G01X1040986D01*
G02X1040837Y1151924I0J200D01*
G01X1040638Y1152148D01*
G02X1040589Y1152305I150J133D01*
G03X1040600Y1152491I-1491J182D01*
G03X1039098Y1153993I-1502J0D01*
G03X1038531Y1153882I0J-1502D01*
G01X1038484Y1153863D01*
X1038386Y1153873D01*
X1038130Y1154045D01*
X1038113Y1154043D01*
X1038047Y1154102D01*
G02X1037980Y1154251I133J149D01*
G01Y1162233D01*
G02X1038039Y1162375I200J0D01*
G01X1038700Y1163036D01*
G02X1038842Y1163095I142J-141D01*
G01X1044906D01*
G03X1045048Y1163154I0J200D01*
G01X1046265Y1164371D01*
G03X1046324Y1164513I-141J142D01*
G01Y1166492D01*
G02X1046339Y1166569I200J1D01*
G01X1046366Y1166633D01*
G03X1046380Y1166688I-185J76D01*
G01X1046386Y1166742D01*
X1046447Y1166828D01*
X1046831Y1167001D01*
G02X1047046Y1166968I82J-183D01*
G03X1048043Y1166589I997J1122D01*
G03Y1169593I0J1502D01*
G03X1047046Y1169214I0J-1501D01*
G01X1047001Y1169175D01*
X1046885Y1169157D01*
X1046499Y1169331D01*
X1046445Y1169355D01*
X1046381Y1169454D01*
Y1173219D01*
G03X1046365Y1173297I-200J0D01*
G01X1046339Y1173358D01*
G02X1046324Y1173435I185J76D01*
G01Y1173694D01*
G02X1046383Y1173836I200J0D01*
G01X1046876Y1174329D01*
G02X1046878Y1174331I142J-140D01*
G02X1047018Y1174388I140J-143D01*
G01X1059701D01*
X1059816Y1174282D01*
X1059822Y1174204D01*
G03X1062418I1298J106D01*
G01X1062424Y1174282D01*
X1062539Y1174388D01*
X1063442D01*
X1063557Y1174282D01*
X1063563Y1174204D01*
G03X1066159I1298J106D01*
G01X1066165Y1174282D01*
X1066280Y1174388D01*
X1067183D01*
X1067298Y1174282D01*
X1067304Y1174204D01*
G03X1069900I1298J106D01*
G01X1069906Y1174282D01*
X1070021Y1174388D01*
X1070923D01*
X1071038Y1174282D01*
X1071044Y1174204D01*
G03X1073640I1298J106D01*
G01X1073646Y1174282D01*
X1073761Y1174388D01*
X1074663D01*
X1074778Y1174282D01*
X1074784Y1174204D01*
G03X1077380I1298J106D01*
G01X1077386Y1174282D01*
X1077501Y1174388D01*
X1078403D01*
X1078518Y1174282D01*
X1078524Y1174204D01*
G03X1081120I1298J106D01*
G01X1081126Y1174282D01*
X1081241Y1174388D01*
X1085883D01*
X1085998Y1174282D01*
X1086004Y1174204D01*
G03X1088600I1298J106D01*
G01X1088606Y1174282D01*
X1088721Y1174388D01*
X1089624D01*
X1089739Y1174282D01*
X1089745Y1174204D01*
G03X1092341I1298J106D01*
G01X1092347Y1174282D01*
X1092462Y1174388D01*
X1093364D01*
X1093479Y1174282D01*
X1093485Y1174204D01*
G03X1096081I1298J106D01*
G01X1096087Y1174282D01*
X1096202Y1174388D01*
G37*
G36*
G01X1103705Y1196532D02*
X1104561D01*
G02X1104752Y1196392I0J-200D01*
G01X1104753Y1196389D01*
Y1196387D01*
G03X1106003Y1195449I1250J364D01*
G03X1106747Y1195683I-1J1302D01*
G02X1106995Y1195668I115J-164D01*
G01X1106999Y1195664D01*
X1107352Y1195311D01*
G02X1107354Y1195309I-140J-142D01*
G02X1107411Y1195169I-143J-140D01*
G01Y1194383D01*
G02X1107302Y1194204I-200J-1D01*
G01X1107301D01*
X1106932Y1194017D01*
X1106820Y1194026D01*
X1106774Y1194060D01*
G03X1106003Y1194313I-771J-1048D01*
G03Y1191709I0J-1302D01*
G03X1106774Y1191962I0J1301D01*
G01X1106820Y1191996D01*
X1106932Y1192005D01*
X1107301Y1191818D01*
G02X1107411Y1191639I-90J-179D01*
G01Y1186903D01*
G02X1107302Y1186724I-200J-1D01*
G01X1107301D01*
X1106932Y1186537D01*
X1106820Y1186546D01*
X1106774Y1186580D01*
G03X1106003Y1186833I-771J-1048D01*
G03Y1184229I0J-1302D01*
G03X1106774Y1184482I0J1301D01*
G01X1106820Y1184516D01*
X1106932Y1184525D01*
X1107301Y1184338D01*
G02X1107411Y1184159I-90J-179D01*
G01Y1183163D01*
G02X1107302Y1182984I-200J-1D01*
G01X1107301D01*
X1106932Y1182797D01*
X1106820Y1182806D01*
X1106774Y1182840D01*
G03X1106003Y1183093I-771J-1048D01*
G03Y1180489I0J-1302D01*
G03X1106774Y1180742I0J1301D01*
G01X1106820Y1180776D01*
X1106932Y1180785D01*
X1107301Y1180598D01*
G02X1107411Y1180419I-90J-179D01*
G01Y1179423D01*
G02X1107302Y1179244I-200J-1D01*
G01X1107301D01*
X1106932Y1179057D01*
X1106820Y1179066D01*
X1106774Y1179100D01*
G03X1106003Y1179353I-771J-1048D01*
G03Y1176749I0J-1302D01*
G01X1106005D01*
G03X1106389Y1176808I-3J1302D01*
G01X1106418Y1176817D01*
X1106462D01*
G02X1106647Y1176694I0J-200D01*
G01X1106671Y1176637D01*
X1106647Y1176519D01*
X1106336Y1176207D01*
X1106335Y1176206D01*
G03X1106323Y1176194I843J-855D01*
G01X1106190Y1176061D01*
X1106162Y1176032D01*
X1106088Y1176002D01*
X1100547D01*
G02X1100347Y1176202I0J200D01*
G01Y1184345D01*
G03X1100288Y1184486I-200J-1D01*
G01X1100165Y1184609D01*
X1100006Y1184769D01*
G03X1099994Y1184781I-856J-844D01*
G01X1099828Y1184947D01*
G02X1099769Y1185089I141J142D01*
G01Y1185155D01*
X1099776Y1185182D01*
G03X1099825Y1185531I-1253J354D01*
G03X1098523Y1186833I-1302J0D01*
G03X1097238Y1185740I0J-1302D01*
G01X1097226Y1185667D01*
X1097115Y1185572D01*
X1096191D01*
X1096080Y1185667D01*
X1096068Y1185740D01*
G03X1094569Y1186815I-1285J-209D01*
G01X1094522Y1186808D01*
X1094433Y1186835D01*
X1094132Y1187122D01*
X1094101Y1187210D01*
X1094106Y1187258D01*
G03X1094115Y1187401I-1193J147D01*
G03X1091711I-1202J0D01*
G03X1091720Y1187258I1202J4D01*
G01X1091725Y1187210D01*
X1091694Y1187122D01*
X1091393Y1186835D01*
X1091304Y1186808D01*
X1091257Y1186815D01*
G03X1090828I-215J-1284D01*
G01X1090781Y1186807D01*
X1090692Y1186835D01*
X1090391Y1187122D01*
X1090360Y1187210D01*
X1090365Y1187258D01*
G03X1090374Y1187401I-1193J147D01*
G03X1087970I-1202J0D01*
G03X1087979Y1187258I1202J4D01*
G01X1087984Y1187210D01*
X1087953Y1187122D01*
X1087652Y1186835D01*
X1087563Y1186808D01*
X1087516Y1186815D01*
G03X1087088I-214J-1284D01*
G01X1087041Y1186808D01*
X1086952Y1186835D01*
X1086651Y1187122D01*
X1086620Y1187210D01*
X1086625Y1187258D01*
G03X1086634Y1187401I-1193J147D01*
G03X1084230I-1202J0D01*
G03X1084239Y1187258I1202J4D01*
G01X1084244Y1187210D01*
X1084213Y1187122D01*
X1083912Y1186835D01*
X1083823Y1186808D01*
X1083776Y1186815D01*
G03X1083415Y1186825I-216J-1284D01*
G01X1083369Y1186820D01*
X1083284Y1186849D01*
X1082998Y1187134D01*
X1082967Y1187219D01*
X1082972Y1187265D01*
G03X1082980Y1187401I-1280J144D01*
G03X1080404I-1288J0D01*
G03X1080412Y1187265I1288J8D01*
G01X1080417Y1187220D01*
X1080386Y1187135D01*
X1080100Y1186850D01*
X1080015Y1186821D01*
X1079969Y1186826D01*
G03X1079822Y1186834I-144J-1295D01*
G01X1079631D01*
G02X1079483Y1186900I0J200D01*
G01X1079255Y1187151D01*
X1079229Y1187231D01*
X1079233Y1187274D01*
G03X1079240Y1187401I-1281J134D01*
G03X1076664I-1288J0D01*
G03X1076671Y1187274I1288J7D01*
G01X1076675Y1187231D01*
X1076649Y1187151D01*
X1076421Y1186900D01*
G02X1076273Y1186834I-148J134D01*
G01X1076082D01*
G03X1075868Y1186816I2J-1303D01*
G01X1075821Y1186808D01*
X1075732Y1186836D01*
X1075431Y1187123D01*
X1075400Y1187211D01*
X1075406Y1187258D01*
G03X1075414Y1187401I-1194J139D01*
G03X1073010I-1202J0D01*
G03X1073019Y1187258I1202J4D01*
G01X1073024Y1187210D01*
X1072993Y1187122D01*
X1072692Y1186835D01*
X1072603Y1186808D01*
X1072556Y1186815D01*
G03X1072195Y1186825I-216J-1284D01*
G01X1072149Y1186820D01*
X1072064Y1186849D01*
X1071778Y1187134D01*
X1071747Y1187219D01*
X1071752Y1187265D01*
G03X1071760Y1187401I-1280J144D01*
G03X1069184I-1288J0D01*
G03X1069192Y1187266I1287J9D01*
G01X1069196Y1187220D01*
X1069166Y1187135D01*
X1068880Y1186851D01*
X1068794Y1186822D01*
X1068749Y1186827D01*
G03X1068602Y1186835I-144J-1295D01*
G01X1068411D01*
G02X1068263Y1186901I0J200D01*
G01X1068035Y1187152D01*
X1068009Y1187232D01*
X1068013Y1187274D01*
G03X1068020Y1187401I-1281J134D01*
G03X1065444I-1288J0D01*
G03X1065451Y1187274I1288J7D01*
G01X1065455Y1187231D01*
X1065429Y1187151D01*
X1065201Y1186900D01*
G02X1065053Y1186834I-148J134D01*
G01X1064862D01*
G03X1064648Y1186816I2J-1302D01*
G01X1064600Y1186808D01*
X1064511Y1186836D01*
X1064210Y1187123D01*
X1064179Y1187211D01*
X1064184Y1187258D01*
G03X1064193Y1187401I-1193J147D01*
G03X1061789I-1202J0D01*
G03X1061798Y1187258I1202J4D01*
G01X1061803Y1187210D01*
X1061772Y1187122D01*
X1061471Y1186835D01*
X1061382Y1186808D01*
X1061335Y1186815D01*
G03X1060907I-214J-1284D01*
G01X1060860Y1186808D01*
X1060771Y1186835D01*
X1060470Y1187122D01*
X1060439Y1187210D01*
X1060444Y1187258D01*
G03X1060453Y1187401I-1193J147D01*
G03X1058049I-1202J0D01*
G03X1058058Y1187258I1202J4D01*
G01X1058063Y1187210D01*
X1058032Y1187122D01*
X1057731Y1186835D01*
X1057642Y1186808D01*
X1057595Y1186815D01*
G03X1056096Y1185740I-214J-1284D01*
G01X1056084Y1185667D01*
X1055973Y1185572D01*
X1038873D01*
G03X1038732Y1185513I1J-200D01*
G01X1038609Y1185390D01*
X1038449Y1185231D01*
X1038447Y1185229D01*
G03X1038437Y1185219I845J-855D01*
G01X1037554Y1184336D01*
G03X1037543Y1184325I844J-855D01*
G01X1037541Y1184323D01*
X1037383Y1184164D01*
X1037260Y1184041D01*
G03X1037201Y1183900I141J-142D01*
G01Y1176393D01*
G03X1037260Y1176252I200J1D01*
G01X1038621Y1174891D01*
X1038623Y1174888D01*
G03X1038636Y1174875I856J843D01*
G01X1038637Y1174874D01*
X1038770Y1174741D01*
G03X1038780Y1174731I855J845D01*
G01X1038782Y1174729D01*
X1038942Y1174570D01*
X1039065Y1174447D01*
G03X1039191Y1174389I141J141D01*
G01X1039227Y1174386D01*
X1039292Y1174356D01*
X1039339Y1174309D01*
G03X1039480Y1174251I141J142D01*
G01X1043933D01*
G02X1044075Y1174192I0J-200D01*
G01X1045320Y1172947D01*
G02X1045322Y1172945I-140J-142D01*
G02X1045379Y1172805I-143J-140D01*
G01Y1167128D01*
G02X1045320Y1166986I-200J0D01*
G01X1044493Y1166159D01*
X1044465Y1166130D01*
X1044391Y1166100D01*
X1040296D01*
G02X1040155Y1166158I0J200D01*
G03X1038041I-1057J-1067D01*
G02X1037900Y1166100I-141J142D01*
G01X1033482D01*
G02X1033340Y1166159I0J200D01*
G01X1031795Y1167704D01*
X1031766Y1167732D01*
X1031736Y1167806D01*
Y1195103D01*
G02X1031793Y1195243I200J0D01*
G01X1031794Y1195244D01*
X1033023Y1196473D01*
G02X1033025Y1196475I142J-140D01*
G02X1033165Y1196532I140J-143D01*
G01X1053543D01*
G02X1053734Y1196392I0J-200D01*
G03X1054881Y1195548I1147J357D01*
G03X1055768Y1195939I0J1202D01*
G01X1055769Y1195940D01*
X1055771Y1195942D01*
G02X1055922Y1196005I146J-137D01*
G01X1056268Y1195996D01*
X1056345Y1195958D01*
X1056373Y1195924D01*
G03X1057381Y1195447I1008J827D01*
G01X1057658D01*
G02X1057806Y1195381I0J-200D01*
G01X1058034Y1195128D01*
X1058060Y1195048D01*
X1058055Y1195006D01*
G03X1058049Y1194881I1196J-120D01*
G03X1060453I1202J0D01*
G03X1060447Y1195006I-1202J5D01*
G01X1060442Y1195048D01*
X1060468Y1195128D01*
X1060696Y1195381D01*
G02X1060844Y1195447I148J-134D01*
G01X1060851D01*
Y1195448D01*
X1061121D01*
G03X1061335Y1195466I-2J1302D01*
G01X1061382Y1195474D01*
X1061471Y1195446D01*
X1061772Y1195159D01*
X1061803Y1195071D01*
X1061797Y1195024D01*
G03X1061789Y1194881I1194J-139D01*
G03X1064193I1202J0D01*
G03X1064184Y1195025I-1202J-3D01*
G01X1064179Y1195072D01*
X1064210Y1195160D01*
X1064511Y1195447D01*
X1064600Y1195475D01*
X1064647Y1195467D01*
G03X1065009Y1195457I217J1283D01*
G01X1065055Y1195463D01*
X1065140Y1195433D01*
X1065426Y1195148D01*
X1065457Y1195063D01*
X1065452Y1195017D01*
G03X1065444Y1194881I1280J-144D01*
G03X1068020I1288J0D01*
G03X1068012Y1195018I-1288J-6D01*
G01X1068007Y1195064D01*
X1068037Y1195149D01*
X1068324Y1195434D01*
X1068409Y1195464D01*
X1068455Y1195458D01*
G03X1068602Y1195450I144J1294D01*
G03X1068749Y1195458I3J1301D01*
G01X1068795Y1195464D01*
X1068880Y1195434D01*
X1069167Y1195149D01*
X1069197Y1195064D01*
X1069192Y1195018D01*
G03X1069184Y1194881I1280J-143D01*
G03X1071760I1288J0D01*
G03X1071752Y1195018I-1288J-6D01*
G01X1071747Y1195064D01*
X1071777Y1195149D01*
X1072064Y1195434D01*
X1072149Y1195464D01*
X1072195Y1195458D01*
G03X1072342Y1195450I144J1293D01*
G03X1072556Y1195468I-2J1302D01*
G01X1072603Y1195476D01*
X1072692Y1195448D01*
X1072993Y1195160D01*
X1073024Y1195073D01*
X1073019Y1195025D01*
G03X1073010Y1194881I1193J-147D01*
G03X1075414I1202J0D01*
G03X1075405Y1195024I-1202J-4D01*
G01X1075400Y1195072D01*
X1075431Y1195160D01*
X1075732Y1195447D01*
X1075821Y1195475D01*
X1075868Y1195467D01*
G03X1076229Y1195457I216J1283D01*
G01X1076275Y1195463D01*
X1076360Y1195433D01*
X1076646Y1195148D01*
X1076677Y1195063D01*
X1076672Y1195017D01*
G03X1076664Y1194881I1280J-144D01*
G03X1079240I1288J0D01*
G03X1079232Y1195017I-1288J-8D01*
G01X1079227Y1195063D01*
X1079258Y1195148D01*
X1079544Y1195433D01*
X1079629Y1195463D01*
X1079675Y1195457D01*
G03X1079969I147J1294D01*
G01X1080015Y1195463D01*
X1080100Y1195433D01*
X1080386Y1195148D01*
X1080417Y1195063D01*
X1080412Y1195017D01*
G03X1080404Y1194881I1280J-144D01*
G03X1082980I1288J0D01*
G03X1082972Y1195017I-1288J-8D01*
G01X1082967Y1195063D01*
X1082998Y1195148D01*
X1083284Y1195433D01*
X1083369Y1195463D01*
X1083415Y1195457D01*
G03X1083776Y1195467I145J1293D01*
G01X1083823Y1195475D01*
X1083912Y1195447D01*
X1084213Y1195160D01*
X1084244Y1195072D01*
X1084239Y1195024D01*
G03X1084230Y1194881I1193J-147D01*
G03X1086634I1202J0D01*
G03X1086625Y1195024I-1202J-4D01*
G01X1086620Y1195072D01*
X1086651Y1195160D01*
X1086952Y1195447D01*
X1087041Y1195475D01*
X1087088Y1195467D01*
G03X1087302Y1195449I216J1283D01*
G01X1087336D01*
X1087337Y1195450D01*
X1087579D01*
G02X1087728Y1195384I0J-200D01*
G01X1087955Y1195131D01*
X1087981Y1195051D01*
X1087977Y1195008D01*
G03X1087970Y1194881I1195J-130D01*
G03X1090374I1202J0D01*
G03X1090367Y1195008I-1202J-3D01*
G01X1090363Y1195051D01*
X1090389Y1195131D01*
X1090616Y1195384D01*
G02X1090765Y1195450I149J-134D01*
G01X1091008D01*
X1091009Y1195449D01*
X1091043D01*
G03X1091257Y1195467I-2J1302D01*
G01X1091304Y1195475D01*
X1091393Y1195447D01*
X1091694Y1195160D01*
X1091725Y1195072D01*
X1091720Y1195024D01*
G03X1091711Y1194881I1193J-147D01*
G03X1094115I1202J0D01*
G03X1094106Y1195024I-1202J-4D01*
G01X1094101Y1195072D01*
X1094132Y1195160D01*
X1094433Y1195447D01*
X1094522Y1195475D01*
X1094569Y1195467D01*
G03X1096033Y1196387I214J1284D01*
G01Y1196389D01*
X1096034Y1196392D01*
G02X1096225Y1196532I191J-60D01*
G01X1097081D01*
G02X1097272Y1196392I0J-200D01*
G01X1097273Y1196389D01*
Y1196387D01*
G03X1099773I1250J364D01*
G01Y1196389D01*
X1099774Y1196392D01*
G02X1099965Y1196532I191J-60D01*
G01X1100821D01*
G02X1101012Y1196392I0J-200D01*
G01X1101013Y1196389D01*
Y1196387D01*
G03X1103513I1250J364D01*
G01Y1196389D01*
X1103514Y1196392D01*
G02X1103705Y1196532I191J-60D01*
G37*
G36*
G01X1095737Y1184570D02*
X1097570D01*
G02X1097670Y1184543I0J-200D01*
G01X1097689Y1184532D01*
X1097702Y1184522D01*
G03X1098523Y1184229I823J1009D01*
G03X1098916Y1184290I-1J1302D01*
G01X1098969Y1184307D01*
X1099077Y1184281D01*
X1099286Y1184072D01*
G02X1099288Y1184070I-140J-142D01*
G02X1099345Y1183930I-143J-140D01*
G01Y1183440D01*
G02X1099268Y1183282I-200J0D01*
G01X1098981Y1183059D01*
X1098891Y1183041D01*
X1098846Y1183052D01*
G03X1098523Y1183093I-324J-1261D01*
G03Y1180489I0J-1302D01*
G03X1098845Y1180530I-2J1302D01*
G02X1098938Y1180531I49J-194D01*
G01X1098983Y1180522D01*
X1099268Y1180300D01*
G02X1099345Y1180142I-123J-158D01*
G01Y1175973D01*
G02X1099286Y1175831I-200J0D01*
G01X1099031Y1175576D01*
X1098928Y1175549D01*
X1098875Y1175564D01*
G03X1098525Y1175612I-350J-1254D01*
G01X1098522D01*
G03X1097863Y1175433I0J-1302D01*
G01X1097841Y1175420D01*
X1097761Y1175398D01*
G02X1097707Y1175390I-56J192D01*
G01X1095599D01*
G02X1095545Y1175398I2J200D01*
G01X1095465Y1175420D01*
X1095443Y1175433D01*
G03X1094784Y1175612I-659J-1123D01*
G01X1094782D01*
G03X1094123Y1175433I0J-1302D01*
G01X1094101Y1175420D01*
X1094021Y1175398D01*
G02X1093967Y1175390I-56J192D01*
G01X1091859D01*
G02X1091805Y1175398I2J200D01*
G01X1091725Y1175420D01*
X1091703Y1175433D01*
G03X1091044Y1175612I-659J-1123D01*
G01X1091042D01*
G03X1090383Y1175433I0J-1302D01*
G01X1090361Y1175420D01*
X1090281Y1175398D01*
G02X1090227Y1175390I-56J192D01*
G01X1088118D01*
G02X1088064Y1175398I2J200D01*
G01X1087984Y1175420D01*
X1087962Y1175433D01*
G03X1087303Y1175612I-659J-1123D01*
G01X1087301D01*
G03X1086642Y1175433I0J-1302D01*
G01X1086620Y1175420D01*
X1086540Y1175398D01*
G02X1086486Y1175390I-56J192D01*
G01X1080638D01*
G02X1080584Y1175398I2J200D01*
G01X1080504Y1175420D01*
X1080482Y1175433D01*
G03X1079823Y1175612I-659J-1123D01*
G01X1079821D01*
G03X1079162Y1175433I0J-1302D01*
G01X1079140Y1175420D01*
X1079060Y1175398D01*
G02X1079006Y1175390I-56J192D01*
G01X1076898D01*
G02X1076844Y1175398I2J200D01*
G01X1076764Y1175420D01*
X1076742Y1175433D01*
G03X1076083Y1175612I-659J-1123D01*
G01X1076081D01*
G03X1075422Y1175433I0J-1302D01*
G01X1075400Y1175420D01*
X1075320Y1175398D01*
G02X1075266Y1175390I-56J192D01*
G01X1073158D01*
G02X1073104Y1175398I2J200D01*
G01X1073024Y1175420D01*
X1073002Y1175433D01*
G03X1072343Y1175612I-659J-1123D01*
G01X1072341D01*
G03X1071682Y1175433I0J-1302D01*
G01X1071660Y1175420D01*
X1071580Y1175398D01*
G02X1071526Y1175390I-56J192D01*
G01X1069418D01*
G02X1069364Y1175398I2J200D01*
G01X1069284Y1175420D01*
X1069262Y1175433D01*
G03X1068603Y1175612I-659J-1123D01*
G01X1068601D01*
G03X1067942Y1175433I0J-1302D01*
G01X1067920Y1175420D01*
X1067840Y1175398D01*
G02X1067786Y1175390I-56J192D01*
G01X1065677D01*
G02X1065623Y1175398I2J200D01*
G01X1065543Y1175420D01*
X1065521Y1175433D01*
G03X1064862Y1175612I-659J-1123D01*
G01X1064860D01*
G03X1064201Y1175433I0J-1302D01*
G01X1064179Y1175420D01*
X1064099Y1175398D01*
G02X1064045Y1175390I-56J192D01*
G01X1061936D01*
G02X1061882Y1175398I2J200D01*
G01X1061802Y1175420D01*
X1061780Y1175433D01*
G03X1061121Y1175612I-659J-1123D01*
G01X1061119D01*
G03X1060460Y1175433I0J-1302D01*
G01X1060438Y1175420D01*
X1060358Y1175398D01*
G02X1060304Y1175390I-56J192D01*
G01X1039621D01*
G02X1039479Y1175449I0J200D01*
G01X1039350Y1175578D01*
G02X1039335Y1175595I142J141D01*
G01X1039332Y1175599D01*
G02X1039294Y1175774I156J125D01*
G01X1039393Y1176159D01*
X1039466Y1176234D01*
X1039518Y1176249D01*
G03X1040600Y1177691I-420J1442D01*
G03X1039098Y1179193I-1502J0D01*
G03X1038719Y1179144I1J-1502D01*
G01X1038717D01*
X1038705Y1179141D01*
X1038645Y1179131D01*
X1038565Y1179152D01*
X1038532Y1179177D01*
X1038281Y1179369D01*
G02X1038203Y1179527I122J158D01*
G01Y1183485D01*
G02X1038260Y1183625I200J0D01*
G01X1038261Y1183626D01*
X1039146Y1184511D01*
G02X1039148Y1184513I142J-140D01*
G02X1039288Y1184570I140J-143D01*
G01X1056428D01*
G02X1056528Y1184543I0J-200D01*
G01X1056547Y1184532D01*
X1056560Y1184522D01*
G03X1057381Y1184229I823J1009D01*
G03X1057594Y1184247I-3J1301D01*
G01X1057642Y1184255D01*
X1057731Y1184228D01*
X1058032Y1183940D01*
X1058063Y1183852D01*
X1058058Y1183805D01*
G03X1058049Y1183661I1193J-147D01*
G03X1059251Y1182459I1202J0D01*
G03X1059472Y1182479I3J1202D01*
G01X1059522Y1182489D01*
X1059615Y1182460D01*
X1059919Y1182155D01*
X1059948Y1182062D01*
X1059939Y1182013D01*
G03X1059918Y1181791I1181J-224D01*
G03X1062322I1202J0D01*
G03X1062301Y1182013I-1202J-2D01*
G01X1062292Y1182062D01*
X1062321Y1182156D01*
X1062625Y1182460D01*
X1062720Y1182489D01*
X1062768Y1182480D01*
G03X1062991Y1182459I224J1181D01*
G03X1063213Y1182480I-2J1202D01*
G01X1063262Y1182489D01*
X1063355Y1182460D01*
X1063660Y1182155D01*
X1063689Y1182062D01*
X1063680Y1182013D01*
G03X1063659Y1181791I1181J-224D01*
G03X1066063I1202J0D01*
G03X1066042Y1182013I-1202J-2D01*
G01X1066033Y1182062D01*
X1066062Y1182156D01*
X1066366Y1182460D01*
X1066461Y1182489D01*
X1066509Y1182480D01*
G03X1066732Y1182459I224J1181D01*
G03X1066954Y1182480I-2J1202D01*
G01X1067003Y1182489D01*
X1067096Y1182460D01*
X1067401Y1182155D01*
X1067430Y1182062D01*
X1067421Y1182013D01*
G03X1067400Y1181791I1181J-224D01*
G03X1069804I1202J0D01*
G03X1069783Y1182013I-1202J-2D01*
G01X1069774Y1182062D01*
X1069803Y1182155D01*
X1070108Y1182460D01*
X1070201Y1182489D01*
X1070250Y1182480D01*
G03X1070472Y1182459I224J1181D01*
G03X1070694Y1182480I-2J1202D01*
G01X1070743Y1182489D01*
X1070836Y1182460D01*
X1071141Y1182155D01*
X1071170Y1182062D01*
X1071161Y1182013D01*
G03X1071140Y1181791I1181J-224D01*
G03X1073544I1202J0D01*
G03X1073523Y1182013I-1202J-2D01*
G01X1073514Y1182062D01*
X1073543Y1182155D01*
X1073848Y1182460D01*
X1073941Y1182489D01*
X1073990Y1182480D01*
G03X1074212Y1182459I224J1181D01*
G03X1074434Y1182480I-2J1202D01*
G01X1074483Y1182489D01*
X1074576Y1182460D01*
X1074881Y1182155D01*
X1074910Y1182062D01*
X1074901Y1182013D01*
G03X1074880Y1181791I1181J-224D01*
G03X1077284I1202J0D01*
G03X1077263Y1182013I-1202J-2D01*
G01X1077254Y1182062D01*
X1077283Y1182155D01*
X1077588Y1182460D01*
X1077681Y1182489D01*
X1077730Y1182480D01*
G03X1077952Y1182459I224J1181D01*
G03X1079154Y1183661I0J1202D01*
G03X1079147Y1183786I-1202J-5D01*
G01X1079143Y1183829D01*
X1079169Y1183909D01*
X1079397Y1184162D01*
G02X1079545Y1184228I148J-134D01*
G01X1079823D01*
G03X1080036Y1184246I-3J1303D01*
G01X1080083Y1184254D01*
X1080172Y1184226D01*
X1080473Y1183939D01*
X1080504Y1183851D01*
X1080499Y1183804D01*
G03X1080490Y1183661I1193J-147D01*
G03X1081692Y1182459I1202J0D01*
G03X1081914Y1182480I-2J1202D01*
G01X1081963Y1182489D01*
X1082056Y1182460D01*
X1082361Y1182155D01*
X1082390Y1182062D01*
X1082381Y1182013D01*
G03X1082360Y1181791I1181J-224D01*
G03X1082381Y1181569I1202J2D01*
G01X1082390Y1181520D01*
X1082361Y1181427D01*
X1082056Y1181122D01*
X1081963Y1181093D01*
X1081914Y1181102D01*
G03X1081692Y1181123I-224J-1181D01*
G03X1080490Y1179921I0J-1202D01*
G03X1080511Y1179698I1202J1D01*
G01X1080520Y1179650D01*
X1080491Y1179555D01*
X1080187Y1179251D01*
X1080093Y1179222D01*
X1080044Y1179231D01*
G03X1079822Y1179252I-224J-1181D01*
G03X1081024Y1178050I0J-1202D01*
G03X1081003Y1178273I-1202J-1D01*
G01X1080994Y1178321D01*
X1081023Y1178416D01*
X1081327Y1178720D01*
X1081421Y1178749D01*
X1081470Y1178740D01*
G03X1081692Y1178719I224J1181D01*
G03X1082894Y1179921I0J1202D01*
G03X1082873Y1180143I-1202J-2D01*
G01X1082864Y1180192D01*
X1082893Y1180285D01*
X1083198Y1180590D01*
X1083291Y1180619D01*
X1083340Y1180610D01*
G03X1083562Y1180589I224J1181D01*
G03X1084764Y1181791I0J1202D01*
G03X1084743Y1182013I-1202J-2D01*
G01X1084734Y1182062D01*
X1084763Y1182155D01*
X1085068Y1182460D01*
X1085161Y1182489D01*
X1085210Y1182480D01*
G03X1085432Y1182459I224J1181D01*
G03X1085654Y1182480I-2J1202D01*
G01X1085703Y1182489D01*
X1085796Y1182460D01*
X1086101Y1182155D01*
X1086130Y1182062D01*
X1086121Y1182013D01*
G03X1086100Y1181791I1181J-224D01*
G03X1087302Y1182993I1202J0D01*
G03X1087080Y1182972I2J-1202D01*
G01X1087031Y1182963D01*
X1086938Y1182992D01*
X1086633Y1183297D01*
X1086604Y1183390D01*
X1086613Y1183439D01*
G03X1086634Y1183661I-1181J224D01*
G03X1086625Y1183805I-1202J-3D01*
G01X1086620Y1183852D01*
X1086651Y1183940D01*
X1086952Y1184228D01*
X1087041Y1184255D01*
X1087089Y1184247D01*
G03X1087302Y1184229I216J1283D01*
G03X1088122Y1184521I-2J1302D01*
G01X1088136Y1184532D01*
X1088159Y1184545D01*
G02X1088256Y1184570I97J-175D01*
G01X1090090D01*
G02X1090190Y1184543I0J-200D01*
G01X1090209Y1184532D01*
X1090222Y1184522D01*
G03X1091043Y1184229I823J1009D01*
G03X1091863Y1184521I-2J1302D01*
G01X1091877Y1184532D01*
X1091900Y1184545D01*
G02X1091997Y1184570I97J-175D01*
G01X1093830D01*
G02X1093930Y1184543I0J-200D01*
G01X1093949Y1184532D01*
X1093962Y1184522D01*
G03X1094783Y1184229I823J1009D01*
G03X1095603Y1184521I-2J1302D01*
G01X1095617Y1184532D01*
X1095640Y1184545D01*
G02X1095737Y1184570I97J-175D01*
G37*
G36*
G01X1049272Y280161D02*
G03I-577J0D01*
G37*
G36*
G01X1157367Y680208D02*
X1164569D01*
G02X1164711Y680149I0J-200D01*
G01X1165304Y679556D01*
G02X1165362Y679414I-142J-141D01*
G01Y677260D01*
G03X1165949Y675845I2002J1D01*
G01X1166138Y675655D01*
G02X1166197Y675514I-141J-142D01*
G01Y582069D01*
G02X1166138Y581927I-200J0D01*
G01X1140287Y556076D01*
G02X1140146Y556017I-142J141D01*
G01X1139825Y556016D01*
X1139753Y556045D01*
X1139724Y556073D01*
G03X1138673Y556502I-1051J-1073D01*
G03X1137171Y555000I0J-1502D01*
G03X1137600Y553949I1502J0D01*
G01X1137628Y553920D01*
X1137657Y553848D01*
X1137656Y553527D01*
G02X1137597Y553386I-200J1D01*
G01X1134006Y549795D01*
G02X1133864Y549736I-142J141D01*
G01X1101851D01*
G02X1101710Y549794I0J200D01*
G01X1101481Y550021D01*
X1101451Y550093D01*
Y550133D01*
G03X1100937Y551254I-1502J-10D01*
G01X1100906Y551282D01*
X1100870Y551355D01*
X1100854Y551727D01*
X1100882Y551803D01*
X1100911Y551833D01*
G03X1101329Y552872I-1084J1040D01*
G03X1098325I-1502J0D01*
G03X1098839Y551741I1501J0D01*
G01X1098870Y551713D01*
X1098906Y551640D01*
X1098922Y551268D01*
X1098894Y551192D01*
X1098865Y551162D01*
G03X1098447Y550133I1084J-1040D01*
G01Y550093D01*
X1098417Y550021D01*
X1098188Y549794D01*
G02X1098047Y549736I-141J142D01*
G01X1068616D01*
G02X1068474Y549795I0J200D01*
G01X1057334Y560935D01*
G02X1057275Y561077I141J142D01*
G01Y623131D01*
G02X1057334Y623273I200J0D01*
G01X1059954Y625893D01*
G02X1060096Y625952I142J-141D01*
G01X1104504D01*
G02X1104646Y625893I0J-200D01*
G01X1109395Y621144D01*
G02X1109454Y621002I-141J-142D01*
G01Y611888D01*
G02X1109395Y611746I-200J0D01*
G01X1106318Y608669D01*
G02X1106176Y608610I-142J141D01*
G01X1073331D01*
G03X1073189Y608551I0J-200D01*
G01X1067983Y603345D01*
G03X1067924Y603203I141J-142D01*
G01Y574312D01*
G03X1067983Y574170I200J0D01*
G01X1077296Y564857D01*
G03X1077438Y564798I142J141D01*
G01X1116419D01*
G02X1116595Y564694I1J-200D01*
G03X1119231I1318J720D01*
G02X1119407Y564798I175J-96D01*
G01X1121846D01*
G03X1121988Y564857I0J200D01*
G01X1152295Y595164D01*
G03X1152354Y595306I-141J142D01*
G01Y677019D01*
G02X1152413Y677160I200J-1D01*
G01X1153844Y678592D01*
G02X1154055Y678638I141J-142D01*
G01X1154451Y678492D01*
X1154521Y678400D01*
X1154526Y678341D01*
G03X1156023Y676960I1497J121D01*
G03X1157525Y678462I0J1502D01*
G03X1157085Y679525I-1502J1D01*
G01X1157041Y679568D01*
X1157018Y679686D01*
X1157182Y680084D01*
G02X1157367Y680208I185J-76D01*
G37*
G36*
G01X1044751Y778835D02*
G03I-639J0D01*
G37*
G36*
G01X1043891Y902501D02*
G03I-639J0D01*
G37*
G36*
G01X1072218Y1058029D02*
G03I-577J0D01*
G37*
G36*
G01X1071925Y1050503D02*
G03I-577J0D01*
G37*
G36*
G01X1102780Y1138550D02*
X1107056D01*
G02X1107198Y1138491I0J-200D01*
G01X1107869Y1137820D01*
X1107883Y1137796D01*
G03X1108046Y1137573I1045J593D01*
G02X1108099Y1137437I-147J-136D01*
G01Y1136381D01*
G02X1108046Y1136245I-200J0D01*
G03X1107726Y1135431I882J-816D01*
G01Y1134647D01*
G03X1108046Y1133833I1202J2D01*
G02X1108099Y1133697I-147J-136D01*
G01Y1132641D01*
G02X1108046Y1132505I-200J0D01*
G03X1107726Y1131691I882J-816D01*
G01Y1130907D01*
G03X1108046Y1130093I1202J2D01*
G02X1108099Y1129957I-147J-136D01*
G01Y1128901D01*
G02X1108046Y1128765I-200J0D01*
G03X1107726Y1127951I882J-816D01*
G01Y1127166D01*
G03X1108046Y1126352I1202J2D01*
G02X1108099Y1126216I-147J-136D01*
G01Y1125160D01*
G02X1108046Y1125024I-200J0D01*
G03X1107726Y1124210I882J-816D01*
G01Y1123426D01*
G03X1108046Y1122612I1202J2D01*
G02X1108099Y1122476I-147J-136D01*
G01Y1121420D01*
G02X1108046Y1121284I-200J0D01*
G03X1107726Y1120470I882J-816D01*
G01Y1119686D01*
G03X1108046Y1118872I1202J2D01*
G02X1108099Y1118736I-147J-136D01*
G01Y1117680D01*
G02X1108046Y1117544I-200J0D01*
G03X1107726Y1116730I882J-816D01*
G01Y1115946D01*
G03X1108046Y1115132I1202J2D01*
G02X1108099Y1114996I-147J-136D01*
G01Y1113940D01*
G02X1108046Y1113804I-200J0D01*
G03X1107726Y1112990I882J-816D01*
G01Y1112206D01*
G03X1108046Y1111392I1202J2D01*
G02X1108099Y1111256I-147J-136D01*
G01Y1110451D01*
G02X1108048Y1110317I-200J-1D01*
G01X1107845Y1110090D01*
X1107780Y1110057D01*
X1107742Y1110053D01*
G03Y1107663I131J-1195D01*
G01X1107780Y1107659D01*
X1107845Y1107626D01*
X1108048Y1107399D01*
G02X1108099Y1107265I-149J-133D01*
G01Y1106795D01*
G02X1108048Y1106662I-200J0D01*
G01X1107843Y1106435D01*
X1107778Y1106402D01*
X1107740Y1106398D01*
G03Y1103836I134J-1281D01*
G01X1107778Y1103832D01*
X1107843Y1103799D01*
X1108048Y1103572D01*
G02X1108099Y1103439I-149J-133D01*
G01Y1103054D01*
G02X1108048Y1102921I-200J0D01*
G01X1107843Y1102694D01*
X1107778Y1102661D01*
X1107740Y1102657D01*
G03Y1100095I134J-1281D01*
G01X1107778Y1100091D01*
X1107843Y1100058D01*
X1108048Y1099831D01*
G02X1108099Y1099698I-149J-133D01*
G01Y1099230D01*
G02X1108048Y1099096I-200J-1D01*
G01X1107845Y1098869D01*
X1107780Y1098836D01*
X1107742Y1098832D01*
G03Y1096442I131J-1195D01*
G01X1107780Y1096438D01*
X1107845Y1096405D01*
X1108048Y1096178D01*
G02X1108099Y1096044I-149J-133D01*
G01Y1095490D01*
G02X1108048Y1095356I-200J-1D01*
G01X1107845Y1095129D01*
X1107780Y1095096D01*
X1107742Y1095092D01*
G03Y1092702I131J-1195D01*
G01X1107780Y1092698D01*
X1107845Y1092665D01*
X1108048Y1092438D01*
G02X1108099Y1092304I-149J-133D01*
G01Y1091750D01*
G02X1108048Y1091616I-200J-1D01*
G01X1107845Y1091389D01*
X1107780Y1091356D01*
X1107742Y1091352D01*
G03Y1088962I131J-1195D01*
G01X1107780Y1088958D01*
X1107845Y1088925D01*
X1108048Y1088698D01*
G02X1108099Y1088564I-149J-133D01*
G01Y1088095D01*
G02X1108048Y1087962I-200J0D01*
G01X1107843Y1087735D01*
X1107778Y1087702D01*
X1107740Y1087698D01*
G03Y1085136I134J-1281D01*
G01X1107778Y1085132D01*
X1107843Y1085099D01*
X1108048Y1084872D01*
G02X1108099Y1084739I-149J-133D01*
G01Y1084355D01*
G02X1108048Y1084222I-200J0D01*
G01X1107843Y1083995D01*
X1107778Y1083962D01*
X1107740Y1083958D01*
G03Y1081396I134J-1281D01*
G01X1107778Y1081392D01*
X1107843Y1081359D01*
X1108048Y1081132D01*
G02X1108099Y1080999I-149J-133D01*
G01Y1080529D01*
G02X1108048Y1080395I-200J-1D01*
G01X1107845Y1080168D01*
X1107780Y1080135D01*
X1107742Y1080131D01*
G03Y1077741I131J-1195D01*
G01X1107780Y1077737D01*
X1107845Y1077704D01*
X1108048Y1077477D01*
G02X1108099Y1077343I-149J-133D01*
G01Y1076789D01*
G02X1108048Y1076655I-200J-1D01*
G01X1107845Y1076428D01*
X1107780Y1076395D01*
X1107742Y1076391D01*
G03Y1074001I131J-1195D01*
G01X1107780Y1073997D01*
X1107845Y1073964D01*
X1108048Y1073737D01*
G02X1108099Y1073603I-149J-133D01*
G01Y1070298D01*
G02X1108046Y1070162I-200J0D01*
G03X1107766Y1069651I882J-816D01*
G01X1107759Y1069625D01*
X1107733Y1069580D01*
X1103677Y1065524D01*
G02X1103535Y1065465I-142J141D01*
G01X1073185D01*
G02X1073043Y1065524I0J200D01*
G01X1072415Y1066152D01*
G02X1072356Y1066294I141J142D01*
G01Y1071249D01*
G02X1072415Y1071391I200J0D01*
G01X1072422Y1071398D01*
X1087866D01*
X1087976Y1071307D01*
X1087989Y1071235D01*
G03X1090353I1182J220D01*
G01X1090366Y1071307D01*
X1090476Y1071398D01*
X1095347D01*
X1095457Y1071307D01*
X1095470Y1071235D01*
G03X1096652Y1070253I1182J220D01*
G03X1097854Y1071455I0J1202D01*
G03X1097734Y1071979I-1202J0D01*
G01X1097706Y1072037D01*
X1097727Y1072163D01*
X1099685Y1074121D01*
X1099811Y1074142D01*
X1099869Y1074114D01*
G03X1100393Y1073994I524J1082D01*
G03X1101595Y1075196I0J1202D01*
G03X1100803Y1076326I-1202J0D01*
G01X1100744Y1076347D01*
X1100672Y1076451D01*
Y1077681D01*
X1100744Y1077785D01*
X1100803Y1077806D01*
G03Y1080066I-410J1130D01*
G01X1100744Y1080087D01*
X1100672Y1080191D01*
Y1081333D01*
X1100746Y1081437D01*
X1100807Y1081458D01*
G03Y1083896I-415J1219D01*
G01X1100746Y1083917D01*
X1100672Y1084021D01*
Y1085073D01*
X1100746Y1085177D01*
X1100807Y1085198D01*
G03Y1087636I-415J1219D01*
G01X1100746Y1087657D01*
X1100672Y1087761D01*
Y1088902D01*
X1100744Y1089006D01*
X1100803Y1089027D01*
G03Y1091287I-410J1130D01*
G01X1100744Y1091308D01*
X1100672Y1091412D01*
Y1092642D01*
X1100744Y1092746D01*
X1100803Y1092767D01*
G03Y1095027I-410J1130D01*
G01X1100744Y1095048D01*
X1100672Y1095152D01*
Y1096382D01*
X1100744Y1096486D01*
X1100803Y1096507D01*
G03Y1098767I-410J1130D01*
G01X1100744Y1098788D01*
X1100672Y1098892D01*
Y1100032D01*
X1100746Y1100136D01*
X1100807Y1100157D01*
G03Y1102595I-415J1219D01*
G01X1100746Y1102616D01*
X1100672Y1102720D01*
Y1103773D01*
X1100746Y1103877D01*
X1100807Y1103898D01*
G03Y1106336I-415J1219D01*
G01X1100746Y1106357D01*
X1100672Y1106461D01*
Y1107603D01*
X1100744Y1107707D01*
X1100803Y1107728D01*
G03Y1109988I-410J1130D01*
G01X1100744Y1110009D01*
X1100672Y1110113D01*
Y1113397D01*
G02X1100800Y1113584I200J1D01*
G01X1101207Y1113740D01*
X1101327Y1113711D01*
X1101369Y1113665D01*
G03X1102263Y1113266I894J802D01*
G03Y1115670I0J1202D01*
G03X1101369Y1115271I0J-1201D01*
G01X1101327Y1115225D01*
X1101207Y1115196D01*
X1100800Y1115352D01*
G02X1100672Y1115539I72J186D01*
G01Y1117137D01*
G02X1100800Y1117324I200J1D01*
G01X1101207Y1117480D01*
X1101327Y1117451D01*
X1101369Y1117405D01*
G03X1102263Y1117006I894J802D01*
G03Y1119410I0J1202D01*
G03X1101369Y1119011I0J-1201D01*
G01X1101327Y1118965D01*
X1101207Y1118936D01*
X1100800Y1119092D01*
G02X1100672Y1119279I72J186D01*
G01Y1120877D01*
G02X1100800Y1121064I200J1D01*
G01X1101207Y1121220D01*
X1101327Y1121191D01*
X1101369Y1121145D01*
G03X1102263Y1120746I894J802D01*
G03Y1123150I0J1202D01*
G03X1101369Y1122751I0J-1201D01*
G01X1101327Y1122705D01*
X1101207Y1122676D01*
X1100800Y1122832D01*
G02X1100672Y1123019I72J186D01*
G01Y1124617D01*
G02X1100800Y1124804I200J1D01*
G01X1101207Y1124960D01*
X1101327Y1124931D01*
X1101369Y1124885D01*
G03X1102263Y1124486I894J802D01*
G03Y1126890I0J1202D01*
G03X1101369Y1126491I0J-1201D01*
G01X1101327Y1126445D01*
X1101207Y1126416D01*
X1100800Y1126572D01*
G02X1100672Y1126759I72J186D01*
G01Y1128358D01*
G02X1100800Y1128545I200J1D01*
G01X1101207Y1128701D01*
X1101327Y1128672D01*
X1101369Y1128626D01*
G03X1102263Y1128227I894J802D01*
G03Y1130631I0J1202D01*
G03X1101369Y1130232I0J-1201D01*
G01X1101327Y1130186D01*
X1101207Y1130157D01*
X1100800Y1130313D01*
G02X1100672Y1130500I72J186D01*
G01Y1132098D01*
G02X1100800Y1132285I200J1D01*
G01X1101207Y1132441D01*
X1101327Y1132412D01*
X1101369Y1132366D01*
G03X1102263Y1131967I894J802D01*
G03Y1134371I0J1202D01*
G03X1101369Y1133972I0J-1201D01*
G01X1101327Y1133926D01*
X1101207Y1133897D01*
X1100800Y1134053D01*
G02X1100672Y1134240I72J186D01*
G01Y1135361D01*
G03X1100613Y1135502I-200J-1D01*
G01X1100476Y1135640D01*
G02X1100417Y1135781I141J142D01*
G01Y1136867D01*
G02X1100476Y1137009I200J0D01*
G01X1100734Y1137267D01*
G02X1100875Y1137326I142J-141D01*
G01X1100878D01*
G02X1101078Y1137126I0J-200D01*
G01Y1137110D01*
X1101075Y1137095D01*
G03X1101061Y1136909I1188J-183D01*
G03X1103465I1202J0D01*
G03X1102767Y1138000I-1202J0D01*
G02X1102660Y1138122I84J182D01*
G01X1102621Y1138245D01*
G02X1102639Y1138405I191J60D01*
G03X1102660Y1138444I-1047J589D01*
G01X1102686Y1138493D01*
X1102780Y1138550D01*
G37*
G36*
G01X1154193Y54588D02*
X1182695D01*
X1183133Y54150D01*
Y53029D01*
X1182695Y52591D01*
X1154193D01*
G03X1148256Y46654I0J-5937D01*
G01Y7874D01*
G02X1142382Y2000I-5874J0D01*
G01X1095138D01*
G02X1089264Y7874I0J5874D01*
G01Y46654D01*
G03Y46656I-5937J1D01*
G01X1091262D01*
Y7874D01*
G03X1095138Y3998I3876J0D01*
G01X1142382D01*
G03X1146258Y7874I0J3876D01*
G01Y46654D01*
G02X1154193Y54588I7935J-1D01*
G37*
G36*
G01X1080386Y1034386D02*
G03I-577J0D01*
G37*
G36*
G01X1082191Y1640501D02*
X1108926D01*
G02X1109066Y1640444I0J-200D01*
G01X1109067Y1640443D01*
X1112406Y1637104D01*
G02X1112408Y1637102I-140J-142D01*
G02X1112465Y1636962I-143J-140D01*
G01Y1517299D01*
G02X1112406Y1517157I-200J0D01*
G01X1107639Y1512390D01*
G02X1107497Y1512331I-142J141D01*
G01X1085839D01*
G02X1085697Y1512390I0J200D01*
G01X1077342Y1520745D01*
G02X1077283Y1520887I141J142D01*
G01Y1635593D01*
G02X1077342Y1635735I200J0D01*
G01X1082049Y1640442D01*
G02X1082051Y1640444I142J-140D01*
G02X1082191Y1640501I140J-143D01*
G37*
G36*
G01X1122830Y396240D02*
G03I-577J0D01*
G37*
G36*
G01Y403327D02*
G03I-577J0D01*
G37*
G36*
G01Y410413D02*
G03I-577J0D01*
G37*
G36*
G01Y424586D02*
G03I-577J0D01*
G37*
G36*
G01Y417500D02*
G03I-577J0D01*
G37*
G36*
G01Y438760D02*
G03I-577J0D01*
G37*
G36*
G01Y431673D02*
G03I-577J0D01*
G37*
G36*
G01Y445847D02*
G03I-577J0D01*
G37*
G36*
G01Y488799D02*
G03I-577J0D01*
G37*
G36*
G01Y474626D02*
G03I-577J0D01*
G37*
G36*
G01Y481712D02*
G03I-577J0D01*
G37*
G36*
G01Y495886D02*
G03I-577J0D01*
G37*
G36*
G01Y518760D02*
G03I-577J0D01*
G37*
G36*
G01Y532933D02*
G03I-577J0D01*
G37*
G36*
G01Y525846D02*
G03I-577J0D01*
G37*
G36*
G01Y540020D02*
G03I-577J0D01*
G37*
G36*
G01X1123295Y598857D02*
G03I-577J0D01*
G37*
G36*
G01X1121768Y612555D02*
G03I-577J0D01*
G37*
G36*
G01X1121089Y617332D02*
G03I-577J0D01*
G37*
G36*
G01X1121599Y607750D02*
G03I-577J0D01*
G37*
G36*
G01X1309383Y1299758D02*
X1364399D01*
G02X1364539Y1299701I0J-200D01*
G01X1364540Y1299700D01*
X1377782Y1286458D01*
G02X1377841Y1286316I-141J-142D01*
G01Y1256065D01*
G02X1377781Y1255922I-200J0D01*
G01X1377545Y1255693D01*
X1377472Y1255664D01*
X1377430Y1255665D01*
G03X1377390Y1255666I-58J-1501D01*
G03Y1252662I0J-1502D01*
G03X1377612Y1252678I3J1502D01*
G01X1377626Y1252681D01*
X1377641D01*
G02X1377841Y1252481I0J-200D01*
G01Y1252443D01*
G02X1377641Y1252243I-200J0D01*
G01X1377626D01*
X1377612Y1252246D01*
G03X1377390Y1252262I-219J-1486D01*
G03Y1249258I0J-1502D01*
G03X1377430Y1249259I-18J1502D01*
G01X1377472Y1249260D01*
X1377545Y1249231D01*
X1377781Y1249002D01*
G02X1377841Y1248859I-140J-143D01*
G01Y1245956D01*
G02X1377781Y1245813I-200J0D01*
G01X1377545Y1245584D01*
X1377472Y1245555D01*
X1377430Y1245556D01*
G03X1377390Y1245557I-58J-1501D01*
G03Y1242553I0J-1502D01*
G03X1377430Y1242554I-18J1502D01*
G01X1377472Y1242555D01*
X1377545Y1242526D01*
X1377781Y1242297D01*
G02X1377841Y1242154I-140J-143D01*
G01Y1158379D01*
G02X1377782Y1158237I-200J0D01*
G01X1376980Y1157435D01*
G02X1376838Y1157376I-142J141D01*
G01X1372723D01*
G03X1372671Y1157369I0J-200D01*
G01X1372658Y1157365D01*
X1372610Y1157346D01*
X1312706D01*
G03X1312564Y1157287I0J-200D01*
G01X1310151Y1154874D01*
X1310123Y1154845D01*
X1310049Y1154815D01*
X1307318D01*
X1307298Y1154819D01*
G03X1304530Y1155094I-2768J-13795D01*
G01X1304528D01*
G03Y1126954I0J-14070D01*
G03X1304847Y1126958I-17J14070D01*
G01X1304888Y1126959D01*
X1304962Y1126930D01*
X1305196Y1126701D01*
G02X1305256Y1126558I-140J-143D01*
G01Y1046572D01*
X1305226Y1046498D01*
X1305197Y1046470D01*
X1304444Y1045718D01*
X1304397Y1045692D01*
X1304370Y1045685D01*
G03X1303619Y1045353I542J-2242D01*
G02X1303506Y1045319I-112J166D01*
G01X1253257D01*
G02X1253144Y1045353I-1J200D01*
G03X1251852Y1045750I-1294J-1909D01*
G01X1177263D01*
G03X1175632Y1045074I1J-2307D01*
G01X1173829Y1043271D01*
G02X1173687Y1043212I-142J141D01*
G01X1116439D01*
G02X1116297Y1043271I0J200D01*
G01X1108787Y1050781D01*
X1108758Y1050809D01*
X1108728Y1050883D01*
Y1069347D01*
G02X1108817Y1069513I200J0D01*
G01X1109094Y1069698D01*
G02X1109282Y1069716I111J-167D01*
G03X1109743Y1069624I461J1109D01*
G03X1110782Y1070222I0J1202D01*
G02X1110891Y1070311I173J-101D01*
G01X1111009Y1070350D01*
G02X1111150Y1070345I64J-189D01*
G03X1111612Y1070253I461J1110D01*
G03Y1072657I0J1202D01*
G03X1111469Y1072648I4J-1202D01*
G01X1111422Y1072643D01*
X1111334Y1072674D01*
X1111047Y1072975D01*
X1111019Y1073064D01*
X1111027Y1073111D01*
G03X1111045Y1073326I-1284J216D01*
G01Y1073517D01*
G02X1111111Y1073665I200J0D01*
G01X1111362Y1073893D01*
X1111442Y1073919D01*
X1111485Y1073915D01*
G03X1111613Y1073908I134J1281D01*
G03Y1076484I0J1288D01*
G03X1111484Y1076477I5J-1288D01*
G01X1111441Y1076473D01*
X1111362Y1076499D01*
X1111110Y1076727D01*
G02X1111044Y1076875I134J148D01*
G01Y1077066D01*
G03X1111036Y1077213I-1302J3D01*
G01X1111030Y1077259D01*
X1111060Y1077344D01*
X1111345Y1077631D01*
X1111430Y1077661D01*
X1111476Y1077656D01*
G03X1111613Y1077648I143J1280D01*
G03Y1080224I0J1288D01*
G03X1111398Y1080205I5J-1288D01*
G01X1111351Y1080197D01*
X1111261Y1080225D01*
X1110960Y1080515D01*
X1110929Y1080604D01*
X1110935Y1080652D01*
G03X1110945Y1080807I-1192J155D01*
G03X1110924Y1081029I-1202J-2D01*
G01X1110915Y1081078D01*
X1110944Y1081171D01*
X1111249Y1081476D01*
X1111342Y1081505D01*
X1111391Y1081496D01*
G03X1111613Y1081475I224J1181D01*
G03Y1083879I0J1202D01*
G03X1111391Y1083858I2J-1202D01*
G01X1111342Y1083849D01*
X1111249Y1083878D01*
X1110944Y1084183D01*
X1110915Y1084276D01*
X1110924Y1084325D01*
G03X1110945Y1084547I-1181J224D01*
G03X1110924Y1084769I-1202J-2D01*
G01X1110915Y1084818D01*
X1110944Y1084911D01*
X1111249Y1085216D01*
X1111342Y1085245D01*
X1111391Y1085236D01*
G03X1111613Y1085215I224J1181D01*
G03Y1087619I0J1202D01*
G03X1111391Y1087598I2J-1202D01*
G01X1111342Y1087589D01*
X1111249Y1087618D01*
X1110944Y1087923D01*
X1110915Y1088016D01*
X1110924Y1088065D01*
G03X1110945Y1088287I-1181J224D01*
G03X1110924Y1088509I-1202J-2D01*
G01X1110915Y1088558D01*
X1110944Y1088651D01*
X1111249Y1088956D01*
X1111342Y1088985D01*
X1111391Y1088976D01*
G03X1111613Y1088955I224J1181D01*
G03Y1091359I0J1202D01*
G03X1111469Y1091350I3J-1202D01*
G01X1111421Y1091345D01*
X1111334Y1091376D01*
X1111046Y1091677D01*
X1111018Y1091766D01*
X1111026Y1091813D01*
G03X1111044Y1092027I-1285J216D01*
G01Y1092218D01*
G02X1111110Y1092366I200J0D01*
G01X1111362Y1092594D01*
X1111441Y1092620D01*
X1111484Y1092616D01*
G03X1111613Y1092610I124J1281D01*
G03Y1095184I0J1287D01*
G03X1111484Y1095178I-5J-1287D01*
G01X1111441Y1095174D01*
X1111362Y1095200D01*
X1111110Y1095428D01*
G02X1111044Y1095576I134J148D01*
G01Y1095767D01*
G03X1111036Y1095914I-1303J3D01*
G01X1111030Y1095960D01*
X1111060Y1096045D01*
X1111345Y1096332D01*
X1111430Y1096362D01*
X1111476Y1096357D01*
G03X1111613Y1096350I134J1280D01*
G03Y1098924I0J1287D01*
G03X1111398Y1098906I-1J-1287D01*
G01X1111351Y1098899D01*
X1111261Y1098926D01*
X1110960Y1099216D01*
X1110929Y1099305D01*
X1110935Y1099352D01*
G03X1110945Y1099507I-1192J155D01*
G03X1110924Y1099729I-1202J-2D01*
G01X1110915Y1099778D01*
X1110944Y1099871D01*
X1111249Y1100176D01*
X1111342Y1100205D01*
X1111391Y1100196D01*
G03X1111613Y1100175I224J1181D01*
G03Y1102579I0J1202D01*
G03X1111391Y1102558I2J-1202D01*
G01X1111342Y1102549D01*
X1111249Y1102578D01*
X1110944Y1102883D01*
X1110915Y1102976D01*
X1110924Y1103025D01*
G03X1110945Y1103247I-1181J224D01*
G03X1110924Y1103469I-1202J-2D01*
G01X1110915Y1103518D01*
X1110944Y1103611D01*
X1111249Y1103916D01*
X1111342Y1103945D01*
X1111391Y1103936D01*
G03X1111613Y1103915I224J1181D01*
G03Y1106319I0J1202D01*
G03X1111391Y1106298I2J-1202D01*
G01X1111342Y1106289D01*
X1111248Y1106318D01*
X1110944Y1106622D01*
X1110915Y1106717D01*
X1110924Y1106765D01*
G03X1110945Y1106988I-1181J224D01*
G03X1110924Y1107210I-1202J-2D01*
G01X1110915Y1107259D01*
X1110944Y1107352D01*
X1111249Y1107657D01*
X1111342Y1107686D01*
X1111391Y1107677D01*
G03X1111613Y1107656I224J1181D01*
G03Y1110060I0J1202D01*
G03X1111391Y1110039I2J-1202D01*
G01X1111342Y1110030D01*
X1111249Y1110059D01*
X1110944Y1110364D01*
X1110915Y1110457D01*
X1110924Y1110506D01*
G03X1110945Y1110728I-1181J224D01*
G03X1109743Y1111930I-1202J0D01*
G03X1109282Y1111838I0J-1201D01*
G02X1109094Y1111856I-77J185D01*
G01X1108817Y1112041D01*
G02X1108728Y1112207I111J166D01*
G01Y1112989D01*
G02X1108817Y1113155I200J0D01*
G01X1109136Y1113368D01*
X1109234Y1113378D01*
X1109282Y1113358D01*
G03X1109743Y1113266I461J1109D01*
G03Y1115670I0J1202D01*
G03X1109282Y1115578I0J-1201D01*
G01X1109234Y1115558D01*
X1109136Y1115568D01*
X1108817Y1115781D01*
G02X1108728Y1115947I111J166D01*
G01Y1116729D01*
G02X1108817Y1116895I200J0D01*
G01X1109136Y1117108D01*
X1109234Y1117118D01*
X1109282Y1117098D01*
G03X1109743Y1117006I461J1109D01*
G03Y1119410I0J1202D01*
G03X1109282Y1119318I0J-1201D01*
G01X1109234Y1119298D01*
X1109136Y1119308D01*
X1108817Y1119521D01*
G02X1108728Y1119687I111J166D01*
G01Y1120469D01*
G02X1108817Y1120635I200J0D01*
G01X1109136Y1120848D01*
X1109234Y1120858D01*
X1109282Y1120838D01*
G03X1109743Y1120746I461J1109D01*
G03Y1123150I0J1202D01*
G03X1109282Y1123058I0J-1201D01*
G01X1109234Y1123038D01*
X1109136Y1123048D01*
X1108817Y1123261D01*
G02X1108728Y1123427I111J166D01*
G01Y1124209D01*
G02X1108817Y1124375I200J0D01*
G01X1109136Y1124588D01*
X1109234Y1124598D01*
X1109282Y1124578D01*
G03X1109743Y1124486I461J1109D01*
G03Y1126890I0J1202D01*
G03X1109282Y1126798I0J-1201D01*
G01X1109234Y1126778D01*
X1109136Y1126788D01*
X1108817Y1127001D01*
G02X1108728Y1127167I111J166D01*
G01Y1127950D01*
G02X1108817Y1128116I200J0D01*
G01X1109136Y1128329D01*
X1109234Y1128339D01*
X1109282Y1128319D01*
G03X1109743Y1128227I461J1109D01*
G03Y1130631I0J1202D01*
G03X1109282Y1130539I0J-1201D01*
G01X1109234Y1130519D01*
X1109136Y1130529D01*
X1108817Y1130742D01*
G02X1108728Y1130908I111J166D01*
G01Y1131690D01*
G02X1108817Y1131856I200J0D01*
G01X1109136Y1132069D01*
X1109234Y1132079D01*
X1109282Y1132059D01*
G03X1109743Y1131967I461J1109D01*
G03Y1134371I0J1202D01*
G03X1109282Y1134279I0J-1201D01*
G01X1109234Y1134259D01*
X1109136Y1134269D01*
X1108817Y1134482D01*
G02X1108728Y1134648I111J166D01*
G01Y1135430D01*
G02X1108817Y1135596I200J0D01*
G01X1109136Y1135809D01*
X1109234Y1135819D01*
X1109282Y1135799D01*
G03X1109743Y1135707I461J1109D01*
G03Y1138111I0J1202D01*
G03X1109282Y1138019I0J-1201D01*
G01X1109234Y1137999D01*
X1109136Y1138009D01*
X1108817Y1138222D01*
G02X1108728Y1138388I111J166D01*
G01Y1139170D01*
G02X1108817Y1139336I200J0D01*
G01X1109136Y1139549D01*
X1109234Y1139559D01*
X1109282Y1139539D01*
G03X1109743Y1139447I461J1109D01*
G03Y1141851I0J1202D01*
G03X1109282Y1141759I0J-1201D01*
G01X1109234Y1141739D01*
X1109136Y1141749D01*
X1108817Y1141962D01*
G02X1108728Y1142128I111J166D01*
G01Y1142910D01*
G02X1108817Y1143076I200J0D01*
G01X1109136Y1143289D01*
X1109234Y1143299D01*
X1109282Y1143279D01*
G03X1109743Y1143187I461J1109D01*
G03Y1145591I0J1202D01*
G03X1109282Y1145499I0J-1201D01*
G01X1109234Y1145479D01*
X1109136Y1145489D01*
X1108817Y1145702D01*
G02X1108728Y1145868I111J166D01*
G01Y1150390D01*
G02X1108817Y1150556I200J0D01*
G01X1109136Y1150769D01*
X1109234Y1150779D01*
X1109282Y1150759D01*
G03X1109743Y1150667I461J1109D01*
G03Y1153071I0J1202D01*
G03X1109282Y1152979I0J-1201D01*
G01X1109234Y1152959D01*
X1109136Y1152969D01*
X1108817Y1153182D01*
G02X1108728Y1153348I111J166D01*
G01Y1157871D01*
G02X1108817Y1158037I200J0D01*
G01X1109136Y1158250D01*
X1109234Y1158260D01*
X1109282Y1158240D01*
G03X1109743Y1158148I461J1109D01*
G03Y1160552I0J1202D01*
G03X1109282Y1160460I0J-1201D01*
G01X1109234Y1160440D01*
X1109136Y1160450D01*
X1108817Y1160663D01*
G02X1108728Y1160829I111J166D01*
G01Y1169091D01*
G02X1108817Y1169257I200J0D01*
G01X1109136Y1169470D01*
X1109234Y1169480D01*
X1109282Y1169460D01*
G03X1109743Y1169368I461J1109D01*
G03Y1171772I0J1202D01*
G03X1109282Y1171680I0J-1201D01*
G01X1109234Y1171660D01*
X1109136Y1171670D01*
X1108817Y1171883D01*
G02X1108728Y1172049I111J166D01*
G01Y1176572D01*
G02X1108817Y1176738I200J0D01*
G01X1109136Y1176951D01*
X1109234Y1176961D01*
X1109282Y1176941D01*
G03X1109743Y1176849I461J1109D01*
G03Y1179253I0J1202D01*
G03X1109282Y1179161I0J-1201D01*
G01X1109234Y1179141D01*
X1109136Y1179151D01*
X1108817Y1179364D01*
G02X1108728Y1179530I111J166D01*
G01Y1184052D01*
G02X1108817Y1184218I200J0D01*
G01X1109136Y1184431D01*
X1109234Y1184441D01*
X1109282Y1184421D01*
G03X1109743Y1184329I461J1109D01*
G03Y1186733I0J1202D01*
G03X1109282Y1186641I0J-1201D01*
G01X1109234Y1186621D01*
X1109136Y1186631D01*
X1108817Y1186844D01*
G02X1108728Y1187010I111J166D01*
G01Y1187792D01*
G02X1108817Y1187958I200J0D01*
G01X1109136Y1188171D01*
X1109234Y1188181D01*
X1109282Y1188161D01*
G03X1109743Y1188069I461J1109D01*
G03Y1190473I0J1202D01*
G03X1109282Y1190381I0J-1201D01*
G01X1109234Y1190361D01*
X1109136Y1190371D01*
X1108817Y1190584D01*
G02X1108728Y1190750I111J166D01*
G01Y1191532D01*
G02X1108817Y1191698I200J0D01*
G01X1109136Y1191911D01*
X1109234Y1191921D01*
X1109282Y1191901D01*
G03X1109743Y1191809I461J1109D01*
G03Y1194213I0J1202D01*
G03X1109282Y1194121I0J-1201D01*
G01X1109234Y1194101D01*
X1109136Y1194111D01*
X1108817Y1194324D01*
G02X1108728Y1194490I111J166D01*
G01Y1195272D01*
G02X1108817Y1195438I200J0D01*
G01X1109136Y1195651D01*
X1109234Y1195661D01*
X1109282Y1195641D01*
G03X1109743Y1195549I461J1109D01*
G03Y1197953I0J1202D01*
G03X1109282Y1197861I0J-1201D01*
G01X1109234Y1197841D01*
X1109136Y1197851D01*
X1108817Y1198064D01*
G02X1108728Y1198230I111J166D01*
G01Y1199012D01*
G02X1108817Y1199178I200J0D01*
G01X1109136Y1199391D01*
X1109234Y1199401D01*
X1109282Y1199381D01*
G03X1109743Y1199289I461J1109D01*
G03Y1201693I0J1202D01*
G03X1109282Y1201601I0J-1201D01*
G01X1109234Y1201581D01*
X1109136Y1201591D01*
X1108817Y1201804D01*
G02X1108728Y1201970I111J166D01*
G01Y1202753D01*
G02X1108817Y1202919I200J0D01*
G01X1109136Y1203132D01*
X1109234Y1203142D01*
X1109282Y1203122D01*
G03X1109743Y1203030I461J1109D01*
G03Y1205434I0J1202D01*
G03X1109282Y1205342I0J-1201D01*
G01X1109234Y1205322D01*
X1109136Y1205332D01*
X1108817Y1205545D01*
G02X1108728Y1205711I111J166D01*
G01Y1206493D01*
G02X1108817Y1206659I200J0D01*
G01X1109136Y1206872D01*
X1109234Y1206882D01*
X1109282Y1206862D01*
G03X1109743Y1206770I461J1109D01*
G03Y1209174I0J1202D01*
G03X1109282Y1209082I0J-1201D01*
G01X1109234Y1209062D01*
X1109136Y1209072D01*
X1108817Y1209285D01*
G02X1108728Y1209451I111J166D01*
G01Y1210233D01*
G02X1108817Y1210399I200J0D01*
G01X1109136Y1210612D01*
X1109234Y1210622D01*
X1109282Y1210602D01*
G03X1109743Y1210510I461J1109D01*
G03Y1212914I0J1202D01*
G03X1109282Y1212822I0J-1201D01*
G01X1109234Y1212802D01*
X1109136Y1212812D01*
X1108817Y1213025D01*
G02X1108728Y1213191I111J166D01*
G01Y1213973D01*
G02X1108817Y1214139I200J0D01*
G01X1109136Y1214352D01*
X1109234Y1214362D01*
X1109282Y1214342D01*
G03X1109743Y1214250I461J1109D01*
G03X1110945Y1215452I0J1202D01*
G03X1110924Y1215674I-1202J-2D01*
G01X1110915Y1215723D01*
X1110944Y1215816D01*
X1111249Y1216121D01*
X1111342Y1216150D01*
X1111391Y1216141D01*
G03X1111613Y1216120I224J1181D01*
G03X1112815Y1217322I0J1202D01*
G03X1112806Y1217466I-1202J-3D01*
G01X1112801Y1217513D01*
X1112832Y1217601D01*
X1113133Y1217888D01*
X1113222Y1217916D01*
X1113269Y1217908D01*
G03X1113484Y1217890I216J1284D01*
G03X1113698Y1217908I-2J1302D01*
G01X1113745Y1217916D01*
X1113834Y1217888D01*
X1114135Y1217601D01*
X1114166Y1217513D01*
X1114161Y1217465D01*
G03X1114152Y1217322I1193J-147D01*
G03X1115354Y1216120I1202J0D01*
G03X1115576Y1216141I-2J1202D01*
G01X1115625Y1216150D01*
X1115718Y1216121D01*
X1116023Y1215816D01*
X1116052Y1215723D01*
X1116043Y1215674D01*
G03X1116022Y1215452I1181J-224D01*
G03X1117224Y1216654I1202J0D01*
G03X1117002Y1216633I2J-1202D01*
G01X1116953Y1216624D01*
X1116860Y1216653D01*
X1116555Y1216958D01*
X1116526Y1217051D01*
X1116535Y1217100D01*
G03X1116556Y1217322I-1181J224D01*
G03X1116547Y1217465I-1202J-4D01*
G01X1116542Y1217513D01*
X1116573Y1217601D01*
X1116874Y1217888D01*
X1116963Y1217916D01*
X1117010Y1217908D01*
G03X1117224Y1217890I216J1284D01*
G03X1118526Y1219192I0J1302D01*
G03X1118525Y1219248I-1302J5D01*
G02X1118620Y1219426I200J8D01*
G01X1118964Y1219638D01*
X1119071Y1219641D01*
X1119119Y1219614D01*
G03X1119537Y1219414I1845J3318D01*
G02X1119662Y1219229I-75J-185D01*
G01Y1219192D01*
G03X1122266I1302J0D01*
G01Y1219223D01*
X1122264Y1219285D01*
X1122332Y1219390D01*
X1122391Y1219414D01*
G03X1122809Y1219614I-1427J3518D01*
G01X1122857Y1219641D01*
X1122964Y1219638D01*
X1123308Y1219426D01*
G02X1123403Y1219248I-105J-170D01*
G03X1123402Y1219192I1301J-51D01*
G03X1126006I1302J0D01*
G03X1126005Y1219248I-1302J5D01*
G02X1126100Y1219426I200J8D01*
G01X1126444Y1219638D01*
X1126551Y1219641D01*
X1126599Y1219614D01*
G03X1127017Y1219414I1845J3318D01*
G02X1127142Y1219229I-75J-185D01*
G01Y1219192D01*
G03X1129746I1302J0D01*
G01Y1219223D01*
X1129744Y1219285D01*
X1129812Y1219390D01*
X1129871Y1219414D01*
G03X1130289Y1219614I-1427J3518D01*
G01X1130337Y1219641D01*
X1130444Y1219638D01*
X1130788Y1219426D01*
G02X1130883Y1219248I-105J-170D01*
G03X1130882Y1219192I1301J-51D01*
G03X1132184Y1217890I1302J0D01*
G03X1132398Y1217908I-2J1302D01*
G01X1132445Y1217916D01*
X1132534Y1217888D01*
X1132835Y1217601D01*
X1132866Y1217513D01*
X1132861Y1217465D01*
G03X1132852Y1217322I1193J-147D01*
G03X1132873Y1217100I1202J2D01*
G01X1132882Y1217051D01*
X1132853Y1216958D01*
X1132548Y1216653D01*
X1132455Y1216624D01*
X1132406Y1216633D01*
G03X1132184Y1216654I-224J-1181D01*
G03X1133386Y1215452I0J-1202D01*
G03X1133365Y1215674I-1202J-2D01*
G01X1133356Y1215723D01*
X1133385Y1215816D01*
X1133690Y1216121D01*
X1133783Y1216150D01*
X1133832Y1216141D01*
G03X1134054Y1216120I224J1181D01*
G03X1134277Y1216141I-1J1202D01*
G01X1134325Y1216150D01*
X1134420Y1216121D01*
X1134724Y1215817D01*
X1134753Y1215723D01*
X1134744Y1215674D01*
G03X1134723Y1215452I1181J-224D01*
G03X1135925Y1216654I1202J0D01*
G03X1135702Y1216633I1J-1202D01*
G01X1135654Y1216624D01*
X1135559Y1216653D01*
X1135255Y1216957D01*
X1135226Y1217051D01*
X1135235Y1217100D01*
G03X1135256Y1217322I-1181J224D01*
G03X1135247Y1217465I-1202J-4D01*
G01X1135242Y1217513D01*
X1135273Y1217601D01*
X1135574Y1217888D01*
X1135663Y1217916D01*
X1135710Y1217908D01*
G03X1135924Y1217890I216J1284D01*
G03X1137226Y1219192I0J1302D01*
G01Y1219223D01*
X1137224Y1219286D01*
X1137293Y1219391D01*
X1137392Y1219431D01*
G03X1137418Y1219442I-1466J3502D01*
G01X1137474Y1219465D01*
G03X1137606Y1219528I-1569J3458D01*
G03X1137728Y1219591I-1681J3404D01*
G01X1137750Y1219603D01*
X1137797Y1219615D01*
X1137908D01*
X1137919D01*
G02X1137973Y1219604I-13J-200D01*
G02X1138013Y1219585I-65J-189D01*
G01X1138250Y1219440D01*
X1138261Y1219433D01*
X1138327Y1219380D01*
X1138366Y1219294D01*
X1138364Y1219247D01*
G03X1138363Y1219192I1301J-51D01*
G03X1140967I1302J0D01*
G03X1140949Y1219406I-1302J-2D01*
G01X1140941Y1219453D01*
X1140969Y1219542D01*
X1141256Y1219843D01*
X1141344Y1219874D01*
X1141392Y1219869D01*
G03X1141535Y1219860I147J1193D01*
G03Y1222264I0J1202D01*
G03X1141130Y1222194I-1J-1202D01*
G02X1140877Y1222455I-67J188D01*
G03X1140916Y1222570I-1212J475D01*
G02X1140943Y1222628I192J-54D01*
G03X1141382Y1223471I-3148J2175D01*
G02X1141565Y1223601I187J-70D01*
G03X1142737Y1224803I-30J1202D01*
G03X1141769Y1225982I-1202J0D01*
G02X1141609Y1226162I39J196D01*
G03X1141540Y1226632I-3813J-320D01*
G02Y1226714I196J41D01*
G03X1141609Y1227184I-3744J790D01*
G02X1141769Y1227364I199J-16D01*
G03X1142737Y1228513I-234J1179D01*
G02X1142867Y1228696I200J-4D01*
G03X1143711Y1229135I-1330J3588D01*
G02X1143769Y1229163I115J-164D01*
G03X1143793Y1229170I-353J1253D01*
G02X1144044Y1228921I60J-191D01*
G03X1143988Y1228543I1231J-376D01*
G03X1145275Y1229830I1287J0D01*
G03X1144897Y1229774I-2J-1287D01*
G02X1144648Y1230025I-58J191D01*
G03X1144655Y1230049I-1246J377D01*
G02X1144683Y1230107I192J-57D01*
G03X1145122Y1230951I-3149J2174D01*
G02X1145305Y1231081I187J-70D01*
G03X1146477Y1232283I-30J1202D01*
G03X1145509Y1233462I-1202J0D01*
G02X1145349Y1233642I39J196D01*
G03X1145280Y1234112I-3813J-320D01*
G02Y1234194I196J41D01*
G03X1145349Y1234664I-3744J790D01*
G02X1145509Y1234844I199J-16D01*
G03X1146477Y1236023I-234J1179D01*
G03X1145305Y1237225I-1202J0D01*
G02X1145122Y1237355I4J200D01*
G03X1144805Y1238010I-3587J-1332D01*
G01X1144769Y1238069D01*
X1144785Y1238205D01*
X1145113Y1238533D01*
X1145190Y1238563D01*
X1145232Y1238562D01*
G03X1145275Y1238561I49J1201D01*
G03X1146477Y1239763I0J1202D01*
G03X1146476Y1239806I-1202J-6D01*
G01X1146475Y1239848D01*
X1146505Y1239925D01*
X1146559Y1239979D01*
G03X1146618Y1240121I-141J142D01*
G01Y1255205D01*
G02X1146677Y1255347I200J0D01*
G01X1147294Y1255964D01*
G02X1147406Y1256021I142J-141D01*
G01X1147542Y1256041D01*
G02X1147740Y1255951I30J-198D01*
G01X1147969Y1255594D01*
Y1255477D01*
X1147936Y1255427D01*
G03X1147728Y1254724I1079J-702D01*
G03X1149015Y1253436I1288J0D01*
G03X1149142Y1253443I-7J1288D01*
G01X1149185Y1253447D01*
X1149265Y1253421D01*
X1149516Y1253193D01*
G02X1149582Y1253045I-134J-148D01*
G01Y1252854D01*
G03X1149590Y1252707I1303J-3D01*
G01X1149595Y1252661D01*
X1149566Y1252576D01*
X1149281Y1252290D01*
X1149196Y1252259D01*
X1149151Y1252264D01*
G03X1149015Y1252272I-144J-1280D01*
G03X1150302Y1250984I0J-1287D01*
G03X1150295Y1251120I-1287J2D01*
G01X1150290Y1251165D01*
X1150321Y1251250D01*
X1150607Y1251535D01*
X1150692Y1251564D01*
X1150738Y1251559D01*
G03X1150885Y1251551I144J1295D01*
G03X1151099Y1251569I-2J1303D01*
G01X1151146Y1251577D01*
X1151235Y1251549D01*
X1151536Y1251262D01*
X1151567Y1251174D01*
X1151561Y1251127D01*
G03X1151553Y1250984I1194J-139D01*
G03X1152755Y1252186I1202J0D01*
G03X1152612Y1252178I-4J-1202D01*
G01X1152565Y1252172D01*
X1152477Y1252203D01*
X1152190Y1252504D01*
X1152162Y1252593D01*
X1152170Y1252640D01*
G03X1152188Y1252854I-1285J216D01*
G01Y1253131D01*
G02X1152254Y1253279I200J0D01*
G01X1152507Y1253507D01*
X1152587Y1253533D01*
X1152630Y1253529D01*
G03X1152755Y1253522I130J1195D01*
G03Y1255926I0J1202D01*
G03X1152630Y1255919I5J-1202D01*
G01X1152587Y1255915D01*
X1152507Y1255941D01*
X1152254Y1256169D01*
G02X1152188Y1256317I134J148D01*
G01Y1256560D01*
G02X1152359Y1256758I200J0D01*
G01X1156128Y1257320D01*
X1156169Y1257308D01*
G03X1156495Y1257263I326J1158D01*
G03X1157144Y1257453I0J1202D01*
G01X1157180Y1257476D01*
X1157979Y1257595D01*
G03X1158170Y1257628I-573J3885D01*
G01X1162345Y1258462D01*
G02X1162491Y1258435I39J-196D01*
G01X1162757Y1258268D01*
X1162802Y1258206D01*
X1162811Y1258169D01*
G03X1163976Y1257263I1165J296D01*
G03X1165178Y1258465I0J1202D01*
G03X1165165Y1258639I-1202J-2D01*
G01X1165160Y1258677D01*
X1165178Y1258751D01*
X1165359Y1259008D01*
G02X1165483Y1259089I164J-115D01*
G01X1242606Y1274486D01*
G03X1243416Y1274742I-771J3850D01*
G01X1264787Y1284131D01*
G02X1264829Y1284144I80J-184D01*
G01X1273708Y1285922D01*
G03X1273808Y1285943I-750J3818D01*
G01X1273915Y1285969D01*
G03X1274125Y1286029I-964J3771D01*
G01X1274209Y1286057D01*
G03X1274407Y1286131I-1263J3681D01*
G01X1274409Y1286132D01*
X1277395Y1287297D01*
X1309310Y1299744D01*
G02X1309383Y1299758I73J-186D01*
G37*
G36*
G01X1125330Y389153D02*
G03I-577J0D01*
G37*
G36*
G01X1130130D02*
G03I-577J0D01*
G37*
G36*
G01X1292034Y495435D02*
X1311789D01*
G02X1311929Y495378I0J-200D01*
G01X1311930Y495377D01*
X1313153Y494154D01*
G02X1313155Y494152I-140J-142D01*
G02X1313212Y494012I-143J-140D01*
G01Y480925D01*
Y480915D01*
G02X1313098Y480745I-200J11D01*
G02X1313090Y480741I-93J177D01*
G01X1312695Y480574D01*
X1312577Y480596D01*
X1312534Y480638D01*
G03X1311488Y481062I-1046J-1078D01*
G03Y478058I0J-1502D01*
G03X1312534Y478482I0J1502D01*
G01X1312577Y478524D01*
X1312695Y478546D01*
X1313090Y478379D01*
G02X1313098Y478375I-85J-181D01*
G02X1313212Y478205I-86J-181D01*
G01Y476094D01*
G02X1313153Y475952I-200J0D01*
G01X1312066Y474865D01*
G02X1311925Y474806I-142J141D01*
G01X1309341D01*
X1309240Y474875D01*
X1309217Y474933D01*
G03X1307819Y475884I-1398J-552D01*
G03X1306317Y474382I0J-1502D01*
G03X1307373Y472948I1502J0D01*
G01X1307396Y472940D01*
X1307438Y472915D01*
X1307777Y472576D01*
G03X1308227Y472283I923J925D01*
G02X1308239Y472277I-83J-182D01*
G03X1308776Y472158I536J1149D01*
G01X1309597D01*
G02X1309745Y472092I0J-200D01*
G01X1309972Y471841D01*
X1309999Y471761D01*
X1309994Y471718D01*
G03X1309986Y471560I1494J-155D01*
G03X1311488Y470058I1502J0D01*
G03X1311688Y470071I3J1502D01*
G03X1312534Y470482I-200J1489D01*
G01X1312577Y470524D01*
X1312695Y470546D01*
X1313090Y470379D01*
G02X1313098Y470375I-85J-181D01*
G02X1313212Y470205I-86J-181D01*
G01Y455717D01*
G02X1313153Y455575I-200J0D01*
G01X1311415Y453837D01*
X1311387Y453808D01*
X1311313Y453778D01*
X1311017D01*
G02X1310868Y453844I-1J200D01*
G03X1310864Y453849I-1175J-936D01*
G01X1310863D01*
G03X1310794Y453921I-1118J-1003D01*
G01X1310766Y453948D01*
X1310719Y454055D01*
G02X1310702Y454136I183J81D01*
G01Y454346D01*
G02X1310719Y454427I200J0D01*
G01X1310767Y454534D01*
X1310795Y454562D01*
G03X1311252Y455641I-1045J1079D01*
G01Y455679D01*
G03X1308248I-1502J-38D01*
G01Y455652D01*
Y455641D01*
G03X1308705Y454562I1502J0D01*
G01X1308733Y454534D01*
X1308781Y454427D01*
G02X1308798Y454346I-183J-81D01*
G01Y454136D01*
G02X1308781Y454055I-200J0D01*
G01X1308734Y453948D01*
X1308706Y453921D01*
G03X1308637Y453849I1049J-1075D01*
G01X1308636D01*
G03X1308632Y453844I1171J-941D01*
G02X1308483Y453778I-148J134D01*
G01X1301024D01*
G02X1300875Y453844I-1J200D01*
G03X1300871Y453849I-1175J-936D01*
G01X1300870D01*
G03X1300801Y453921I-1118J-1003D01*
G01X1300773Y453948D01*
X1300726Y454055D01*
G02X1300709Y454136I183J81D01*
G01Y454346D01*
G02X1300726Y454427I200J0D01*
G01X1300774Y454534D01*
X1300802Y454562D01*
G03X1301259Y455641I-1045J1079D01*
G01Y455679D01*
G03X1298255I-1502J-38D01*
G01Y455652D01*
Y455641D01*
G03X1298712Y454562I1502J0D01*
G01X1298740Y454534D01*
X1298788Y454427D01*
G02X1298805Y454346I-183J-81D01*
G01Y454136D01*
G02X1298788Y454055I-200J0D01*
G01X1298741Y453948D01*
X1298713Y453921D01*
G03X1298644Y453849I1049J-1075D01*
G01X1298643D01*
G03X1298639Y453844I1171J-941D01*
G02X1298490Y453778I-148J134D01*
G01X1292169D01*
G02X1292023Y453842I1J200D01*
G01X1291824Y454055D01*
G02X1291781Y454126I146J137D01*
G01X1291768Y454165D01*
X1291770Y454206D01*
G03X1291774Y454309I-1498J110D01*
G03X1288770I-1502J0D01*
G03X1288775Y454189I1502J2D01*
G01X1288776Y454164D01*
X1288763Y454126D01*
G02X1288720Y454055I-189J66D01*
G01X1288520Y453841D01*
G02X1288374Y453778I-146J137D01*
G01X1282944D01*
G02X1282869Y453792I-1J200D01*
G01X1282769Y453833D01*
X1282743Y453856D01*
G03X1282488Y454041I-1005J-1117D01*
G02X1282388Y454214I100J173D01*
G01Y454560D01*
G02X1282488Y454733I200J0D01*
G03X1283239Y456034I-751J1301D01*
G03X1280235I-1502J0D01*
G03X1280986Y454733I1502J0D01*
G02X1281086Y454560I-100J-173D01*
G01Y454214D01*
G02X1280986Y454041I-200J0D01*
G03X1280731Y453856I750J-1302D01*
G01X1280705Y453833D01*
X1280605Y453792D01*
G02X1280530Y453778I-74J186D01*
G01X1274628D01*
G03X1274486Y453719I0J-200D01*
G01X1272150Y451383D01*
G02X1272116Y451356I-141J142D01*
G03X1271662Y450902I811J-1265D01*
G01X1271651Y450884D01*
X1270473Y449706D01*
G03X1270414Y449564I141J-142D01*
G01Y448696D01*
X1270313Y448583D01*
X1270236Y448574D01*
G03X1269869Y448487I160J-1493D01*
G01X1269821Y448469D01*
X1269719Y448484D01*
X1269367Y448754D01*
X1269326Y448849D01*
X1269331Y448900D01*
G03X1269338Y449042I-1495J145D01*
G01Y449047D01*
G03X1267836Y450547I-1502J-2D01*
G03Y447543I0J-1502D01*
G03X1268364Y447639I0J1502D01*
G01X1268412Y447657D01*
X1268514Y447642D01*
X1268866Y447372D01*
X1268907Y447277D01*
X1268902Y447226D01*
G03X1268895Y447084I1495J-145D01*
G01Y447079D01*
G03X1270236Y445588I1502J2D01*
G01X1270313Y445579D01*
X1270414Y445466D01*
Y427197D01*
X1270404Y427166D01*
G03X1270326Y426689I1424J-478D01*
G03X1270404Y426212I1502J1D01*
G01X1270414Y426181D01*
Y424597D01*
X1270404Y424566D01*
G03X1270326Y424089I1424J-478D01*
G03X1270404Y423612I1502J1D01*
G01X1270414Y423581D01*
Y422509D01*
G02X1270355Y422367I-200J0D01*
G01X1270215Y422227D01*
G02X1270052Y422170I-141J142D01*
G01X1269696Y422209D01*
X1269620Y422257D01*
X1269595Y422295D01*
G03X1268328Y422991I-1267J-805D01*
G03X1266826Y421489I0J-1502D01*
G03X1267232Y420462I1502J0D01*
G01X1267259Y420434D01*
X1267286Y420364D01*
Y420014D01*
X1267259Y419945D01*
X1267232Y419916D01*
G03X1266826Y418917I1096J-1027D01*
G01X1266825Y418878D01*
X1266796Y418808D01*
X1247367Y399379D01*
G02X1247225Y399320I-142J141D01*
G01X1246210D01*
G03X1245314Y398949I0J-1267D01*
G01X1223739Y377373D01*
G02X1223597Y377314I-142J141D01*
G01X1215064D01*
G02X1214916Y377380I0J200D01*
G01X1214689Y377631D01*
X1214662Y377711D01*
X1214667Y377754D01*
G03X1214675Y377912I-1494J155D01*
G03X1211671I-1502J0D01*
G03X1211712Y377561I1502J-2D01*
G01X1211718Y377538D01*
Y377514D01*
G02X1211518Y377314I-200J0D01*
G01X1211459D01*
G02X1211318Y377372I0J200D01*
G01X1206464Y382226D01*
G02X1206420Y382441I142J141D01*
G01X1206578Y382839D01*
X1206675Y382907D01*
X1206736Y382909D01*
G03X1208195Y384410I-43J1501D01*
G03X1206693Y385912I-1502J0D01*
G03X1205192Y384453I0J-1502D01*
G01X1205190Y384392D01*
X1205122Y384295D01*
X1204724Y384137D01*
G02X1204509Y384181I-74J186D01*
G01X1196229Y392461D01*
G03X1196087Y392520I-142J-141D01*
G01X1193778D01*
G02X1193637Y392579I1J200D01*
G01X1193235Y392980D01*
X1193209Y393025D01*
X1193202Y393052D01*
G03X1191748Y394178I-1454J-376D01*
G03X1190247Y392715I0J-1501D01*
G01X1190244Y392633D01*
X1190128Y392520D01*
X1144141D01*
G02X1143999Y392579I0J200D01*
G01X1143972Y392606D01*
X1143942Y392679D01*
Y392720D01*
G03X1140938I-1502J-2D01*
G01Y392719D01*
G02X1140879Y392577I-200J0D01*
G01X1140852Y392550D01*
X1140779Y392520D01*
X1136655D01*
G02X1136513Y392579I0J200D01*
G01X1131269Y397823D01*
X1131240Y397851D01*
X1131210Y397925D01*
Y442136D01*
G02X1131267Y442276I200J0D01*
G01X1131268Y442277D01*
X1140844Y451853D01*
G02X1140846Y451855I142J-140D01*
G02X1140986Y451912I140J-143D01*
G01X1174841D01*
G02X1174997Y451837I0J-200D01*
G01X1175192Y451594D01*
G02X1175231Y451426I-156J-125D01*
G03X1175197Y451118I1468J-318D01*
G01Y451098D01*
G03X1178201I1502J10D01*
G01Y451109D01*
G03X1178167Y451426I-1502J-1D01*
G02X1178206Y451594I195J43D01*
G01X1178401Y451837D01*
G02X1178558Y451912I156J-125D01*
G01X1178686D01*
G02X1178834Y451846I0J-200D01*
G01X1179062Y451594D01*
X1179088Y451514D01*
X1179084Y451471D01*
G03X1179076Y451319I1494J-155D01*
G03X1182080I1502J0D01*
G03X1182072Y451471I-1502J-3D01*
G01X1182068Y451514D01*
X1182094Y451594D01*
X1182322Y451846D01*
G02X1182470Y451912I148J-134D01*
G01X1184333D01*
G03X1184475Y451971I0J200D01*
G01X1193431Y460927D01*
G03X1193490Y461069I-141J142D01*
G01Y491219D01*
G02X1193547Y491359I200J0D01*
G01X1193548Y491360D01*
X1196515Y494327D01*
G02X1196743Y494366I142J-141D01*
G01X1197142Y494175D01*
X1197203Y494065D01*
X1197196Y494001D01*
G03X1197187Y493839I1493J-164D01*
G03X1198689Y492337I1502J0D01*
G03X1200191Y493808I0J1502D01*
G01Y493833D01*
Y493839D01*
G03X1199857Y494784I-1502J1D01*
G01X1199821Y494829D01*
X1199807Y494943D01*
X1199987Y495321D01*
G02X1199988Y495324I189J-61D01*
G02X1200150Y495434I179J-89D01*
G02X1200168Y495435I20J-199D01*
G01X1205010D01*
G02X1205028Y495434I-2J-200D01*
G02X1205190Y495324I-17J-199D01*
G02X1205191Y495321I-188J-64D01*
G01X1205371Y494943D01*
X1205357Y494829D01*
X1205321Y494784D01*
G03X1204987Y493839I1168J-944D01*
G01Y493808D01*
G03X1207991I1502J31D01*
G01Y493833D01*
Y493839D01*
G03X1207657Y494784I-1502J1D01*
G01X1207621Y494829D01*
X1207607Y494943D01*
X1207787Y495321D01*
G02X1207788Y495324I189J-61D01*
G02X1207950Y495434I179J-89D01*
G02X1207968Y495435I20J-199D01*
G01X1266574D01*
G02X1266761Y495307I0J-200D01*
G01X1266894Y494958D01*
G02X1266841Y494737I-186J-72D01*
G03X1266341Y493618I1002J-1119D01*
G03X1266711Y492631I1501J0D01*
G01X1266735Y492603D01*
X1266760Y492537D01*
Y492199D01*
X1266735Y492133D01*
X1266711Y492105D01*
G03Y490131I1131J-987D01*
G01X1266735Y490103D01*
X1266760Y490037D01*
Y489699D01*
X1266735Y489633D01*
X1266711Y489605D01*
G03X1266341Y488618I1131J-987D01*
G03X1269345I1502J0D01*
G03X1268975Y489605I-1501J0D01*
G01X1268951Y489633D01*
X1268926Y489699D01*
Y490037D01*
X1268951Y490103D01*
X1268975Y490131D01*
G03X1269049Y490223I-1132J987D01*
G03X1269262Y490625I-1205J896D01*
G01X1269279Y490673D01*
X1269354Y490741D01*
X1269779Y490844D01*
X1269878Y490817D01*
X1269915Y490782D01*
G03X1270951Y490368I1036J1089D01*
G03X1271938Y490738I0J1501D01*
G01X1271966Y490762D01*
X1272032Y490787D01*
X1272370D01*
X1272436Y490762D01*
X1272464Y490738D01*
G03X1273451Y490368I987J1131D01*
G03X1274953Y491870I0J1502D01*
G03X1274950Y491968I-1502J3D01*
G01X1274947Y492020D01*
X1274990Y492112D01*
X1275349Y492372D01*
X1275450Y492384D01*
X1275499Y492365D01*
G03X1276060Y492256I562J1394D01*
G03X1277562Y493758I0J1502D01*
G03X1277192Y494745I-1501J0D01*
G01X1277168Y494773D01*
X1277143Y494839D01*
Y495177D01*
X1277168Y495243D01*
X1277192Y495271D01*
G03X1277260Y495355I-1133J986D01*
G02X1277420Y495435I160J-120D01*
G01X1288726D01*
G02X1288920Y495282I0J-200D01*
G03X1289335Y494556I1460J353D01*
G01X1289364Y494529D01*
X1289411Y494422D01*
G02X1289428Y494341I-183J-81D01*
G01Y494131D01*
G02X1289411Y494050I-200J0D01*
G01X1289363Y493943D01*
X1289335Y493915D01*
G03X1288878Y492836I1045J-1079D01*
G01Y492798D01*
G03X1291882I1502J38D01*
G01Y492825D01*
Y492836D01*
G03X1291425Y493915I-1502J0D01*
G01X1291397Y493943D01*
X1291349Y494050D01*
G02X1291332Y494131I183J81D01*
G01Y494341D01*
G02X1291349Y494422I200J0D01*
G01X1291396Y494529D01*
X1291425Y494556D01*
G03X1291840Y495282I-1045J1079D01*
G02X1292034Y495435I194J-47D01*
G37*
G36*
G01X1125330Y396240D02*
G03I-577J0D01*
G37*
G36*
G01Y403326D02*
G03I-577J0D01*
G37*
G36*
G01X1130130Y396240D02*
G03I-577J0D01*
G37*
G36*
G01Y403326D02*
G03I-577J0D01*
G37*
G36*
G01Y410413D02*
G03I-577J0D01*
G37*
G36*
G01X1125330Y424586D02*
G03I-577J0D01*
G37*
G36*
G01Y417499D02*
G03I-577J0D01*
G37*
G36*
G01X1130130Y424586D02*
G03I-577J0D01*
G37*
G36*
G01Y417499D02*
G03I-577J0D01*
G37*
G36*
G01X1125330Y410413D02*
G03I-577J0D01*
G37*
G36*
G01Y438760D02*
G03I-577J0D01*
G37*
G36*
G01Y431673D02*
G03I-577J0D01*
G37*
G36*
G01X1130130D02*
G03I-577J0D01*
G37*
G36*
G01Y438760D02*
G03I-577J0D01*
G37*
G36*
G01X1125330Y467539D02*
G03I-577J0D01*
G37*
G36*
G01X1130130D02*
G03I-577J0D01*
G37*
G36*
G01X1125330Y488799D02*
G03I-577J0D01*
G37*
G36*
G01X1130130D02*
G03I-577J0D01*
G37*
G36*
G01X1125330Y474626D02*
G03I-577J0D01*
G37*
G36*
G01X1130130D02*
G03I-577J0D01*
G37*
G36*
G01X1125330Y481712D02*
G03I-577J0D01*
G37*
G36*
G01X1130130D02*
G03I-577J0D01*
G37*
G36*
G01X1125330Y518760D02*
G03I-577J0D01*
G37*
G36*
G01Y511673D02*
G03I-577J0D01*
G37*
G36*
G01X1130130Y518760D02*
G03I-577J0D01*
G37*
G36*
G01Y511673D02*
G03I-577J0D01*
G37*
G36*
G01X1125330Y532933D02*
G03I-577J0D01*
G37*
G36*
G01Y525846D02*
G03I-577J0D01*
G37*
G36*
G01X1130130D02*
G03I-577J0D01*
G37*
G36*
G01Y532933D02*
G03I-577J0D01*
G37*
G36*
G01X1169055Y472579D02*
G03I-577J0D01*
G37*
G36*
G01Y479666D02*
G03I-577J0D01*
G37*
G36*
G01Y486752D02*
G03I-577J0D01*
G37*
G36*
G01Y493839D02*
G03I-577J0D01*
G37*
G36*
G01Y516713D02*
G03I-577J0D01*
G37*
G36*
G01Y523800D02*
G03I-577J0D01*
G37*
G36*
G01Y537973D02*
G03I-577J0D01*
G37*
G36*
G01Y530886D02*
G03I-577J0D01*
G37*
G36*
G01X1161851Y550462D02*
G03I-577J0D01*
G37*
G36*
G01X1169055Y566753D02*
G03I-577J0D01*
G37*
G36*
G01Y580926D02*
G03I-577J0D01*
G37*
G36*
G01Y588013D02*
G03I-577J0D01*
G37*
G36*
G01Y573840D02*
G03I-577J0D01*
G37*
G36*
G01Y602186D02*
G03I-577J0D01*
G37*
G36*
G01Y595099D02*
G03I-577J0D01*
G37*
G36*
G01Y609272D02*
G03I-577J0D01*
G37*
G36*
G01Y616359D02*
G03I-577J0D01*
G37*
G36*
G01X1177435Y306534D02*
G03I-577J0D01*
G37*
G36*
G01X1173855Y472579D02*
G03I-577J0D01*
G37*
G36*
G01X1176355D02*
G03I-577J0D01*
G37*
G36*
G01Y465492D02*
G03I-577J0D01*
G37*
G36*
G01X1173855Y479666D02*
G03I-577J0D01*
G37*
G36*
G01X1176355Y479665D02*
G03I-577J0D01*
G37*
G36*
G01Y486752D02*
G03I-577J0D01*
G37*
G36*
G01X1173855D02*
G03I-577J0D01*
G37*
G36*
G01Y493839D02*
G03I-577J0D01*
G37*
G36*
G01Y516713D02*
G03I-577J0D01*
G37*
G36*
G01X1176355D02*
G03I-577J0D01*
G37*
G36*
G01X1173855Y523800D02*
G03I-577J0D01*
G37*
G36*
G01X1176355D02*
G03I-577J0D01*
G37*
G36*
G01X1173855Y537973D02*
G03I-577J0D01*
G37*
G36*
G01Y530886D02*
G03I-577J0D01*
G37*
G36*
G01X1176355D02*
G03I-577J0D01*
G37*
G36*
G01X1173855Y566753D02*
G03I-577J0D01*
G37*
G36*
G01X1176355D02*
G03I-577J0D01*
G37*
G36*
G01Y559666D02*
G03I-577J0D01*
G37*
G36*
G01X1173855Y588013D02*
G03I-577J0D01*
G37*
G36*
G01Y573840D02*
G03I-577J0D01*
G37*
G36*
G01X1176355Y580926D02*
G03I-577J0D01*
G37*
G36*
G01Y588012D02*
G03I-577J0D01*
G37*
G36*
G01Y573839D02*
G03I-577J0D01*
G37*
G36*
G01X1173855Y580926D02*
G03I-577J0D01*
G37*
G36*
G01Y602186D02*
G03I-577J0D01*
G37*
G36*
G01Y595099D02*
G03I-577J0D01*
G37*
G36*
G01X1176355Y602185D02*
G03I-577J0D01*
G37*
G36*
G01Y595099D02*
G03I-577J0D01*
G37*
G36*
G01X1173855Y616359D02*
G03I-577J0D01*
G37*
G36*
G01Y609272D02*
G03I-577J0D01*
G37*
G36*
G01X1176355D02*
G03I-577J0D01*
G37*
G36*
G01X1256555Y54588D02*
X1285191D01*
X1285226D01*
X1285275Y54539D01*
Y52675D01*
X1285191Y52591D01*
X1256555D01*
G03X1250618Y46654I0J-5937D01*
G01Y7874D01*
G02X1244744Y2000I-5874J0D01*
G01X1197500D01*
G02X1191626Y7874I0J5874D01*
G01Y46654D01*
G03X1190170Y50549I-5938J0D01*
G01Y50728D01*
X1190174Y50732D01*
X1192419D01*
X1192602Y50549D01*
G02X1193624Y46654I-6911J-3895D01*
G01Y7874D01*
G03X1197500Y3998I3876J0D01*
G01X1244744D01*
G03X1248620Y7874I0J3876D01*
G01Y46654D01*
G02X1256555Y54588I7935J-1D01*
G37*
G36*
G01X1200881Y258164D02*
X1217678D01*
G02X1217874Y258003I0J-200D01*
G01X1217888Y257932D01*
X1217821Y257806D01*
X1211871Y255342D01*
G02X1211794Y255326I-78J184D01*
G01X1201422D01*
G02X1201259Y255411I1J200D01*
G01X1201131Y255592D01*
X1201106Y255627D01*
G02X1201073Y255775I164J114D01*
G01X1201076Y255792D01*
X1201081Y255807D01*
Y255808D01*
X1201086Y255823D01*
G03X1201163Y256226I-1423J481D01*
G01Y256227D01*
G03X1201165Y256285I-1500J81D01*
G01Y256306D01*
G03X1200625Y257456I-1502J-3D01*
G01X1200577Y257497D01*
X1200544Y257619D01*
X1200693Y258032D01*
G02X1200881Y258164I188J-68D01*
G37*
G36*
G01X1193077Y322400D02*
G03I-577J0D01*
G37*
G36*
G01X1199636Y790610D02*
G03I-639J0D01*
G37*
G36*
G01X1190640Y844377D02*
G03I-577J0D01*
G37*
G36*
G01X1233247Y515617D02*
G03I-577J0D01*
G37*
G36*
G01X1238239D02*
G03I-577J0D01*
G37*
G36*
G01X1233247Y510661D02*
G03I-577J0D01*
G37*
G36*
G01X1238239D02*
G03I-577J0D01*
G37*
G36*
G01Y524835D02*
G03I-577J0D01*
G37*
G36*
G01Y529791D02*
G03I-577J0D01*
G37*
G36*
G01X1233247Y524835D02*
G03I-577J0D01*
G37*
G36*
G01Y529791D02*
G03I-577J0D01*
G37*
G36*
G01Y565657D02*
G03I-577J0D01*
G37*
G36*
G01Y560701D02*
G03I-577J0D01*
G37*
G36*
G01X1238239Y565657D02*
G03I-577J0D01*
G37*
G36*
G01Y560701D02*
G03I-577J0D01*
G37*
G36*
G01X1233247Y579830D02*
G03I-577J0D01*
G37*
G36*
G01X1238239Y574874D02*
G03I-577J0D01*
G37*
G36*
G01X1233247D02*
G03I-577J0D01*
G37*
G36*
G01X1238239Y579830D02*
G03I-577J0D01*
G37*
G36*
G01Y589047D02*
G03I-577J0D01*
G37*
G36*
G01X1233247D02*
G03I-577J0D01*
G37*
G36*
G01X1238239Y603221D02*
G03I-577J0D01*
G37*
G36*
G01X1233247D02*
G03I-577J0D01*
G37*
G36*
G01Y594003D02*
G03I-577J0D01*
G37*
G36*
G01X1238239D02*
G03I-577J0D01*
G37*
G36*
G01Y608177D02*
G03I-577J0D01*
G37*
G36*
G01X1233247D02*
G03I-577J0D01*
G37*
G36*
G01X1248641Y517774D02*
G03I-577J0D01*
G37*
G36*
G01Y522730D02*
G03I-577J0D01*
G37*
G36*
G01X1243649Y517774D02*
G03I-577J0D01*
G37*
G36*
G01Y522730D02*
G03I-577J0D01*
G37*
G36*
G01X1248641Y536903D02*
G03I-577J0D01*
G37*
G36*
G01X1243649D02*
G03I-577J0D01*
G37*
G36*
G01Y531947D02*
G03I-577J0D01*
G37*
G36*
G01X1248641D02*
G03I-577J0D01*
G37*
G36*
G01Y567813D02*
G03I-577J0D01*
G37*
G36*
G01X1243649D02*
G03I-577J0D01*
G37*
G36*
G01X1248641Y572769D02*
G03I-577J0D01*
G37*
G36*
G01X1243649D02*
G03I-577J0D01*
G37*
G36*
G01X1248641Y581987D02*
G03I-577J0D01*
G37*
G36*
G01Y586943D02*
G03I-577J0D01*
G37*
G36*
G01X1243649D02*
G03I-577J0D01*
G37*
G36*
G01Y581987D02*
G03I-577J0D01*
G37*
G36*
G01Y601116D02*
G03I-577J0D01*
G37*
G36*
G01X1248641D02*
G03I-577J0D01*
G37*
G36*
G01X1243649Y596160D02*
G03I-577J0D01*
G37*
G36*
G01X1248641D02*
G03I-577J0D01*
G37*
G36*
G01X1243649Y610333D02*
G03I-577J0D01*
G37*
G36*
G01Y615289D02*
G03I-577J0D01*
G37*
G36*
G01X1248641D02*
G03I-577J0D01*
G37*
G36*
G01Y610333D02*
G03I-577J0D01*
G37*
G36*
G01X1260077Y330000D02*
G03I-577J0D01*
G37*
G36*
G01X1274994Y861964D02*
G03I-577J0D01*
G37*
G36*
G01X1406555Y54588D02*
X1435515D01*
X1435890Y54213D01*
Y52966D01*
X1435515Y52591D01*
X1406555D01*
G03X1400618Y46654I0J-5937D01*
G01Y7874D01*
G02X1394744Y2000I-5874J0D01*
G01X1299862D01*
G02X1293988Y7874I0J5874D01*
G01Y46654D01*
G03X1292425Y50669I-5938J0D01*
G01Y50696D01*
X1292470Y50741D01*
X1294823D01*
X1294895Y50669D01*
G02X1295986Y46654I-6842J-4015D01*
G01Y7874D01*
G03X1299862Y3998I3876J0D01*
G01X1394744D01*
G03X1398620Y7874I0J3876D01*
G01Y46654D01*
G02X1406555Y54588I7935J-1D01*
G37*
G36*
G01X1293308Y331820D02*
G03I-577J0D01*
G37*
G36*
G01X1307328Y798223D02*
X1300589D01*
G02X1300435Y798295I0J200D01*
G01X1300210Y798567D01*
X1300188Y798652D01*
X1300196Y798697D01*
G03X1300222Y798975I-1476J278D01*
G03X1298720Y800477I-1502J0D01*
G03X1297407Y799705I0J-1503D01*
G01X1297382Y799659D01*
X1297294Y799605D01*
X1296850Y799584D01*
X1296758Y799629D01*
X1296728Y799673D01*
G03X1295491Y800323I-1237J-852D01*
G03X1294714Y800106I1J-1502D01*
G01X1294667Y800078D01*
X1294560Y800076D01*
X1294209Y800274D01*
G02X1294107Y800449I98J174D01*
G01Y810317D01*
G02X1294166Y810459I200J0D01*
G01X1295172Y811465D01*
G02X1295314Y811524I142J-141D01*
G01X1301043D01*
G02X1301172Y811477I0J-200D01*
G03X1302140Y811123I968J1148D01*
G03X1303108Y811477I0J1502D01*
G02X1303237Y811524I129J-153D01*
G01X1304023Y810738D01*
X1304884Y809877D01*
X1308865D01*
X1309377Y809365D01*
Y800272D01*
G02X1309318Y800130I-200J0D01*
G01X1307469Y798281D01*
G02X1307328Y798223I-141J142D01*
G37*
G36*
G01X1317470Y925603D02*
G03I-577J0D01*
G37*
G36*
G01X1305241Y1023462D02*
G03I-577J0D01*
G37*
G36*
G01X1447831Y1099666D02*
G03Y1073642I2760J-13012D01*
G02X1447990Y1073446I-41J-196D01*
G01Y1007538D01*
G02X1447976Y1007463I-200J-1D01*
G01X1447961Y1007427D01*
X1427536Y987001D01*
X1427508Y986972D01*
X1425348Y984812D01*
G02X1425337Y984802I-140J143D01*
G01X1425332Y984798D01*
G02X1425259Y984761I-125J156D01*
G02X1425207Y984754I-52J193D01*
G01X1416003D01*
G02X1415991Y984755I11J200D01*
G01X1415987D01*
G02X1415623Y985224I30J399D01*
G03X1415646Y985486I-1481J262D01*
G03X1412640I-1503J0D01*
G03X1412663Y985224I1504J0D01*
G02X1412299Y984755I-394J-70D01*
G01X1412295D01*
G02X1412283Y984754I-23J199D01*
G01X1400308D01*
G02X1400169Y984810I0J200D01*
G01X1399583Y985376D01*
G02X1399523Y985541I139J144D01*
G01X1399562Y985901D01*
X1399610Y985979D01*
X1399650Y986003D01*
G03X1400356Y987277I-796J1274D01*
G01Y987278D01*
G03X1400328Y987566I-1502J-1D01*
G01X1400318Y987617D01*
X1400350Y987716D01*
X1400644Y987982D01*
G02X1400835Y988026I135J-148D01*
G03X1401265Y987963I430J1439D01*
G03X1399763Y989465I0J1502D01*
G01Y989464D01*
G03X1399791Y989176I1502J1D01*
G01X1399801Y989125D01*
X1399769Y989026D01*
X1399475Y988760D01*
G02X1399284Y988716I-135J148D01*
G03X1398854Y988779I-430J-1439D01*
G03X1397553Y988028I0J-1502D01*
G01X1397530Y987988D01*
X1397453Y987937D01*
X1397096Y987887D01*
G02X1396929Y987941I-28J198D01*
G01X1394653Y990140D01*
G03X1393747Y990506I-907J-940D01*
G01X1385510D01*
G02X1385310Y990706I0J200D01*
G01Y997637D01*
G03X1385251Y997779I-200J0D01*
G01X1381592Y1001438D01*
G02X1381548Y1001505I142J141D01*
G01X1381534Y1001539D01*
Y1003140D01*
G03X1381519Y1003216I-200J0D01*
G01X1381490Y1003285D01*
G02X1381477Y1003339I186J73D01*
G02X1381476Y1003359I199J20D01*
G01Y1006034D01*
G03X1381036Y1007096I-1502J0D01*
G01X1376845Y1011287D01*
G03X1375785Y1011726I-1061J-1062D01*
G01X1375427D01*
G02X1375407Y1011727I0J200D01*
G02X1375295Y1011775I19J199D01*
G02X1375278Y1011792I133J150D01*
G01X1375080Y1012009D01*
G02X1375068Y1012024I150J133D01*
G02X1375046Y1012061I160J120D01*
G02X1375039Y1012081I185J76D01*
G01X1375024Y1012125D01*
X1375028Y1012170D01*
Y1012171D01*
G03X1375036Y1012318I-1494J155D01*
G01Y1012330D01*
G03X1373534Y1013827I-1502J-5D01*
G03X1372032Y1012325I0J-1502D01*
G03X1372040Y1012168I1502J-2D01*
G01Y1012165D01*
G02X1371998Y1012022I-199J-19D01*
G01X1371783Y1011785D01*
G02X1371764Y1011768I-143J140D01*
G02X1371642Y1011726I-123J158D01*
G01X1357758D01*
G02X1357647Y1011760I1J200D01*
G01X1357629Y1011772D01*
X1346286Y1023116D01*
G03X1345224Y1023556I-1062J-1062D01*
G01X1343968D01*
G02X1343838Y1023604I0J200D01*
G03X1342991Y1023916I-847J-994D01*
G01X1318802D01*
G02X1318660Y1023975I0J200D01*
G01X1313807Y1028829D01*
G02X1313805Y1028857I198J28D01*
G01Y1035228D01*
G02X1313812Y1035281I200J1D01*
G02X1313822Y1035309I193J-53D01*
G01X1313871Y1035419D01*
X1313900Y1035446D01*
G03X1314376Y1036543I-1026J1097D01*
G01Y1036556D01*
X1314374Y1036601D01*
Y1036602D01*
G03X1314371Y1036649I-1500J-72D01*
G01X1314368Y1036691D01*
X1314382Y1036730D01*
G02X1314424Y1036799I188J-67D01*
G01X1314624Y1037014D01*
G02X1314748Y1037077I147J-136D01*
G02X1314771Y1037078I20J-199D01*
G01X1315325D01*
X1315343Y1037075D01*
G03X1315753Y1037038I411J2269D01*
G01X1315756D01*
G03X1317954Y1038644I0J2307D01*
G01Y1038645D01*
G02X1318003Y1038725I190J-62D01*
G01X1318559Y1039281D01*
G02X1318774Y1039326I142J-141D01*
G03X1319008Y1039255I552J1397D01*
G02X1319150Y1039138I-42J-196D01*
G01X1319298Y1038794D01*
X1319291Y1038698D01*
X1319265Y1038656D01*
G03X1319047Y1037877I1284J-779D01*
G01Y1037876D01*
G03X1322051I1502J0D01*
G03X1320867Y1039344I-1502J0D01*
G02X1320725Y1039461I42J196D01*
G01X1320596Y1039761D01*
G02X1320609Y1039943I184J78D01*
G03X1320828Y1040723I-1283J781D01*
G03X1320030Y1042050I-1502J0D01*
G01X1319981Y1042076D01*
X1319924Y1042170D01*
Y1044257D01*
G03X1319249Y1045887I-2306J0D01*
G01X1318281Y1046855D01*
G03X1316651Y1047530I-1630J-1631D01*
G01X1312162D01*
G03X1310532Y1046855I0J-2306D01*
G01X1310236Y1046559D01*
G02X1310094Y1046500I-142J141D01*
G01X1308341D01*
G02X1308199Y1046559I0J200D01*
G01X1306317Y1048441D01*
G02X1306258Y1048583I141J142D01*
G01Y1126922D01*
G02X1306354Y1127093I200J0D01*
G01X1306390Y1127115D01*
G03X1318560Y1141024I-1863J13909D01*
G03X1313738Y1151612I-14034J1D01*
G01X1313736D01*
X1313735Y1151614D01*
G02X1313685Y1151681I132J150D01*
G01X1313668Y1151719D01*
Y1154023D01*
G02X1313670Y1154049I200J-2D01*
G02X1313724Y1154162I198J-25D01*
G01X1314572Y1155009D01*
X1315448Y1155885D01*
G02X1315450Y1155887I142J-140D01*
G02X1315557Y1155941I139J-143D01*
G02X1315590Y1155944I35J-197D01*
G01X1444775D01*
G02X1444866Y1155922I0J-200D01*
G02X1444916Y1155886I-90J-178D01*
G01X1447933Y1152869D01*
G02X1447987Y1152762I-143J-139D01*
G02X1447990Y1152729I-197J-35D01*
G01Y1099862D01*
G02X1447831Y1099666I-200J0D01*
G37*
G36*
G01X1310514Y1037038D02*
G03I-577J0D01*
G37*
G36*
G01X1347713Y780040D02*
G03I-577J0D01*
G37*
G36*
G01X1383761Y587652D02*
G03I-577J0D01*
G37*
G36*
G01X1641633Y1154308D02*
G03X1641750Y1154313I3J1302D01*
G01X1641792Y1154317D01*
X1641871Y1154290D01*
X1642119Y1154062D01*
G02X1642184Y1153915I-135J-148D01*
G01Y1153566D01*
G02X1642120Y1153419I-200J0D01*
G01X1641903Y1153218D01*
G02X1641748Y1153166I-136J147D01*
G03X1641635Y1153171I-114J-1297D01*
G01X1641633D01*
G03Y1150567I0J-1302D01*
G03X1641750Y1150572I3J1302D01*
G01X1641792Y1150576D01*
X1641871Y1150549D01*
X1642119Y1150321D01*
G02X1642184Y1150174I-135J-148D01*
G01Y1149826D01*
G02X1642120Y1149679I-200J0D01*
G01X1641903Y1149478D01*
G02X1641748Y1149426I-136J147D01*
G03X1641635Y1149431I-114J-1297D01*
G01X1641633D01*
G03Y1146827I0J-1302D01*
G03X1641750Y1146832I3J1302D01*
G01X1641792Y1146836D01*
X1641871Y1146809D01*
X1642119Y1146581D01*
G02X1642184Y1146434I-135J-148D01*
G01Y1146086D01*
G02X1642120Y1145939I-200J0D01*
G01X1641903Y1145738D01*
G02X1641748Y1145686I-136J147D01*
G03X1641635Y1145691I-114J-1297D01*
G01X1641633D01*
G03Y1143087I0J-1302D01*
G03X1641750Y1143092I3J1302D01*
G01X1641792Y1143096D01*
X1641871Y1143069D01*
X1642119Y1142841D01*
G02X1642184Y1142694I-135J-148D01*
G01Y1142346D01*
G02X1642120Y1142199I-200J0D01*
G01X1641903Y1141998D01*
G02X1641748Y1141946I-136J147D01*
G03X1641635Y1141951I-114J-1297D01*
G01X1641633D01*
G03X1640331Y1140649I0J-1302D01*
G03X1641632Y1139347I1302J0D01*
G01X1641634D01*
G03X1641674Y1139348I-13J1302D01*
G01X1641680D01*
G02X1641792Y1139316I3J-200D01*
G01X1641896Y1139248D01*
G02X1641931Y1139220I-107J-169D01*
G01X1641948Y1139202D01*
X1641959Y1139183D01*
G03X1641972Y1139164I171J103D01*
G01X1642061Y1139051D01*
G02X1642104Y1138927I-157J-124D01*
G01Y1138639D01*
G02X1642041Y1138493I-200J0D01*
G01X1641797Y1138265D01*
G02X1641705Y1138216I-137J146D01*
G01X1641682Y1138211D01*
X1641633D01*
G03X1640331Y1136909I0J-1302D01*
G03X1641628Y1135607I1302J0D01*
G01X1641674D01*
X1641840Y1135524D01*
G03X1641864Y1135496I163J116D01*
G01X1642009Y1135356D01*
G02X1642011Y1135354I-140J-142D01*
G01X1642045Y1135320D01*
G02X1642104Y1135178I-141J-142D01*
G01Y1134899D01*
G02X1642041Y1134753I-200J0D01*
G01X1641961Y1134678D01*
X1641960Y1134677D01*
G03X1641939Y1134655I134J-149D01*
G01X1641891Y1134592D01*
X1641889Y1134590D01*
G03X1641863Y1134555I1016J-782D01*
G02X1641692Y1134470I-164J115D01*
G03X1641633Y1134471I-52J-1301D01*
G03X1640331Y1133169I0J-1302D01*
G03X1640962Y1132052I1304J0D01*
G01X1641004Y1132027D01*
X1641054Y1131947D01*
X1641060Y1131882D01*
G02X1641003Y1131723I-199J-18D01*
G01X1640911Y1131630D01*
G02X1640769Y1131571I-142J141D01*
G01X1640682D01*
X1640619Y1131582D01*
X1640605Y1131586D01*
G03X1640207Y1131650I-400J-1218D01*
G01X1639136D01*
G02X1638988Y1131716I0J200D01*
G01X1638839Y1131881D01*
X1638826Y1131913D01*
X1638763Y1132063D01*
Y1132155D01*
X1638792Y1132227D01*
X1638821Y1132256D01*
G03X1639195Y1133169I-927J913D01*
G03X1636591I-1302J0D01*
G03X1636968Y1132253I1301J0D01*
G01X1637011Y1132210D01*
X1637034Y1132092D01*
X1636945Y1131879D01*
G02X1636878Y1131793I-185J75D01*
G03X1636847Y1131766I115J-164D01*
G01X1636846Y1131765D01*
X1636799Y1131714D01*
G02X1636652Y1131650I-147J136D01*
G01X1635395D01*
G02X1635249Y1131713I0J200D01*
G01X1635104Y1131868D01*
X1635090Y1131902D01*
X1635012Y1132091D01*
X1635033Y1132207D01*
X1635073Y1132250D01*
X1635159Y1132342D01*
G03X1635455Y1133168I-1006J826D01*
G01Y1133169D01*
G03X1632851I-1302J0D01*
G03X1633228Y1132253I1301J0D01*
G01X1633271Y1132210D01*
X1633294Y1132092D01*
X1633205Y1131879D01*
G02X1633138Y1131793I-185J75D01*
G03X1633107Y1131766I115J-164D01*
G01X1633106Y1131765D01*
X1633059Y1131714D01*
G02X1632912Y1131650I-147J136D01*
G01X1631655D01*
G02X1631509Y1131713I0J200D01*
G01X1631364Y1131868D01*
X1631350Y1131902D01*
X1631272Y1132091D01*
X1631293Y1132207D01*
X1631333Y1132250D01*
X1631419Y1132342D01*
G03X1631715Y1133168I-1006J826D01*
G01Y1133169D01*
G03X1629111I-1302J0D01*
G03X1629488Y1132253I1301J0D01*
G01X1629531Y1132210D01*
X1629554Y1132092D01*
X1629465Y1131879D01*
G02X1629398Y1131793I-185J75D01*
G03X1629367Y1131766I115J-164D01*
G01X1629366Y1131765D01*
X1629319Y1131714D01*
G02X1629172Y1131650I-147J136D01*
G01X1627915D01*
G02X1627769Y1131713I0J200D01*
G01X1627624Y1131868D01*
X1627610Y1131902D01*
X1627532Y1132091D01*
X1627553Y1132207D01*
X1627593Y1132250D01*
X1627679Y1132342D01*
G03X1627975Y1133168I-1006J826D01*
G01Y1133169D01*
G03X1625371I-1302J0D01*
G03X1625748Y1132253I1301J0D01*
G01X1625791Y1132210D01*
X1625814Y1132092D01*
X1625725Y1131879D01*
G02X1625658Y1131793I-185J75D01*
G03X1625627Y1131766I115J-164D01*
G01X1625626Y1131765D01*
X1625579Y1131714D01*
G02X1625432Y1131650I-147J136D01*
G01X1624176D01*
G02X1624028Y1131716I0J200D01*
G01X1623879Y1131881D01*
X1623866Y1131913D01*
X1623803Y1132063D01*
Y1132155D01*
X1623832Y1132227D01*
X1623861Y1132256D01*
G03X1624235Y1133169I-927J913D01*
G03X1621631I-1302J0D01*
G03X1622008Y1132253I1301J0D01*
G01X1622051Y1132210D01*
X1622074Y1132092D01*
X1621985Y1131879D01*
G02X1621918Y1131793I-185J75D01*
G03X1621887Y1131766I115J-164D01*
G01X1621886Y1131765D01*
X1621839Y1131714D01*
G02X1621692Y1131650I-147J136D01*
G01X1620435D01*
G02X1620289Y1131713I0J200D01*
G01X1620144Y1131868D01*
X1620130Y1131902D01*
X1620052Y1132091D01*
X1620073Y1132207D01*
X1620113Y1132250D01*
X1620199Y1132342D01*
G03X1620495Y1133168I-1006J826D01*
G01Y1133169D01*
G03X1617891I-1302J0D01*
G03X1618268Y1132253I1301J0D01*
G01X1618311Y1132210D01*
X1618334Y1132092D01*
X1618245Y1131879D01*
G02X1618178Y1131793I-185J75D01*
G03X1618147Y1131766I115J-164D01*
G01X1618146Y1131765D01*
X1618099Y1131714D01*
G02X1617952Y1131650I-147J136D01*
G01X1616695D01*
G02X1616547Y1131716I0J200D01*
G01X1616398Y1131881D01*
X1616385Y1131913D01*
X1616322Y1132063D01*
Y1132155D01*
X1616351Y1132227D01*
X1616380Y1132256D01*
G03X1616754Y1133169I-927J913D01*
G03X1614150I-1302J0D01*
G03X1614527Y1132253I1301J0D01*
G01X1614570Y1132210D01*
X1614593Y1132092D01*
X1614504Y1131879D01*
G02X1614437Y1131793I-185J75D01*
G03X1614406Y1131766I115J-164D01*
G01X1614405Y1131765D01*
X1614358Y1131714D01*
G02X1614211Y1131650I-147J136D01*
G01X1612955D01*
G02X1612807Y1131716I0J200D01*
G01X1612658Y1131881D01*
X1612645Y1131913D01*
X1612582Y1132063D01*
Y1132155D01*
X1612611Y1132227D01*
X1612640Y1132256D01*
G03X1613014Y1133169I-927J913D01*
G03X1610410I-1302J0D01*
G03X1610787Y1132253I1301J0D01*
G01X1610830Y1132210D01*
X1610853Y1132092D01*
X1610764Y1131879D01*
G02X1610697Y1131793I-185J75D01*
G03X1610666Y1131766I115J-164D01*
G01X1610665Y1131765D01*
X1610618Y1131714D01*
G02X1610471Y1131650I-147J136D01*
G01X1602209D01*
G02X1602167Y1131654I-2J200D01*
G01X1602138Y1131661D01*
G02X1602012Y1131747I41J196D01*
G01X1601827Y1132030D01*
G02X1601810Y1132061I166J111D01*
G02X1601795Y1132120I184J78D01*
G01X1601790Y1132168D01*
X1601807Y1132213D01*
G03X1601892Y1132676I-1217J463D01*
G01Y1132677D01*
G03X1599288I-1302J0D01*
G01Y1132676D01*
G03X1599373Y1132213I1302J0D01*
G01X1599391Y1132167D01*
X1599380Y1132071D01*
X1599333Y1132001D01*
Y1131999D01*
X1599168Y1131742D01*
G02X1599147Y1131715I-168J109D01*
G02X1599006Y1131650I-148J135D01*
G01X1597994D01*
G02X1597848Y1131713I0J200D01*
G01X1597703Y1131868D01*
X1597689Y1131902D01*
X1597611Y1132091D01*
X1597632Y1132207D01*
X1597672Y1132250D01*
X1597758Y1132342D01*
G03X1598054Y1133168I-1006J826D01*
G01Y1133169D01*
G03X1595450I-1302J0D01*
G03X1595827Y1132253I1301J0D01*
G01X1595870Y1132210D01*
X1595893Y1132092D01*
X1595804Y1131879D01*
G02X1595737Y1131793I-185J75D01*
G03X1595706Y1131766I115J-164D01*
G01X1595705Y1131765D01*
X1595658Y1131714D01*
G02X1595511Y1131650I-147J136D01*
G01X1594254D01*
G02X1594106Y1131716I0J200D01*
G01X1593957Y1131881D01*
X1593944Y1131913D01*
X1593881Y1132063D01*
Y1132155D01*
X1593910Y1132227D01*
X1593939Y1132256D01*
G03X1594313Y1133169I-927J913D01*
G03X1591709I-1302J0D01*
G03X1592086Y1132253I1301J0D01*
G01X1592129Y1132210D01*
X1592152Y1132092D01*
X1592063Y1131879D01*
G02X1591996Y1131793I-185J75D01*
G03X1591965Y1131766I115J-164D01*
G01X1591964Y1131765D01*
X1591917Y1131714D01*
G02X1591770Y1131650I-147J136D01*
G01X1590514D01*
G02X1590366Y1131716I0J200D01*
G01X1590217Y1131881D01*
X1590204Y1131913D01*
X1590141Y1132063D01*
Y1132155D01*
X1590170Y1132227D01*
X1590199Y1132256D01*
G03X1590573Y1133169I-927J913D01*
G03X1587969I-1302J0D01*
G03X1588346Y1132253I1301J0D01*
G01X1588389Y1132210D01*
X1588412Y1132092D01*
X1588323Y1131879D01*
G02X1588256Y1131793I-185J75D01*
G03X1588225Y1131766I115J-164D01*
G01X1588224Y1131765D01*
X1588177Y1131714D01*
G02X1588030Y1131650I-147J136D01*
G01X1586773D01*
G02X1586627Y1131713I0J200D01*
G01X1586482Y1131868D01*
X1586468Y1131902D01*
X1586390Y1132091D01*
X1586411Y1132207D01*
X1586451Y1132250D01*
X1586537Y1132342D01*
G03X1586833Y1133168I-1006J826D01*
G01Y1133169D01*
G03X1584229I-1302J0D01*
G03X1584606Y1132253I1301J0D01*
G01X1584649Y1132210D01*
X1584672Y1132092D01*
X1584583Y1131879D01*
G02X1584516Y1131793I-185J75D01*
G03X1584485Y1131766I115J-164D01*
G01X1584484Y1131765D01*
X1584437Y1131714D01*
G02X1584290Y1131650I-147J136D01*
G01X1583033D01*
G02X1582887Y1131713I0J200D01*
G01X1582742Y1131868D01*
X1582728Y1131902D01*
X1582650Y1132091D01*
X1582671Y1132207D01*
X1582711Y1132250D01*
X1582797Y1132342D01*
G03X1583093Y1133168I-1006J826D01*
G01Y1133169D01*
G03X1580489I-1302J0D01*
G03X1580866Y1132253I1301J0D01*
G01X1580909Y1132210D01*
X1580932Y1132092D01*
X1580843Y1131879D01*
G02X1580776Y1131793I-185J75D01*
G03X1580745Y1131766I115J-164D01*
G01X1580744Y1131765D01*
X1580697Y1131714D01*
G02X1580550Y1131650I-147J136D01*
G01X1579293D01*
G02X1579147Y1131713I0J200D01*
G01X1579002Y1131868D01*
X1578988Y1131902D01*
X1578910Y1132091D01*
X1578931Y1132207D01*
X1578971Y1132250D01*
X1579057Y1132342D01*
G03X1579353Y1133168I-1006J826D01*
G01Y1133169D01*
G03X1576749I-1302J0D01*
G03X1577126Y1132253I1301J0D01*
G01X1577169Y1132210D01*
X1577192Y1132092D01*
X1577103Y1131879D01*
G02X1577036Y1131793I-185J75D01*
G03X1577005Y1131766I115J-164D01*
G01X1577004Y1131765D01*
X1576957Y1131714D01*
G02X1576810Y1131650I-147J136D01*
G01X1575553D01*
G02X1575407Y1131713I0J200D01*
G01X1575262Y1131868D01*
X1575248Y1131902D01*
X1575170Y1132091D01*
X1575191Y1132207D01*
X1575231Y1132250D01*
X1575317Y1132342D01*
G03X1575613Y1133168I-1006J826D01*
G01Y1133169D01*
G03X1573009I-1302J0D01*
G03X1573386Y1132253I1301J0D01*
G01X1573429Y1132210D01*
X1573452Y1132092D01*
X1573363Y1131879D01*
G02X1573296Y1131793I-185J75D01*
G03X1573265Y1131766I115J-164D01*
G01X1573264Y1131765D01*
X1573217Y1131714D01*
G02X1573070Y1131650I-147J136D01*
G01X1571813D01*
G02X1571667Y1131713I0J200D01*
G01X1571522Y1131868D01*
X1571508Y1131902D01*
X1571430Y1132091D01*
X1571451Y1132207D01*
X1571491Y1132250D01*
X1571577Y1132342D01*
G03X1571873Y1133168I-1006J826D01*
G01Y1133169D01*
G03X1569269I-1302J0D01*
G03X1569646Y1132253I1301J0D01*
G01X1569689Y1132210D01*
X1569712Y1132092D01*
X1569623Y1131879D01*
G02X1569556Y1131793I-185J75D01*
G03X1569525Y1131766I115J-164D01*
G01X1569524Y1131765D01*
X1569477Y1131714D01*
G02X1569330Y1131650I-147J136D01*
G01X1568051D01*
G02X1568027Y1131651I-4J200D01*
G01X1567981Y1131657D01*
G02X1567819Y1131779I23J199D01*
G01X1567712Y1132035D01*
G02X1567755Y1132253I185J77D01*
G03X1568132Y1133169I-924J916D01*
G03X1565528I-1302J0D01*
G03X1565905Y1132253I1301J0D01*
G02X1565948Y1132035I-142J-141D01*
G01X1565841Y1131779D01*
X1565820Y1131728D01*
X1565735Y1131663D01*
X1565638Y1131651D01*
G02X1565614Y1131650I-20J199D01*
G01X1565034D01*
G03X1564692Y1131587I59J-1280D01*
G01X1564677Y1131582D01*
X1564627Y1131574D01*
G02X1564594Y1131571I-35J197D01*
G01X1564345D01*
G03X1564322Y1131570I-3J-200D01*
G01X1564256Y1131562D01*
X1564141Y1131630D01*
X1563972Y1132035D01*
G02X1564015Y1132253I185J77D01*
G03X1564392Y1133169I-924J916D01*
G03X1561788I-1302J0D01*
G03X1562165Y1132253I1301J0D01*
G02X1562208Y1132035I-142J-141D01*
G01X1562066Y1131694D01*
G02X1561881Y1131571I-185J77D01*
G01X1560605D01*
G03X1560582Y1131570I-3J-200D01*
G01X1560516Y1131562D01*
X1560401Y1131630D01*
X1560232Y1132035D01*
G02X1560275Y1132253I185J77D01*
G03X1560652Y1133169I-924J916D01*
G03X1558048I-1302J0D01*
G03X1558425Y1132253I1301J0D01*
G02X1558468Y1132035I-142J-141D01*
G01X1558326Y1131694D01*
G02X1558141Y1131571I-185J77D01*
G01X1556865D01*
G03X1556842Y1131570I-3J-200D01*
G01X1556776Y1131562D01*
X1556661Y1131630D01*
X1556492Y1132035D01*
G02X1556535Y1132253I185J77D01*
G03X1556912Y1133169I-924J916D01*
G03X1554308I-1302J0D01*
G03X1554685Y1132253I1301J0D01*
G02X1554728Y1132035I-142J-141D01*
G01X1554586Y1131694D01*
G02X1554401Y1131571I-185J77D01*
G01X1553125D01*
G03X1553102Y1131570I-3J-200D01*
G01X1553036Y1131562D01*
X1552921Y1131630D01*
X1552752Y1132035D01*
G02X1552795Y1132253I185J77D01*
G03X1553172Y1133169I-924J916D01*
G03X1550568I-1302J0D01*
G03X1550945Y1132253I1301J0D01*
G02X1550988Y1132035I-142J-141D01*
G01X1550846Y1131694D01*
G02X1550661Y1131571I-185J77D01*
G01X1549385D01*
G03X1549362Y1131570I-3J-200D01*
G01X1549296Y1131562D01*
X1549181Y1131630D01*
X1549012Y1132035D01*
G02X1549055Y1132253I185J77D01*
G03X1549432Y1133169I-924J916D01*
G03X1546828I-1302J0D01*
G03X1547205Y1132253I1301J0D01*
G02X1547248Y1132035I-142J-141D01*
G01X1547106Y1131694D01*
G02X1546921Y1131571I-185J77D01*
G01X1534424D01*
G03X1534401Y1131570I-3J-200D01*
G01X1534335Y1131562D01*
X1534220Y1131630D01*
X1534051Y1132035D01*
G02X1534094Y1132253I185J77D01*
G03X1534471Y1133169I-924J916D01*
G03X1531867I-1302J0D01*
G03X1532244Y1132253I1301J0D01*
G02X1532287Y1132035I-142J-141D01*
G01X1532145Y1131694D01*
G02X1531960Y1131571I-185J77D01*
G01X1523204D01*
G03X1523181Y1131570I-3J-200D01*
G01X1523115Y1131562D01*
X1523000Y1131630D01*
X1522831Y1132035D01*
G02X1522874Y1132253I185J77D01*
G03X1523251Y1133169I-924J916D01*
G03X1520647I-1302J0D01*
G03X1521024Y1132253I1301J0D01*
G02X1521067Y1132035I-142J-141D01*
G01X1520925Y1131694D01*
G02X1520740Y1131571I-185J77D01*
G01X1519463D01*
G03X1519440Y1131570I-3J-200D01*
G01X1519374Y1131562D01*
X1519259Y1131630D01*
X1519090Y1132035D01*
G02X1519133Y1132253I185J77D01*
G03X1519510Y1133169I-924J916D01*
G03X1516906I-1302J0D01*
G03X1517283Y1132253I1301J0D01*
G02X1517326Y1132035I-142J-141D01*
G01X1517184Y1131694D01*
G02X1516999Y1131571I-185J77D01*
G01X1515723D01*
G03X1515700Y1131570I-3J-200D01*
G01X1515634Y1131562D01*
X1515519Y1131630D01*
X1515350Y1132035D01*
G02X1515393Y1132253I185J77D01*
G03X1515770Y1133169I-924J916D01*
G03X1513166I-1302J0D01*
G03X1513543Y1132253I1301J0D01*
G02X1513586Y1132035I-142J-141D01*
G01X1513444Y1131694D01*
G02X1513259Y1131571I-185J77D01*
G01X1505972D01*
X1505873Y1131597D01*
X1505851Y1131609D01*
G03X1505131Y1131793I-720J-1318D01*
G01X1505130D01*
G03X1504410Y1131609I0J-1501D01*
G01X1504387Y1131597D01*
X1504288Y1131571D01*
X1502482D01*
X1502383Y1131597D01*
X1502361Y1131609D01*
G03X1501641Y1131793I-720J-1318D01*
G01X1501640D01*
G03X1500920Y1131609I0J-1501D01*
G01X1500897Y1131597D01*
X1500798Y1131571D01*
X1496982D01*
X1496883Y1131597D01*
X1496861Y1131609D01*
G03X1496141Y1131793I-720J-1318D01*
G01X1496140D01*
G03X1495420Y1131609I0J-1501D01*
G01X1495397Y1131597D01*
X1495298Y1131571D01*
X1453140D01*
X1453066Y1131601D01*
X1453038Y1131630D01*
X1451044Y1133624D01*
G02X1450985Y1133766I141J142D01*
G01Y1154338D01*
G03X1450926Y1154480I-200J0D01*
G01X1448120Y1157286D01*
G03X1447978Y1157345I-142J-141D01*
G01X1383122D01*
X1383048Y1157375D01*
X1383020Y1157404D01*
X1382071Y1158353D01*
G02X1382012Y1158495I141J142D01*
G01Y1233806D01*
X1382042Y1233880D01*
X1382071Y1233908D01*
X1382030Y1234019D01*
Y1289256D01*
G02X1382089Y1289398I200J0D01*
G01X1394204Y1301513D01*
G02X1394346Y1301572I142J-141D01*
G01X1409360D01*
X1409468Y1301489D01*
X1409485Y1301423D01*
G03X1412389I1452J383D01*
G01X1412406Y1301489D01*
X1412514Y1301572D01*
X1413946D01*
X1413971Y1301566D01*
G03X1414346Y1301518I377J1454D01*
G03X1414721Y1301566I-2J1502D01*
G01X1414746Y1301572D01*
X1416118D01*
X1416227Y1301484D01*
X1416242Y1301414D01*
G03X1419180I1469J315D01*
G01X1419195Y1301484D01*
X1419304Y1301572D01*
X1419641D01*
X1419752Y1301482D01*
X1419766Y1301412D01*
G03X1422710I1472J300D01*
G01X1422724Y1301482D01*
X1422835Y1301572D01*
X1423121D01*
X1423234Y1301474D01*
X1423244Y1301399D01*
G03X1424732Y1300101I1488J204D01*
G03X1426062Y1300906I0J1501D01*
G01X1426087Y1300953D01*
X1426176Y1301010D01*
X1426628Y1301032D01*
X1426722Y1300983D01*
X1426751Y1300939D01*
G03X1428009Y1300258I1258J821D01*
G03X1429205Y1300851I0J1503D01*
G01X1429206Y1300852D01*
G02X1429368Y1300930I158J-122D01*
G01X1429739Y1300923D01*
X1429823Y1300879D01*
X1429851Y1300839D01*
G03X1431080Y1300200I1229J862D01*
G03X1432553Y1301411I0J1501D01*
G01X1432568Y1301482D01*
X1432677Y1301572D01*
X1473539D01*
G02X1473653Y1301536I0J-200D01*
G01X1530069Y1262312D01*
X1530082Y1262299D01*
X1533110Y1259271D01*
G02X1533169Y1259129I-141J-142D01*
G01Y1257907D01*
X1533072Y1257795D01*
X1532998Y1257785D01*
G03X1532947Y1257776I184J-1189D01*
G01X1532899Y1257767D01*
X1532804Y1257796D01*
X1532500Y1258100D01*
X1532471Y1258194D01*
X1532480Y1258243D01*
G03X1532501Y1258465I-1181J224D01*
G03X1531299Y1257263I-1202J0D01*
G03X1531521Y1257284I-2J1202D01*
G01X1531570Y1257293D01*
X1531664Y1257264D01*
X1531968Y1256960D01*
X1531997Y1256865D01*
X1531988Y1256817D01*
G03X1531977Y1256439I1182J-224D01*
G01X1531983Y1256392D01*
X1531952Y1256303D01*
X1531651Y1256013D01*
X1531561Y1255986D01*
X1531514Y1255993D01*
G03X1531299Y1256012I-220J-1269D01*
G03Y1253436I0J-1288D01*
G03X1531514Y1253455I-5J1288D01*
G01X1531561Y1253462D01*
X1531651Y1253435D01*
X1531952Y1253145D01*
X1531983Y1253056D01*
X1531977Y1253009D01*
G03Y1252699I1193J-155D01*
G01X1531983Y1252652D01*
X1531952Y1252563D01*
X1531651Y1252273D01*
X1531561Y1252246D01*
X1531514Y1252253D01*
G03X1531299Y1252272I-220J-1269D01*
G03Y1249696I0J-1288D01*
G03X1531433Y1249704I-10J1287D01*
G01X1531479Y1249708D01*
X1531564Y1249678D01*
X1531848Y1249391D01*
X1531878Y1249306D01*
X1531872Y1249260D01*
G03X1531864Y1249113I1294J-144D01*
G01Y1248836D01*
G02X1531798Y1248688I-200J0D01*
G01X1531545Y1248460D01*
X1531466Y1248434D01*
X1531423Y1248439D01*
G03X1531299Y1248445I-120J-1196D01*
G03Y1246041I0J-1202D01*
G03X1531423Y1246047I4J1202D01*
G01X1531466Y1246052D01*
X1531545Y1246026D01*
X1531798Y1245798D01*
G02X1531864Y1245650I-134J-148D01*
G01Y1245373D01*
G03X1531882Y1245159I1302J2D01*
G01X1531889Y1245112D01*
X1531862Y1245023D01*
X1531575Y1244723D01*
X1531488Y1244691D01*
X1531440Y1244697D01*
G03X1531299Y1244705I-138J-1194D01*
G03Y1242301I0J-1202D01*
G03X1531521Y1242322I-2J1202D01*
G01X1531570Y1242331D01*
X1531663Y1242302D01*
X1531968Y1241997D01*
X1531997Y1241904D01*
X1531988Y1241855D01*
G03X1531967Y1241633I1182J-224D01*
G03X1531988Y1241411I1202J2D01*
G01X1531997Y1241362D01*
X1531968Y1241269D01*
X1531663Y1240964D01*
X1531570Y1240935D01*
X1531521Y1240944D01*
G03X1531299Y1240965I-224J-1181D01*
G03Y1238561I0J-1202D01*
G03X1531442Y1238570I-4J1202D01*
G01X1531490Y1238575D01*
X1531578Y1238544D01*
X1531865Y1238243D01*
X1531893Y1238154D01*
X1531885Y1238107D01*
G03X1531867Y1237893I1284J-216D01*
G03X1531875Y1237746I1302J-3D01*
G01X1531881Y1237700D01*
X1531851Y1237615D01*
X1531566Y1237329D01*
X1531481Y1237298D01*
X1531435Y1237303D01*
G03X1531299Y1237310I-134J-1280D01*
G03Y1234736I0J-1287D01*
G03X1531435Y1234743I2J1287D01*
G01X1531481Y1234748D01*
X1531566Y1234717D01*
X1531851Y1234431D01*
X1531881Y1234346D01*
X1531875Y1234300D01*
G03X1531867Y1234153I1294J-144D01*
G03X1531875Y1234006I1302J-3D01*
G01X1531881Y1233960D01*
X1531851Y1233875D01*
X1531566Y1233589D01*
X1531481Y1233558D01*
X1531435Y1233563D01*
G03X1531299Y1233570I-134J-1280D01*
G03Y1230996I0J-1287D01*
G03X1531435Y1231003I2J1287D01*
G01X1531481Y1231008D01*
X1531566Y1230977D01*
X1531851Y1230691D01*
X1531881Y1230606D01*
X1531875Y1230560D01*
G03X1531867Y1230413I1294J-144D01*
G03X1531885Y1230199I1302J2D01*
G01X1531893Y1230152D01*
X1531865Y1230063D01*
X1531578Y1229762D01*
X1531490Y1229731D01*
X1531442Y1229736D01*
G03X1531299Y1229745I-147J-1193D01*
G03Y1227341I0J-1202D01*
G03X1531441Y1227349I3J1202D01*
G01X1531489Y1227355D01*
X1531576Y1227324D01*
X1531863Y1227023D01*
X1531891Y1226934D01*
X1531883Y1226886D01*
G03X1531865Y1226672I1284J-216D01*
G01Y1226396D01*
G02X1531799Y1226248I-200J0D01*
G01X1531546Y1226020D01*
X1531466Y1225994D01*
X1531424Y1225999D01*
G03X1531299Y1226005I-120J-1196D01*
G03Y1223601I0J-1202D01*
G03X1531424Y1223608I-5J1202D01*
G01X1531467Y1223612D01*
X1531547Y1223586D01*
X1531800Y1223358D01*
G02X1531866Y1223210I-134J-148D01*
G01Y1222932D01*
G03X1531884Y1222718I1302J2D01*
G01X1531892Y1222671D01*
X1531864Y1222582D01*
X1531577Y1222281D01*
X1531489Y1222250D01*
X1531442Y1222256D01*
G03X1531299Y1222264I-139J-1194D01*
G03X1532501Y1221062I0J-1202D01*
G03X1532492Y1221205I-1202J-4D01*
G01X1532487Y1221253D01*
X1532518Y1221341D01*
X1532819Y1221628D01*
X1532908Y1221655D01*
X1532955Y1221648D01*
G03X1533168Y1221630I216J1284D01*
G03X1533498Y1221672I2J1302D01*
G01X1533500D01*
G03X1533551Y1221687I-342J1257D01*
G03X1533646Y1221720I-380J1246D01*
G02X1533907Y1221466I73J-186D01*
G03X1533837Y1221062I1131J-404D01*
G03X1535039Y1219860I1202J0D01*
G03X1535182Y1219869I-4J1202D01*
G01X1535230Y1219874D01*
X1535318Y1219843D01*
X1535605Y1219542D01*
X1535633Y1219453D01*
X1535625Y1219406D01*
G03X1535607Y1219192I1284J-216D01*
G03X1535615Y1219045I1302J-3D01*
G01X1535621Y1218999D01*
X1535591Y1218914D01*
X1535306Y1218628D01*
X1535221Y1218597D01*
X1535175Y1218602D01*
G03X1535039Y1218610I-144J-1280D01*
G03X1536326Y1217322I0J-1287D01*
G03X1536319Y1217458I-1287J2D01*
G01X1536314Y1217504D01*
X1536345Y1217589D01*
X1536631Y1217874D01*
X1536716Y1217904D01*
X1536762Y1217898D01*
G03X1536909Y1217890I144J1294D01*
G03X1537056Y1217898I3J1302D01*
G01X1537102Y1217904D01*
X1537187Y1217874D01*
X1537473Y1217589D01*
X1537504Y1217504D01*
X1537499Y1217458D01*
G03X1537492Y1217322I1280J-134D01*
G03X1540066I1287J0D01*
G03X1540059Y1217458I-1287J2D01*
G01X1540054Y1217504D01*
X1540085Y1217589D01*
X1540371Y1217874D01*
X1540456Y1217904D01*
X1540502Y1217898D01*
G03X1540649Y1217890I144J1294D01*
G03X1540863Y1217908I-2J1302D01*
G01X1540910Y1217916D01*
X1540999Y1217888D01*
X1541300Y1217601D01*
X1541331Y1217513D01*
X1541326Y1217465D01*
G03X1541317Y1217322I1193J-147D01*
G03X1543721I1202J0D01*
G03X1543712Y1217465I-1202J-4D01*
G01X1543707Y1217513D01*
X1543738Y1217601D01*
X1544039Y1217888D01*
X1544128Y1217916D01*
X1544175Y1217908D01*
G03X1544389Y1217890I216J1284D01*
G03X1544603Y1217908I-2J1302D01*
G01X1544650Y1217916D01*
X1544739Y1217888D01*
X1545040Y1217601D01*
X1545071Y1217513D01*
X1545066Y1217465D01*
G03X1545057Y1217322I1193J-147D01*
G03X1547461I1202J0D01*
G03X1547452Y1217466I-1202J-3D01*
G01X1547447Y1217513D01*
X1547478Y1217601D01*
X1547779Y1217888D01*
X1547868Y1217916D01*
X1547915Y1217908D01*
G03X1548130Y1217890I216J1284D01*
G03X1548344Y1217908I-2J1302D01*
G01X1548391Y1217916D01*
X1548480Y1217888D01*
X1548781Y1217601D01*
X1548812Y1217513D01*
X1548807Y1217465D01*
G03X1548798Y1217322I1193J-147D01*
G03X1551202I1202J0D01*
G03X1551193Y1217465I-1202J-4D01*
G01X1551188Y1217513D01*
X1551219Y1217601D01*
X1551520Y1217888D01*
X1551609Y1217916D01*
X1551656Y1217908D01*
G03X1551870Y1217890I216J1284D01*
G03X1552084Y1217908I-2J1302D01*
G01X1552131Y1217916D01*
X1552220Y1217888D01*
X1552521Y1217601D01*
X1552552Y1217513D01*
X1552547Y1217465D01*
G03X1552538Y1217322I1193J-147D01*
G03X1553740Y1216120I1202J0D01*
G03X1553962Y1216141I-2J1202D01*
G01X1554011Y1216150D01*
X1554104Y1216121D01*
X1554409Y1215816D01*
X1554438Y1215723D01*
X1554429Y1215674D01*
G03X1554408Y1215452I1181J-224D01*
G03X1555610Y1216654I1202J0D01*
G03X1555388Y1216633I2J-1202D01*
G01X1555339Y1216624D01*
X1555246Y1216653D01*
X1554941Y1216958D01*
X1554912Y1217051D01*
X1554921Y1217100D01*
G03X1554942Y1217322I-1181J224D01*
G03X1554933Y1217465I-1202J-4D01*
G01X1554928Y1217513D01*
X1554959Y1217601D01*
X1555260Y1217888D01*
X1555349Y1217916D01*
X1555396Y1217908D01*
G03X1555610Y1217890I216J1284D01*
G03X1556912Y1219192I0J1302D01*
G01Y1219223D01*
X1556910Y1219285D01*
X1556978Y1219390D01*
X1557037Y1219414D01*
G03X1557433Y1219602I-1427J3518D01*
G01X1557455Y1219614D01*
X1557510Y1219628D01*
G02X1557665Y1219605I50J-194D01*
G01X1557954Y1219426D01*
X1557999Y1219398D01*
X1558050Y1219305D01*
X1558049Y1219248D01*
Y1219246D01*
G03X1558048Y1219192I1301J-51D01*
G03X1560652I1302J0D01*
G03X1560651Y1219246I-1302J3D01*
G01Y1219248D01*
X1560650Y1219305D01*
X1560701Y1219398D01*
X1560746Y1219426D01*
X1561042Y1219609D01*
G02X1561046Y1219611I91J-178D01*
G02X1561144Y1219639I102J-172D01*
G01X1561199Y1219640D01*
G03X1561663Y1219414I1891J3292D01*
G02X1561788Y1219229I-75J-185D01*
G01Y1219192D01*
G03X1563090Y1217890I1302J0D01*
G03X1563994Y1218255I0J1302D01*
G01X1564023Y1218283D01*
X1564095Y1218312D01*
X1564414Y1218309D01*
G02X1564544Y1218260I-1J-200D01*
G01X1564555Y1218250D01*
X1565885Y1216920D01*
G02X1565897Y1216907I-141J-142D01*
G01X1565901Y1216902D01*
G02X1565947Y1216776I-154J-128D01*
G01X1565950Y1216457D01*
X1565921Y1216385D01*
X1565893Y1216356D01*
G03X1565528Y1215452I937J-904D01*
G03X1566777Y1214151I1302J0D01*
G01X1566778D01*
X1566816Y1214149D01*
X1566849Y1214135D01*
G02X1566911Y1214093I-79J-184D01*
G01X1566996Y1214009D01*
G02X1567056Y1213866I-140J-143D01*
G01Y1213298D01*
G02X1566995Y1213154I-200J0D01*
G01X1566965Y1213125D01*
G03X1566963Y1213123I140J-142D01*
G01X1566884Y1213044D01*
X1566816Y1213015D01*
X1566778Y1213013D01*
G03Y1210411I51J-1301D01*
G01X1566816Y1210410D01*
X1566884Y1210380D01*
X1566996Y1210269D01*
G02X1567056Y1210126I-140J-143D01*
G01Y1209558D01*
G02X1566995Y1209414I-200J0D01*
G01X1566965Y1209385D01*
G03X1566963Y1209383I140J-142D01*
G01X1566884Y1209304D01*
X1566816Y1209275D01*
X1566778Y1209273D01*
G03Y1206671I51J-1301D01*
G01X1566816Y1206670D01*
X1566884Y1206640D01*
X1566996Y1206529D01*
G02X1567056Y1206386I-140J-143D01*
G01Y1205818D01*
G02X1566995Y1205674I-200J0D01*
G01X1566965Y1205645D01*
G03X1566963Y1205643I140J-142D01*
G01X1566884Y1205564D01*
X1566816Y1205535D01*
X1566778Y1205533D01*
G03Y1202931I51J-1301D01*
G01X1566816Y1202930D01*
X1566884Y1202900D01*
X1566996Y1202789D01*
G02X1567056Y1202646I-140J-143D01*
G01Y1202077D01*
G02X1566995Y1201933I-200J0D01*
G01X1566965Y1201904D01*
G03X1566963Y1201902I140J-142D01*
G01X1566884Y1201823D01*
X1566816Y1201794D01*
X1566778Y1201792D01*
G03Y1199190I51J-1301D01*
G01X1566816Y1199189D01*
X1566884Y1199159D01*
X1566996Y1199048D01*
G02X1567056Y1198905I-140J-143D01*
G01Y1198337D01*
G02X1566995Y1198193I-200J0D01*
G01X1566965Y1198164D01*
G03X1566963Y1198162I140J-142D01*
G01X1566884Y1198083D01*
X1566816Y1198054D01*
X1566778Y1198052D01*
G03Y1195450I51J-1301D01*
G01X1566816Y1195449D01*
X1566884Y1195419D01*
X1566996Y1195308D01*
G02X1567056Y1195165I-140J-143D01*
G01Y1194597D01*
G02X1566995Y1194453I-200J0D01*
G01X1566965Y1194424D01*
G03X1566963Y1194422I140J-142D01*
G01X1566884Y1194343D01*
X1566816Y1194314D01*
X1566778Y1194312D01*
G03Y1191710I51J-1301D01*
G01X1566816Y1191709D01*
X1566884Y1191679D01*
X1566996Y1191568D01*
G02X1567056Y1191425I-140J-143D01*
G01Y1190857D01*
G02X1566995Y1190713I-200J0D01*
G01X1566965Y1190684D01*
G03X1566963Y1190682I140J-142D01*
G01X1566884Y1190603D01*
X1566816Y1190574D01*
X1566778Y1190572D01*
G03X1565528Y1189271I52J-1301D01*
G03X1566830Y1187969I1302J0D01*
G03X1567558Y1188192I-1J1302D01*
G02X1567611Y1188217I111J-166D01*
G03X1567732Y1188129I813J991D01*
G01X1567751Y1188117D01*
X1568328Y1187539D01*
G02X1568386Y1187398I-142J-141D01*
G01Y1186759D01*
X1568384Y1186743D01*
Y1186670D01*
G02X1568258Y1186484I-200J0D01*
G01X1567995Y1186379D01*
G02X1567878Y1186370I-73J186D01*
G01X1567876D01*
G02X1567774Y1186428I44J195D01*
G03X1566830Y1186833I-944J-898D01*
G03Y1184229I0J-1302D01*
G01X1566832D01*
G03X1567776Y1184635I-1J1303D01*
G01X1567818Y1184679D01*
X1567938Y1184706D01*
X1568258Y1184578D01*
G02X1568384Y1184403I-74J-186D01*
G01X1568386Y1184367D01*
Y1183229D01*
G03X1568449Y1182834I1282J2D01*
G01X1568453Y1182821D01*
X1568465Y1182754D01*
Y1180778D01*
X1568455Y1180747D01*
G03X1568414Y1180597I1213J-412D01*
G01X1568413Y1180588D01*
X1568411Y1180579D01*
G03X1568386Y1180333I1256J-252D01*
G01Y1179279D01*
X1568384Y1179263D01*
Y1179190D01*
G02X1568258Y1179004I-200J0D01*
G01X1567995Y1178899D01*
G02X1567878Y1178890I-73J186D01*
G01X1567876D01*
G02X1567774Y1178948I44J195D01*
G03X1566830Y1179353I-944J-898D01*
G03Y1176749I0J-1302D01*
G01X1566832D01*
G03X1567776Y1177155I-1J1303D01*
G01X1567818Y1177200D01*
X1567936Y1177226D01*
X1568319Y1177074D01*
X1568345Y1177064D01*
X1568368Y1177050D01*
G02X1568465Y1176879I-103J-171D01*
G01Y1176268D01*
G03X1568524Y1176126I200J0D01*
G01X1569134Y1175516D01*
X1569185D01*
X1569396Y1175163D01*
G02X1569424Y1175060I-172J-102D01*
G01Y1174952D01*
X1569414Y1174908D01*
X1569403Y1174887D01*
G03X1569269Y1174312I1168J-575D01*
G01Y1174310D01*
G03X1571873I1302J0D01*
G01Y1174312D01*
G03X1571718Y1174927I-1302J-1D01*
G01X1571693Y1174974D01*
X1571695Y1175079D01*
X1571898Y1175419D01*
G02X1572070Y1175516I172J-103D01*
G01X1574994D01*
G03X1575136Y1175575I0J200D01*
G01X1575409Y1175848D01*
G02X1575551Y1175907I142J-141D01*
G01X1576762D01*
G03X1576800Y1175911I-2J200D01*
G01X1576802D01*
G02X1577023Y1175791I36J-197D01*
G01X1577190Y1175386D01*
X1577167Y1175269D01*
X1577125Y1175226D01*
G03X1576749Y1174311I926J-915D01*
G01Y1174310D01*
G03X1579353I1302J0D01*
G01Y1174311D01*
G03X1578977Y1175226I-1302J0D01*
G01X1578976Y1175227D01*
G02X1578934Y1175443I143J140D01*
G01X1579076Y1175784D01*
G02X1579082Y1175797I184J-77D01*
G02X1579232Y1175905I179J-90D01*
G02X1579261Y1175907I28J-198D01*
G01X1584242D01*
G03X1584280Y1175911I-2J200D01*
G01X1584282D01*
G02X1584503Y1175791I36J-197D01*
G01X1584670Y1175386D01*
X1584647Y1175269D01*
X1584605Y1175226D01*
G03X1584229Y1174311I926J-915D01*
G01Y1174310D01*
G03X1586833I1302J0D01*
G01Y1174311D01*
G03X1586457Y1175226I-1302J0D01*
G01X1586456Y1175227D01*
G02X1586414Y1175443I143J140D01*
G01X1586556Y1175784D01*
G02X1586562Y1175797I184J-77D01*
G02X1586712Y1175905I179J-90D01*
G02X1586741Y1175907I28J-198D01*
G01X1591722D01*
G03X1591760Y1175911I-2J200D01*
G01X1591762D01*
G02X1591983Y1175791I36J-197D01*
G01X1592150Y1175386D01*
X1592127Y1175269D01*
X1592085Y1175226D01*
G03X1591709Y1174311I926J-915D01*
G01Y1174310D01*
G03X1594313I1302J0D01*
G01Y1174311D01*
G03X1593937Y1175226I-1302J0D01*
G01X1593936Y1175227D01*
G02X1593894Y1175443I143J140D01*
G01X1594036Y1175784D01*
G02X1594042Y1175797I184J-77D01*
G02X1594192Y1175905I179J-90D01*
G02X1594221Y1175907I28J-198D01*
G01X1599203D01*
G03X1599241Y1175911I-2J200D01*
G01X1599243D01*
G02X1599464Y1175791I36J-197D01*
G01X1599631Y1175386D01*
X1599608Y1175269D01*
X1599566Y1175226D01*
G03X1599190Y1174311I926J-915D01*
G01Y1174310D01*
G03X1601794I1302J0D01*
G01Y1174311D01*
G03X1601418Y1175226I-1302J0D01*
G01X1601417Y1175227D01*
G02X1601375Y1175443I143J140D01*
G01X1601517Y1175784D01*
G02X1601523Y1175797I184J-77D01*
G02X1601673Y1175905I179J-90D01*
G02X1601702Y1175907I28J-198D01*
G01X1610423D01*
G03X1610461Y1175911I-2J200D01*
G01X1610463D01*
G02X1610684Y1175791I36J-197D01*
G01X1610851Y1175386D01*
X1610828Y1175269D01*
X1610786Y1175226D01*
G03X1610410Y1174311I926J-915D01*
G01Y1174310D01*
G03X1613014I1302J0D01*
G01Y1174311D01*
G03X1612638Y1175226I-1302J0D01*
G01X1612637Y1175227D01*
G02X1612595Y1175443I143J140D01*
G01X1612737Y1175784D01*
G02X1612743Y1175797I184J-77D01*
G02X1612893Y1175905I179J-90D01*
G02X1612922Y1175907I28J-198D01*
G01X1617904D01*
G03X1617942Y1175911I-2J200D01*
G01X1617944D01*
G02X1618165Y1175791I36J-197D01*
G01X1618332Y1175386D01*
X1618309Y1175269D01*
X1618267Y1175226D01*
G03X1617891Y1174311I926J-915D01*
G01Y1174310D01*
G03X1620495I1302J0D01*
G01Y1174311D01*
G03X1620119Y1175226I-1302J0D01*
G01X1620118Y1175227D01*
G02X1620076Y1175443I143J140D01*
G01X1620218Y1175784D01*
G02X1620224Y1175797I184J-77D01*
G02X1620374Y1175905I179J-90D01*
G02X1620403Y1175907I28J-198D01*
G01X1625384D01*
G03X1625422Y1175911I-2J200D01*
G01X1625424D01*
G02X1625645Y1175791I36J-197D01*
G01X1625812Y1175386D01*
X1625789Y1175269D01*
X1625747Y1175226D01*
G03X1625371Y1174311I926J-915D01*
G01Y1174310D01*
G03X1627975I1302J0D01*
G01Y1174311D01*
G03X1627599Y1175226I-1302J0D01*
G01X1627598Y1175227D01*
G02X1627556Y1175443I143J140D01*
G01X1627698Y1175784D01*
G02X1627704Y1175797I184J-77D01*
G02X1627854Y1175905I179J-90D01*
G02X1627883Y1175907I28J-198D01*
G01X1632864D01*
G03X1632902Y1175911I-2J200D01*
G01X1632904D01*
G02X1633125Y1175791I36J-197D01*
G01X1633292Y1175386D01*
X1633269Y1175269D01*
X1633227Y1175226D01*
G03X1632851Y1174311I926J-915D01*
G01Y1174310D01*
G03X1635455I1302J0D01*
G01Y1174311D01*
G03X1635079Y1175226I-1302J0D01*
G01X1635078Y1175227D01*
G02X1635036Y1175443I143J140D01*
G01X1635178Y1175784D01*
G02X1635184Y1175797I184J-77D01*
G02X1635334Y1175905I179J-90D01*
G02X1635363Y1175907I28J-198D01*
G01X1638664D01*
G02X1638697Y1175904I-2J-200D01*
G02X1638804Y1175850I-32J-197D01*
G01X1639076Y1175578D01*
G02X1639135Y1175436I-141J-142D01*
G01Y1174184D01*
G03X1639194Y1174042I200J0D01*
G01X1640968Y1172268D01*
G02X1641016Y1172190I-142J-141D01*
G01X1641031Y1172146D01*
X1640996Y1171798D01*
G02X1640909Y1171652I-199J20D01*
G01X1640908D01*
G03X1640331Y1170570I726J-1082D01*
G03X1641633Y1169268I1302J0D01*
G03X1641750Y1169273I3J1302D01*
G01X1641792Y1169277D01*
X1641871Y1169250D01*
X1642119Y1169022D01*
G02X1642184Y1168875I-135J-148D01*
G01Y1168527D01*
G02X1642120Y1168380I-200J0D01*
G01X1641903Y1168179D01*
G02X1641748Y1168127I-136J147D01*
G03X1641635Y1168132I-114J-1297D01*
G01X1641633D01*
G03Y1165528I0J-1302D01*
G03X1641750Y1165533I3J1302D01*
G01X1641792Y1165537D01*
X1641871Y1165510D01*
X1642119Y1165282D01*
G02X1642184Y1165135I-135J-148D01*
G01Y1161047D01*
G02X1642120Y1160900I-200J0D01*
G01X1641903Y1160699D01*
G02X1641748Y1160647I-136J147D01*
G03X1641635Y1160652I-114J-1297D01*
G01X1641633D01*
G03Y1158048I0J-1302D01*
G03X1641750Y1158053I3J1302D01*
G01X1641792Y1158057D01*
X1641871Y1158030D01*
X1642119Y1157802D01*
G02X1642184Y1157655I-135J-148D01*
G01Y1157307D01*
G02X1642120Y1157160I-200J0D01*
G01X1641903Y1156959D01*
G02X1641748Y1156907I-136J147D01*
G03X1641635Y1156912I-114J-1297D01*
G01X1641633D01*
G03Y1154308I0J-1302D01*
G37*
G36*
G01X1578974Y1557270D02*
X1578280Y1556576D01*
G03X1578221Y1556434I141J-142D01*
G01Y1551976D01*
G03X1578280Y1551834I200J0D01*
G01X1579682Y1550432D01*
G03X1579824Y1550373I142J141D01*
G01X1630227D01*
G03X1630369Y1550432I0J200D01*
G01X1630757Y1550820D01*
G03X1630816Y1550962I-141J142D01*
G01Y1551223D01*
G02X1630819Y1551256I200J-2D01*
G02X1630873Y1551363I197J-32D01*
G01X1631743Y1552233D01*
G02X1631783Y1552264I142J-141D01*
G02X1631788Y1552267I105J-170D01*
G01X1631810Y1552279D01*
X1631837Y1552286D01*
X1631838D01*
G03X1631990Y1552480I-48J194D01*
G01Y1635207D01*
G02X1632190Y1635407I200J0D01*
G01X1825437D01*
G02X1825469Y1635404I-3J-200D01*
G01X1825471D01*
G02X1825577Y1635350I-34J-197D01*
G01X1834718Y1626209D01*
G02X1834772Y1626102I-143J-139D01*
G02X1834775Y1626069I-197J-35D01*
G01Y1284477D01*
G02X1834761Y1284402I-200J-1D01*
G01X1834746Y1284366D01*
X1822095Y1271715D01*
G02X1822028Y1271671I-141J142D01*
G01X1821994Y1271657D01*
X1768908D01*
G03X1768766Y1271598I0J-200D01*
G01X1758601Y1261433D01*
G03X1758542Y1261291I141J-142D01*
G01Y1234722D01*
G02X1758528Y1234647I-200J-1D01*
G01X1758513Y1234611D01*
X1749089Y1225187D01*
G02X1749022Y1225143I-141J142D01*
G01X1748988Y1225129D01*
X1731159D01*
G02X1731071Y1225149I-1J200D01*
G01X1731031Y1225169D01*
X1731018Y1225186D01*
X1731002Y1225207D01*
X1730951Y1225273D01*
X1730806Y1225461D01*
G02X1730802Y1225467I164J114D01*
G03X1730901Y1226016I-1480J550D01*
G03X1730867Y1226343I-1579J1D01*
G02X1730921Y1226526I195J42D01*
G01X1731087Y1226692D01*
G02X1731246Y1226750I142J-141D01*
G01X1731265Y1226748D01*
X1731272Y1226747D01*
G03X1731533Y1226724I262J1479D01*
G01X1731543D01*
G03X1733035Y1228226I-10J1502D01*
G03X1730031I-1502J0D01*
G03X1730055Y1227959I1502J0D01*
G01X1730064Y1227910D01*
X1730050Y1227864D01*
G02X1730000Y1227782I-191J60D01*
G01X1729768Y1227550D01*
G02X1729751Y1227535I-141J142D01*
G03X1729322Y1227595I-431J-1519D01*
G03X1727743Y1226016I0J-1579D01*
G01Y1226013D01*
G03X1727841Y1225467I1579J2D01*
G02X1727834Y1225458I-161J118D01*
G01X1727776Y1225381D01*
G02X1727774Y1225379I-141J139D01*
G01X1727637Y1225201D01*
G02X1727484Y1225129I-154J128D01*
G01X1698996D01*
G02X1698977Y1225130I1J200D01*
G02X1698824Y1225228I20J199D01*
G02X1698820Y1225235I171J103D01*
G01X1698716Y1225466D01*
G02X1698701Y1225540I185J76D01*
G01Y1225723D01*
G02X1698742Y1225844I200J0D01*
G01X1698765Y1225874D01*
X1698778Y1225891D01*
X1698791Y1225910D01*
G03X1699034Y1226563I-1055J764D01*
G01X1699037Y1226599D01*
G03X1699039Y1226673I-1301J72D01*
G03X1697737Y1227976I-1303J0D01*
G01X1697545D01*
G02X1697396Y1228042I-1J200D01*
G01X1697198Y1228261D01*
G02X1697147Y1228415I148J134D01*
G01Y1228416D01*
G03X1697154Y1228542I-1281J134D01*
G01Y1228544D01*
G03X1694578I-1288J-1D01*
G01Y1228542D01*
G03X1694585Y1228416I1288J8D01*
G01Y1228415D01*
G02X1694534Y1228261I-199J-20D01*
G01X1694336Y1228042D01*
G02X1694187Y1227976I-148J134D01*
G01X1693996D01*
G03X1693849Y1227968I-3J-1303D01*
G01X1693804Y1227963D01*
X1693718Y1227992D01*
X1693432Y1228277D01*
X1693401Y1228362D01*
X1693406Y1228407D01*
G03X1693414Y1228542I-1280J144D01*
G01Y1228544D01*
G03X1692126Y1227256I-1287J-1D01*
G01X1692129D01*
G03X1692503Y1227312I-2J1287D01*
G02X1692756Y1227073I59J-191D01*
G03X1692751Y1227057I1241J-397D01*
G01Y1227055D01*
G03X1692694Y1226673I1245J-381D01*
G03Y1226671I1302J-1D01*
G03X1692701Y1226537I1302J1D01*
G01X1692706Y1226492D01*
X1692676Y1226407D01*
X1692391Y1226123D01*
X1692306Y1226093D01*
X1692262Y1226098D01*
G03X1692128Y1226105I-135J-1295D01*
G01X1692126D01*
G03X1690906Y1225259I0J-1303D01*
G01X1690884Y1225200D01*
X1690782Y1225129D01*
X1689729D01*
X1689627Y1225200D01*
X1689605Y1225259D01*
G03X1688385Y1226105I-1220J-457D01*
G03X1688257Y1226099I-3J-1302D01*
G01X1688215Y1226095D01*
X1688135Y1226121D01*
X1687884Y1226348D01*
G02X1687818Y1226497I134J148D01*
G01Y1226672D01*
G03X1686515Y1227975I-1303J0D01*
G03X1686368Y1227967I-3J-1303D01*
G01X1686323Y1227962D01*
X1686237Y1227991D01*
X1685983Y1228244D01*
G02X1685925Y1228406I141J142D01*
G01Y1228407D01*
G03X1685932Y1228543I-1280J134D01*
G03X1684645Y1227256I-1287J0D01*
G03X1684781Y1227263I2J1287D01*
G01X1684826Y1227268D01*
X1684911Y1227237D01*
X1685196Y1226951D01*
X1685225Y1226865D01*
X1685220Y1226820D01*
G03X1685212Y1226672I1295J-144D01*
G01Y1226482D01*
G02X1685146Y1226333I-200J-1D01*
G01X1684927Y1226135D01*
G02X1684773Y1226084I-134J148D01*
G01X1684772D01*
G03X1684645Y1226090I-124J-1281D01*
G03X1683441Y1225258I0J-1287D01*
G01X1683419Y1225199D01*
X1683317Y1225129D01*
X1682249D01*
X1682147Y1225200D01*
X1682125Y1225259D01*
G03X1680905Y1226105I-1220J-457D01*
G03X1680777Y1226099I-3J-1302D01*
G01X1680735Y1226095D01*
X1680655Y1226121D01*
X1680404Y1226348D01*
G02X1680338Y1226497I134J148D01*
G01Y1226672D01*
G03X1679035Y1227975I-1303J0D01*
G03X1678888Y1227967I-3J-1303D01*
G01X1678843Y1227962D01*
X1678757Y1227991D01*
X1678503Y1228244D01*
G02X1678445Y1228406I141J142D01*
G01Y1228407D01*
G03X1678452Y1228543I-1280J134D01*
G03X1677165Y1227256I-1287J0D01*
G03X1677301Y1227263I2J1287D01*
G01X1677346Y1227268D01*
X1677431Y1227237D01*
X1677716Y1226951D01*
X1677745Y1226865D01*
X1677740Y1226820D01*
G03X1677732Y1226672I1295J-144D01*
G01Y1226482D01*
G02X1677666Y1226333I-200J-1D01*
G01X1677447Y1226135D01*
G02X1677293Y1226084I-134J148D01*
G01X1677292D01*
G03X1677165Y1226090I-124J-1281D01*
G03X1675961Y1225258I0J-1287D01*
G01X1675939Y1225199D01*
X1675837Y1225129D01*
X1674769D01*
X1674667Y1225200D01*
X1674645Y1225259D01*
G03X1673425Y1226105I-1220J-457D01*
G03X1673297Y1226099I-3J-1302D01*
G01X1673255Y1226095D01*
X1673175Y1226121D01*
X1672924Y1226348D01*
G02X1672858Y1226497I134J148D01*
G01Y1226672D01*
G03X1671555Y1227975I-1303J0D01*
G03X1671408Y1227967I-3J-1303D01*
G01X1671363Y1227962D01*
X1671277Y1227991D01*
X1671023Y1228244D01*
G02X1670965Y1228406I141J142D01*
G01Y1228407D01*
G03X1670972Y1228543I-1280J134D01*
G03X1669685Y1227256I-1287J0D01*
G03X1669821Y1227263I2J1287D01*
G01X1669866Y1227268D01*
X1669951Y1227237D01*
X1670236Y1226951D01*
X1670265Y1226865D01*
X1670260Y1226820D01*
G03X1670252Y1226672I1295J-144D01*
G01Y1226482D01*
G02X1670186Y1226333I-200J-1D01*
G01X1669967Y1226135D01*
G02X1669813Y1226084I-134J148D01*
G01X1669812D01*
G03X1669685Y1226090I-124J-1281D01*
G03X1668481Y1225258I0J-1287D01*
G01X1668459Y1225199D01*
X1668357Y1225129D01*
X1667289D01*
X1667187Y1225200D01*
X1667165Y1225259D01*
G03X1665945Y1226105I-1220J-457D01*
G03X1665817Y1226099I-3J-1302D01*
G01X1665775Y1226095D01*
X1665695Y1226121D01*
X1665444Y1226348D01*
G02X1665378Y1226497I134J148D01*
G01Y1226672D01*
G03X1664727Y1227800I-1303J0D01*
G03X1664458Y1227917I-651J-1128D01*
G03X1664075Y1227974I-381J-1245D01*
G03X1663773Y1227939I-2J-1302D01*
G01X1663772D01*
G03X1663720Y1227925I312J-1264D01*
G01X1663719D01*
X1663716Y1227924D01*
G03X1663686Y1227915I359J-1252D01*
G01X1663626Y1227906D01*
G02X1663426Y1228106I0J200D01*
G01X1663433Y1228151D01*
G02X1663439Y1228178I198J-30D01*
G03X1663492Y1228543I-1235J366D01*
G03X1662286Y1229827I-1287J0D01*
G02X1662157Y1229886I13J200D01*
G01X1662072Y1229971D01*
G02X1662014Y1230113I142J141D01*
G01Y1230594D01*
G02X1662037Y1230687I200J0D01*
G01X1662092Y1230779D01*
G02X1662161Y1230848I172J-103D01*
G01X1662202Y1230872D01*
X1662206Y1230873D01*
G03X1662375Y1230975I-1866J3283D01*
G02X1662446Y1231004I110J-167D01*
G03X1663484Y1232041I-241J1280D01*
G02X1663512Y1232111I196J-38D01*
G03X1663639Y1232326I-3187J2027D01*
G03X1663809Y1232674I-3304J1829D01*
G01X1663821Y1232701D01*
X1663838Y1232722D01*
G02X1663882Y1232762I155J-126D01*
G01X1663966Y1232818D01*
G02X1664018Y1232843I112J-166D01*
G01X1664045Y1232851D01*
X1664047D01*
G03X1664222Y1232859I28J1302D01*
G01X1664267Y1232864D01*
X1664353Y1232835D01*
X1664639Y1232550D01*
X1664670Y1232465D01*
X1664665Y1232420D01*
G03X1664658Y1232283I1280J-134D01*
G03X1665945Y1233570I1287J0D01*
G03X1665808Y1233563I-3J-1287D01*
G01X1665807D01*
G02X1665645Y1233621I-20J199D01*
G01X1665392Y1233875D01*
X1665363Y1233961D01*
X1665368Y1234006D01*
G03X1665376Y1234153I-1294J144D01*
G03X1665368Y1234300I-1302J3D01*
G01X1665363Y1234345D01*
X1665392Y1234431D01*
X1665645Y1234685D01*
G02X1665807Y1234743I142J-141D01*
G01X1665808D01*
G03X1665945Y1234736I134J1280D01*
G03Y1237310I0J1287D01*
G03X1665808Y1237303I-3J-1287D01*
G01X1665807D01*
G02X1665645Y1237361I-20J199D01*
G01X1665392Y1237615D01*
X1665363Y1237701D01*
X1665368Y1237746D01*
G03X1665376Y1237893I-1294J144D01*
G03X1664076Y1239195I-1302J0D01*
G01X1664045D01*
X1664018Y1239203D01*
G02X1663965Y1239229I61J191D01*
G01X1663881Y1239285D01*
G02X1663840Y1239322I112J166D01*
G01X1663821Y1239345D01*
X1663809Y1239372D01*
G03X1663601Y1239787I-3474J-1482D01*
G03X1663511Y1239935I-3271J-1888D01*
G02X1663484Y1240005I170J106D01*
G03X1662735Y1240952I-1280J-242D01*
G02X1662616Y1241135I81J183D01*
G01Y1242148D01*
G02X1662733Y1242329I200J-1D01*
G01X1662734Y1242330D01*
G03X1663492Y1243502I-529J1173D01*
G01Y1243504D01*
G03X1663484Y1243638I-1288J-10D01*
G01Y1243640D01*
X1663479Y1243684D01*
X1663510Y1243769D01*
X1663764Y1244021D01*
G02X1663927Y1244078I141J-142D01*
G01X1663928D01*
G03X1664075Y1244070I144J1295D01*
G03X1665378Y1245373I0J1303D01*
G01Y1249113D01*
G03X1665370Y1249261I-1303J4D01*
G01X1665365Y1249306D01*
X1665394Y1249392D01*
X1665679Y1249678D01*
X1665764Y1249709D01*
X1665809Y1249704D01*
G03X1665944Y1249696I144J1280D01*
G01X1665946D01*
G03X1664658Y1250984I-1J1287D01*
G03X1664665Y1250848I1287J-2D01*
G01Y1250847D01*
G02X1664607Y1250685I-199J-20D01*
G01X1664353Y1250432D01*
X1664267Y1250403D01*
X1664222Y1250408D01*
G03X1664075Y1250416I-144J-1295D01*
G03X1663939Y1250409I-1J-1303D01*
G02X1663777Y1250466I-21J199D01*
G01X1663524Y1250718D01*
X1663494Y1250803D01*
X1663499Y1250848D01*
G03X1663506Y1250982I-1295J135D01*
G01Y1250984D01*
G03X1662735Y1252173I-1302J0D01*
G02X1662616Y1252356I81J183D01*
G01Y1253352D01*
G02X1662735Y1253535I200J0D01*
G03Y1255913I-531J1189D01*
G02X1662616Y1256096I81J183D01*
G01Y1258584D01*
G02X1662619Y1258620I200J1D01*
G01X1662626Y1258656D01*
X1662636Y1258692D01*
G03X1662896Y1260090I-3632J1399D01*
G01Y1260166D01*
X1662898Y1260182D01*
G03X1662946Y1260788I-3879J612D01*
G01Y1268908D01*
G03X1662898Y1269514I-3927J-6D01*
G01X1662896Y1269530D01*
Y1272862D01*
G03X1662164Y1275133I-3892J-1D01*
G01X1662081Y1275249D01*
G02X1662048Y1275345I166J111D01*
G02X1662047Y1275361I199J20D01*
G01Y1298112D01*
G03X1661988Y1298254I-200J0D01*
G01X1617668Y1342574D01*
G02X1617624Y1342641I142J141D01*
G01X1617610Y1342675D01*
Y1346846D01*
G02X1617617Y1346899I200J1D01*
G02X1617636Y1346945I193J-53D01*
G01X1617681Y1347025D01*
G02X1617712Y1347067I175J-97D01*
G01X1617726Y1347081D01*
X1617731Y1347084D01*
G03Y1349290I-694J1103D01*
G01X1617726Y1349293D01*
X1617712Y1349307D01*
G02X1617681Y1349349I144J139D01*
G01X1617636Y1349429D01*
G02X1617617Y1349475I174J99D01*
G02X1617610Y1349528I193J52D01*
G01Y1358758D01*
G02X1617617Y1358811I200J1D01*
G02X1617636Y1358857I193J-53D01*
G01X1617681Y1358937D01*
G02X1617712Y1358979I175J-97D01*
G01X1617726Y1358993D01*
X1617731Y1358996D01*
G03Y1361202I-694J1103D01*
G01X1617726Y1361205D01*
X1617712Y1361219D01*
G02X1617681Y1361261I144J139D01*
G01X1617636Y1361341D01*
G02X1617617Y1361387I174J99D01*
G02X1617610Y1361440I193J52D01*
G01Y1365662D01*
G03X1617551Y1365804I-200J0D01*
G01X1613759Y1369596D01*
G02X1613715Y1369663I142J141D01*
G01X1613701Y1369697D01*
Y1370777D01*
G02X1613702Y1370797I200J0D01*
G02X1613731Y1370882I199J-20D01*
G01X1614798D01*
G03X1616300Y1372385I0J1502D01*
G01Y1372424D01*
G03X1616301Y1372479I-1502J55D01*
G03X1614798Y1373982I-1503J0D01*
G01X1613901D01*
G02X1613701Y1374182I0J200D01*
G01Y1382689D01*
G02X1613702Y1382709I200J0D01*
G02X1613731Y1382794I199J-20D01*
G01X1614798D01*
G03X1616300Y1384297I0J1502D01*
G01Y1384336D01*
G03X1616301Y1384391I-1502J55D01*
G03X1614798Y1385894I-1503J0D01*
G01X1613901D01*
G02X1613701Y1386094I0J200D01*
G01Y1398328D01*
G03X1613642Y1398470I-200J0D01*
G01X1559887Y1452225D01*
G02X1559843Y1452292I142J141D01*
G01X1559829Y1452326D01*
Y1615388D01*
G02X1559832Y1615421I200J-2D01*
G02X1559886Y1615528I197J-32D01*
G01X1560558Y1616200D01*
G03X1560617Y1616342I-141J142D01*
G01Y1624711D01*
G03X1560558Y1624853I-200J0D01*
G01X1558384Y1627027D01*
G03X1558242Y1627086I-142J-141D01*
G01X1478187D01*
G03X1478045Y1627027I0J-200D01*
G01X1473579Y1622561D01*
G03X1473520Y1622419I141J-142D01*
G01Y1562366D01*
G02X1473506Y1562291I-200J-1D01*
G01X1473491Y1562255D01*
X1470244Y1559008D01*
G02X1470177Y1558964I-141J142D01*
G01X1470143Y1558950D01*
X1468186D01*
G03X1468044Y1558891I0J-200D01*
G01X1453159Y1544006D01*
G03X1453100Y1543864I141J-142D01*
G01Y1540713D01*
G02X1453021Y1540554I-200J0D01*
G01X1449845Y1538140D01*
G03X1448620Y1536582I2374J-3127D01*
G01X1448397Y1536071D01*
X1448150Y1535503D01*
X1448148Y1535498D01*
G02X1448103Y1535436I-182J84D01*
G01X1446954Y1534499D01*
G03X1445692Y1532621I2459J-3016D01*
G01X1445613Y1532363D01*
G02X1445572Y1532290I-191J59D01*
G01X1445545Y1532259D01*
X1445505Y1532241D01*
G03X1444632Y1530876I631J-1365D01*
G01Y1530875D01*
G03X1444850Y1530095I1503J0D01*
G01X1444852Y1530093D01*
G02X1444879Y1530016I-172J-103D01*
G01X1444884Y1529976D01*
X1444493Y1528699D01*
Y1528698D01*
G02X1444384Y1528575I-191J59D01*
G01X1444074Y1528458D01*
G02X1443984Y1528447I-69J188D01*
G01X1443939Y1528451D01*
X1443899Y1528476D01*
G03X1443103Y1528704I-796J-1276D01*
G03Y1525698I0J-1503D01*
G01X1443104D01*
G03X1443277Y1525708I0J1503D01*
G01X1443278D01*
G03X1443285Y1525709I-209J1489D01*
G01X1443294Y1525710D01*
G02X1443503Y1525458I16J-200D01*
G02X1443501Y1525452I-191J60D01*
G01X1442858Y1523354D01*
G02X1442857Y1523350I-194J46D01*
G01X1442022Y1521431D01*
G03X1441698Y1520012I3600J-1568D01*
G01X1441680Y1519521D01*
G02X1441671Y1519470I-200J9D01*
G01X1440958Y1517138D01*
G02X1440955Y1517129I-191J59D01*
G01X1439017Y1511721D01*
G03X1438789Y1510446I3663J-1313D01*
G01X1438749Y1506374D01*
G02X1438745Y1506336I-200J2D01*
G01X1433403Y1479930D01*
X1428855Y1457447D01*
G02X1428835Y1457392I-196J40D01*
G01X1428822Y1457368D01*
X1413360Y1441906D01*
G02X1413293Y1441862I-141J142D01*
G01X1413259Y1441848D01*
X1388588D01*
G02X1388513Y1441862I-1J200D01*
G01X1388477Y1441877D01*
X1379396Y1450958D01*
G02X1379352Y1451025I142J141D01*
G01X1379338Y1451059D01*
Y1623045D01*
G02X1379341Y1623078I200J-2D01*
G02X1379395Y1623185I197J-32D01*
G01X1396366Y1640156D01*
G02X1396473Y1640210I139J-143D01*
G02X1396506Y1640213I35J-197D01*
G01X1576461D01*
G02X1576661Y1640013I0J-200D01*
G01Y1638594D01*
G03X1576720Y1638452I200J0D01*
G01X1578975Y1636197D01*
G02X1579029Y1636090I-143J-139D01*
G02X1579032Y1636057I-197J-35D01*
G01Y1557411D01*
G02X1578987Y1557285I-200J0D01*
G02X1578974Y1557270I-157J123D01*
G37*
G36*
G01X1398824Y926261D02*
G03I-577J0D01*
G37*
G36*
G01X1508917Y54588D02*
X1537184D01*
X1537398Y54374D01*
Y52805D01*
X1537184Y52591D01*
X1508917D01*
G03X1502980Y46654I0J-5937D01*
G01Y7874D01*
G02X1497106Y2000I-5874J0D01*
G01X1449862D01*
G02X1443988Y7874I0J5874D01*
G01Y46654D01*
G03X1442424Y50670I-5938J0D01*
G01Y50786D01*
X1442657Y51019D01*
X1444546D01*
X1444895Y50670D01*
G02X1445986Y46656I-6843J-4015D01*
G01Y7874D01*
G03X1449862Y3998I3876J0D01*
G01X1497106D01*
G03X1500982Y7874I0J3876D01*
G01Y46654D01*
G02X1508917Y54588I7935J-1D01*
G37*
G36*
G01X1441145Y369566D02*
G03I-577J0D01*
G37*
G36*
G01X1439165Y380589D02*
G03I-577J0D01*
G37*
G36*
G01X1440026Y979009D02*
G03I-577J0D01*
G37*
G36*
G01X1450196Y363290D02*
G03I-577J0D01*
G37*
G36*
G01X1456556Y391756D02*
G03I-577J0D01*
G37*
G36*
G01X1458789Y403374D02*
G03I-577J0D01*
G37*
G36*
G01X1519789Y1130088D02*
X1561301D01*
G02X1561443Y1130029I0J-200D01*
G01X1561861Y1129611D01*
X1561892Y1129532D01*
X1561890Y1129489D01*
G03X1561888Y1129429I1200J-70D01*
G01Y1129428D01*
G03X1563089Y1128227I1202J1D01*
G01X1563090D01*
G03X1563150Y1128229I-10J1202D01*
G02X1563232Y1128215I8J-200D01*
G01X1563272Y1128200D01*
X1564216Y1127256D01*
G02X1564274Y1127115I-142J-141D01*
G01Y1126800D01*
G03X1564275Y1126781I1200J54D01*
G01Y1126777D01*
Y1124608D01*
Y1124599D01*
Y1124595D01*
G03X1564274Y1124576I1199J-73D01*
G01Y1123060D01*
G03X1564275Y1123041I1200J54D01*
G01Y1123037D01*
Y1120868D01*
Y1120859D01*
Y1120855D01*
G03X1564274Y1120836I1199J-73D01*
G01Y1119320D01*
G03X1564275Y1119301I1200J54D01*
G01Y1119297D01*
Y1117128D01*
Y1117119D01*
Y1117115D01*
G03X1564274Y1117096I1199J-73D01*
G01Y1115864D01*
G02X1564272Y1115835I-200J-1D01*
G02X1564179Y1115693I-198J28D01*
G02X1564175Y1115691I-91J178D01*
G01X1563879Y1115518D01*
G02X1563780Y1115490I-102J172D01*
G01X1563727D01*
X1563681Y1115516D01*
X1563680D01*
G03X1563092Y1115670I-589J-1050D01*
G01X1563090D01*
G03Y1113266I0J-1202D01*
G01X1563092D01*
G03X1563600Y1113379I-1J1204D01*
G01X1563628Y1113392D01*
X1563636Y1113396D01*
G02X1563730Y1113420I95J-176D01*
G01X1563822D01*
G02X1563924Y1113392I0J-200D01*
G01X1564176Y1113244D01*
G02X1564274Y1113071I-102J-172D01*
G01Y1111840D01*
G03X1564275Y1111821I1200J54D01*
G01Y1111817D01*
Y1110072D01*
G02X1564193Y1109910I-200J-1D01*
G03X1563658Y1108858I767J-1052D01*
G03X1563713Y1108484I1302J0D01*
G02X1563464Y1108236I-192J-57D01*
G03X1563253Y1108280I-371J-1249D01*
G01X1563251Y1108281D01*
X1563227Y1108284D01*
G03X1563089Y1108291I-135J-1296D01*
G03X1561786Y1106989I0J-1303D01*
G01Y1103248D01*
G03X1563088Y1101946I1302J0D01*
G01X1563089D01*
G03X1563237Y1101954I4J1303D01*
G01X1563283Y1101959D01*
X1563368Y1101930D01*
X1563655Y1101645D01*
X1563685Y1101560D01*
X1563680Y1101514D01*
G03X1563672Y1101376I1280J-143D01*
G03X1564194Y1100341I1287J0D01*
G02X1564275Y1100180I-119J-161D01*
G01Y1098851D01*
G02X1564193Y1098689I-200J-1D01*
G03Y1096585I767J-1052D01*
G02X1564275Y1096423I-118J-161D01*
G01Y1095111D01*
G02X1564193Y1094949I-200J-1D01*
G03Y1092845I767J-1052D01*
G02X1564275Y1092683I-118J-161D01*
G01Y1091371D01*
G02X1564193Y1091209I-200J-1D01*
G03Y1089105I767J-1052D01*
G02X1564275Y1088943I-118J-161D01*
G01Y1087613D01*
G02X1564194Y1087452I-200J0D01*
G03X1563672Y1086417I765J-1035D01*
G03X1563680Y1086281I1288J8D01*
G01X1563685Y1086235D01*
X1563654Y1086150D01*
X1563367Y1085866D01*
X1563282Y1085836D01*
X1563236Y1085842D01*
G03X1563089Y1085850I-144J-1294D01*
G03X1561786Y1084547I0J-1303D01*
G01Y1080807D01*
G03X1561794Y1080659I1303J-4D01*
G01X1561800Y1080614D01*
X1561770Y1080529D01*
X1561486Y1080242D01*
X1561401Y1080212D01*
X1561355Y1080216D01*
G03X1561220Y1080224I-144J-1279D01*
G03X1562508Y1078936I0J-1288D01*
G03X1562500Y1079072I-1288J-8D01*
G01X1562495Y1079118D01*
X1562526Y1079203D01*
X1562812Y1079488D01*
X1562897Y1079517D01*
X1562943Y1079512D01*
G03X1563088Y1079504I144J1295D01*
G01X1563089D01*
G03X1563220Y1079511I-4J1302D01*
G01X1563221Y1079512D01*
X1563226D01*
X1563271Y1079517D01*
X1563356Y1079487D01*
X1563640Y1079203D01*
X1563670Y1079118D01*
X1563665Y1079072D01*
G03X1563658Y1078936I1295J-135D01*
G03X1564193Y1077884I1302J0D01*
G02X1564275Y1077722I-118J-161D01*
G01Y1076410D01*
G02X1564193Y1076248I-200J-1D01*
G03Y1074144I767J-1052D01*
G02X1564275Y1073982I-118J-161D01*
G01Y1069746D01*
Y1069737D01*
Y1069733D01*
G03X1564274Y1069714I1199J-73D01*
G01Y1029950D01*
G03X1564275Y1029931I1200J54D01*
G01Y1029927D01*
Y986342D01*
G02X1564216Y986200I-200J0D01*
G01X1560834Y982818D01*
G02X1560692Y982759I-142J141D01*
G01X1529856D01*
G02X1529656Y982959I0J200D01*
G01Y984864D01*
G03X1529214Y985929I-1507J-1D01*
G01X1527680Y987463D01*
G02X1527622Y987605I142J141D01*
G01Y988790D01*
G03X1527180Y989855I-1507J-1D01*
G01X1522506Y994529D01*
G03X1521441Y994970I-1065J-1065D01*
G01X1463551D01*
G03X1462486Y994529I0J-1506D01*
G01X1458454Y990497D01*
G03X1458012Y989432I1065J-1066D01*
G03X1458147Y988810I1507J1D01*
G01X1458173Y988752D01*
X1458151Y988631D01*
X1456377Y986858D01*
G02X1456094I-141J141D01*
G01X1449329Y993623D01*
X1449300Y993651D01*
X1449270Y993725D01*
Y1000586D01*
G02X1449329Y1000728I200J0D01*
G01X1453767Y1005166D01*
G03X1453955Y1005404I-924J923D01*
G01X1453967Y1005424D01*
X1454050Y1005507D01*
G03X1454109Y1005648I-141J142D01*
G01Y1005766D01*
X1454114Y1005789D01*
G03X1454150Y1006090I-1271J305D01*
G01Y1029763D01*
G02X1454208Y1029904I200J0D01*
G01X1460192Y1035888D01*
G02X1460333Y1035946I141J-142D01*
G01X1502006D01*
G02X1502182Y1035841I0J-200D01*
G01X1502322Y1035580D01*
G02X1502337Y1035427I-177J-95D01*
G01X1502318Y1035366D01*
X1502302Y1035342D01*
G03X1502069Y1034538I1271J-804D01*
G01Y1034506D01*
X1502073Y1034445D01*
G03X1503572Y1033036I1499J93D01*
G03X1505074Y1034538I0J1502D01*
G01Y1034598D01*
G03X1504842Y1035342I-1502J-60D01*
G01X1504826Y1035366D01*
X1504807Y1035427D01*
G02X1504822Y1035580I192J58D01*
G01X1504962Y1035841D01*
G02X1505138Y1035946I176J-95D01*
G01X1511927D01*
G03X1512228Y1035982I-4J1307D01*
G01X1512251Y1035987D01*
X1512369D01*
G03X1512510Y1036046I-1J200D01*
G01X1512593Y1036129D01*
X1512613Y1036141D01*
G03X1512851Y1036329I-685J1112D01*
G01X1522857Y1046335D01*
G02X1522998Y1046394I142J-141D01*
G01X1526400D01*
G03X1527324Y1046776I1J1306D01*
G01X1530032Y1049484D01*
G02X1530173Y1049542I141J-142D01*
G01X1531193D01*
X1531240Y1049531D01*
X1531262Y1049520D01*
G03X1531961Y1049347I700J1329D01*
G03Y1052351I0J1502D01*
G03X1531262Y1052178I1J-1502D01*
G01X1531240Y1052167D01*
X1531193Y1052156D01*
X1529549D01*
G03X1529252Y1052121I3J-1307D01*
G01X1529229Y1052116D01*
X1529175D01*
G03X1529148Y1052115I33J-1267D01*
G01X1528733D01*
G03X1528592Y1052056I1J-200D01*
G01X1528316Y1051780D01*
X1528312Y1051777D01*
G03X1528279Y1051745I866J-926D01*
G01X1527320Y1050786D01*
G03X1527306Y1050772I889J-903D01*
G01X1527305Y1050771D01*
X1527300Y1050766D01*
X1527011Y1050475D01*
G03X1526952Y1050334I141J-142D01*
G01Y1050293D01*
G02X1526893Y1050151I-200J0D01*
G01X1525840Y1049097D01*
G02X1525698Y1049038I-142J141D01*
G01X1522004D01*
G03X1521863Y1048979I1J-200D01*
G01X1521725Y1048841D01*
G02X1521689Y1048812I-143J140D01*
G03X1521450Y1048624I683J-1114D01*
G01X1511444Y1038618D01*
G02X1511303Y1038560I-141J142D01*
G01X1509491D01*
G02X1509306Y1038683I-1J200D01*
G01X1509283Y1038740D01*
X1509306Y1038857D01*
X1525537Y1055088D01*
G02X1525678Y1055146I141J-142D01*
G01X1531225D01*
X1531272Y1055135D01*
X1531294Y1055123D01*
G03X1531993Y1054950I700J1330D01*
G03Y1057956I0J1503D01*
G03X1531294Y1057783I1J-1503D01*
G01X1531272Y1057771D01*
X1531225Y1057760D01*
X1525054D01*
G03X1524753Y1057724I4J-1307D01*
G01X1524730Y1057719D01*
X1524320D01*
G03X1524179Y1057660I1J-200D01*
G01X1524072Y1057553D01*
X1523907Y1057389D01*
X1523903Y1057384D01*
X1523892Y1057374D01*
G03X1523866Y1057349I865J-926D01*
G01X1520404Y1053886D01*
X1520013Y1053495D01*
G02X1519812Y1053446I-141J142D01*
G01X1519419Y1053570D01*
X1519346Y1053654D01*
X1519337Y1053710D01*
G03X1517855Y1054960I-1482J-254D01*
G03X1516352Y1053457I0J-1503D01*
G03X1517602Y1051975I1504J0D01*
G01X1517659Y1051965D01*
X1517742Y1051893D01*
X1517866Y1051500D01*
G02X1517817Y1051299I-191J-60D01*
G01X1506545Y1040028D01*
G02X1506404Y1039970I-141J142D01*
G01X1459124D01*
G03X1458200Y1039587I0J-1306D01*
G01X1450509Y1031896D01*
G03X1450126Y1030972I923J-924D01*
G01Y1007299D01*
G02X1450068Y1007158I-200J0D01*
G01X1449738Y1006827D01*
G02X1449522Y1006783I-141J142D01*
G02X1449270Y1007154I148J372D01*
G01Y1124317D01*
G02X1449329Y1124459I200J0D01*
G01X1454899Y1130029D01*
G02X1455041Y1130088I142J-141D01*
G01X1494557D01*
X1494664Y1130003D01*
X1494681Y1129935D01*
G03X1495228Y1129098I1459J356D01*
G01X1495238Y1129090D01*
X1495255Y1129073D01*
G02X1495314Y1128934I-141J-142D01*
G01X1495319Y1128574D01*
X1495280Y1128491D01*
X1495244Y1128462D01*
G03X1494683Y1127291I942J-1171D01*
G03X1497687I1502J0D01*
G03X1497099Y1128483I-1502J0D01*
G01X1497088Y1128491D01*
X1497063Y1128516D01*
X1497056Y1128524D01*
G02X1497011Y1128648I155J126D01*
G01X1497006Y1129009D01*
X1497045Y1129092D01*
X1497082Y1129121D01*
G03X1497599Y1129935I-942J1170D01*
G01X1497616Y1130003D01*
X1497723Y1130088D01*
X1500057D01*
X1500164Y1130003D01*
X1500181Y1129935D01*
G03X1503099I1459J356D01*
G01X1503116Y1130003D01*
X1503223Y1130088D01*
X1503547D01*
X1503654Y1130003D01*
X1503671Y1129935D01*
G03X1506589I1459J356D01*
G01X1506606Y1130003D01*
X1506713Y1130088D01*
X1512887D01*
G02X1513029Y1130029I0J-200D01*
G01X1513036Y1130022D01*
X1513234Y1129789D01*
G02X1513249Y1129769I-152J-130D01*
G02X1513282Y1129659I-167J-110D01*
G01Y1129625D01*
X1513280Y1129610D01*
G03X1513266Y1129429I1188J-183D01*
G03X1515670I1202J0D01*
G03X1515654Y1129623I-1202J-1D01*
G01X1515647Y1129667D01*
X1515670Y1129751D01*
X1515896Y1130017D01*
G02X1516049Y1130088I153J-129D01*
G01X1516627D01*
G02X1516769Y1130029I0J-200D01*
G01X1516776Y1130022D01*
X1516974Y1129789D01*
G02X1516989Y1129769I-152J-130D01*
G02X1517022Y1129659I-167J-110D01*
G01Y1129625D01*
X1517020Y1129610D01*
G03X1517006Y1129429I1188J-183D01*
G03X1519410I1202J0D01*
G03X1519394Y1129623I-1202J-1D01*
G01X1519387Y1129667D01*
X1519410Y1129751D01*
X1519636Y1130017D01*
G02X1519789Y1130088I153J-129D01*
G37*
G36*
G01X1473941Y410724D02*
G03I-577J0D01*
G37*
G36*
G01X1472980Y417338D02*
G03I-577J0D01*
G37*
G36*
G01X1469870Y428815D02*
G03I-577J0D01*
G37*
G36*
G01X1617832Y693408D02*
X1620615D01*
G03X1622246Y694084I-1J2307D01*
G01X1634431Y706269D01*
G03X1635106Y707899I-1631J1630D01*
G01Y718658D01*
G03X1634431Y720288I-2306J0D01*
G01X1629392Y725327D01*
G02X1629363Y725574I141J142D01*
G01X1629380Y725601D01*
X1629475Y725696D01*
X1629503Y725711D01*
X1629529Y725725D01*
G03X1630315Y727045I-715J1320D01*
G03X1629279Y728472I-1501J0D01*
G01X1629265Y728476D01*
X1629261Y728478D01*
X1629242Y728484D01*
G02X1629106Y728674I64J190D01*
G01Y745835D01*
G02X1629129Y745927I200J-1D01*
G01X1629171Y746009D01*
G02X1629230Y746076I176J-95D01*
G01X1629231D01*
G03X1629845Y747288I-888J1211D01*
G03X1628343Y748790I-1502J0D01*
G01X1628342D01*
G03X1627702Y748647I0J-1502D01*
G01X1627645Y748620D01*
X1627521Y748641D01*
X1623867Y752294D01*
G02X1623808Y752436I141J142D01*
G01Y759117D01*
G02X1623867Y759259I200J0D01*
G01X1623924Y759316D01*
G02X1623984Y759357I141J-142D01*
G01X1624078Y759399D01*
X1624113Y759402D01*
G03X1624115Y762398I-113J1498D01*
G01X1624080Y762401D01*
X1623985Y762443D01*
G02X1623923Y762487I83J182D01*
G01X1623865Y762547D01*
G02X1623808Y762686I143J140D01*
G01Y762697D01*
X1625222Y764113D01*
G02X1625224Y764115I142J-140D01*
G01X1625248Y764138D01*
G02X1625387Y764194I139J-144D01*
G01X1657202D01*
G03X1658832Y764869I0J2306D01*
G01X1660438Y766475D01*
G03X1661114Y768106I-1631J1632D01*
G01Y771839D01*
G03X1660438Y773470I-2307J-1D01*
G01X1658673Y775235D01*
G03X1657043Y775910I-1630J-1631D01*
G01X1657042D01*
G03X1654736Y773604I0J-2306D01*
G01Y773603D01*
G03X1655411Y771973I2306J0D01*
G01X1656067Y771317D01*
G02X1656110Y771100I-142J-141D01*
G01X1656087Y771043D01*
X1655986Y770976D01*
X1622392D01*
G03X1620761Y770300I1J-2307D01*
G01X1618001Y767540D01*
G03X1617326Y765910I1631J-1630D01*
G01Y765158D01*
G02X1617267Y765016I-200J0D01*
G01X1614442Y762191D01*
G02X1614280Y762134I-141J142D01*
G01X1613978Y762166D01*
G02X1613858Y762223I21J199D01*
G01X1613827Y762254D01*
X1613816Y762270D01*
G03X1612573Y762929I-1243J-843D01*
G01X1612564D01*
G02X1612462Y762957I0J200D01*
G01X1612461D01*
G02X1612380Y763052I104J171D01*
G01X1612236Y763393D01*
G02X1612235Y763395I178J90D01*
G02X1612279Y763612I185J75D01*
G01X1612551Y763884D01*
G03X1612934Y764808I-923J924D01*
G01Y779512D01*
G02X1612940Y779561I200J0D01*
G01X1612957Y779629D01*
X1612967Y779650D01*
X1612968Y779652D01*
G03X1613129Y780327I-1341J676D01*
G03X1610125I-1502J0D01*
G03X1610287Y779649I1502J0D01*
G01X1610297Y779628D01*
X1610314Y779560D01*
G02X1610320Y779511I-194J-49D01*
G01Y777955D01*
G02X1610245Y777799I-200J0D01*
G01X1610004Y777605D01*
G02X1609849Y777563I-125J156D01*
G01X1609832Y777565D01*
X1609826Y777566D01*
X1609815Y777568D01*
G03X1609501Y777602I-318J-1468D01*
G01X1609500D01*
G03Y774598I0J-1502D01*
G01X1609501D01*
G03X1609800Y774629I-5J1502D01*
G01X1609801D01*
X1609830Y774635D01*
X1609851Y774637D01*
G02X1609954Y774619I18J-199D01*
G01X1609978Y774608D01*
G02X1610019Y774583I-83J-182D01*
G01X1610245Y774401D01*
G02X1610320Y774245I-125J-156D01*
G01Y765432D01*
G02X1610261Y765290I-200J0D01*
G01X1608787Y763816D01*
G03X1608404Y762892I923J-924D01*
G01Y756237D01*
G02X1608345Y756095I-200J0D01*
G01X1580599Y728348D01*
G02X1580457Y728289I-142J141D01*
G01X1510145D01*
G02X1510003Y728348I0J200D01*
G01X1507671Y730680D01*
G02X1507612Y730822I141J142D01*
G01Y741766D01*
G02X1507671Y741908I200J0D01*
G01X1508431Y742668D01*
G03X1509106Y744298I-1631J1630D01*
G01Y831894D01*
G02X1509210Y832070I200J0D01*
G01X1509510Y832233D01*
G02X1509529Y832242I95J-176D01*
G02X1509661Y832250I77J-184D01*
G01X1509722Y832232D01*
X1509746Y832218D01*
X1509748Y832217D01*
G03X1510527Y831998I781J1283D01*
G03Y835002I0J1502D01*
G03X1509721Y834767I1J-1502D01*
G01X1509674Y834738D01*
X1509566Y834734D01*
X1509210Y834930D01*
G02X1509106Y835105I96J175D01*
G01Y843778D01*
G03X1508431Y845408I-2306J0D01*
G01X1488301Y865538D01*
G02X1488242Y865680I141J142D01*
G01Y871233D01*
X1488334Y871344D01*
X1488406Y871357D01*
G03X1489644Y872839I-268J1482D01*
G01Y874763D01*
G03X1489203Y875828I-1506J0D01*
G01X1488690Y876342D01*
G02X1488634Y876517I141J142D01*
G01X1488696Y876886D01*
X1488754Y876963D01*
X1488797Y876984D01*
G03X1489644Y878339I-660J1355D01*
G01Y889166D01*
G02X1489765Y889350I200J0D01*
G01X1489766D01*
G02X1489986Y889307I78J-184D01*
G01X1499138Y880156D01*
G03X1500203Y879714I1066J1065D01*
G01X1516657D01*
G02X1516813Y879639I0J-200D01*
G01X1517007Y879398D01*
G02X1517050Y879250I-156J-126D01*
G01X1517047Y879227D01*
X1517045Y879217D01*
Y879216D01*
X1517041Y879196D01*
G03X1517010Y878898I1475J-304D01*
G03X1518515Y877392I1506J0D01*
G01X1644840D01*
G03X1645905Y877833I0J1506D01*
G01X1696382Y928309D01*
G02X1696524Y928368I142J-141D01*
G01X1747275D01*
G03X1748340Y928810I-1J1507D01*
G01X1749570Y930039D01*
G02X1749712Y930098I142J-141D01*
G01X1749994D01*
G02X1750136Y930039I0J-200D01*
G03X1751199Y929598I1063J1061D01*
G01X1751200D01*
G03X1752702Y931100I0J1502D01*
G01Y931101D01*
G03X1752261Y932164I-1502J0D01*
G02X1752202Y932306I141J142D01*
G01Y932589D01*
G02X1752261Y932731I200J0D01*
G01X1752714Y933184D01*
G02X1752716Y933186I142J-140D01*
G01X1752739Y933208D01*
G02X1752878Y933264I139J-144D01*
G01X1775223D01*
G02X1775363Y933207I0J-200D01*
G01X1775364Y933206D01*
X1778335Y930235D01*
G02X1778394Y930093I-141J-142D01*
G01Y923000D01*
G03X1778835Y921935I1506J0D01*
G01X1781635Y919135D01*
G03X1782700Y918694I1065J1065D01*
G01X1786530D01*
G03X1787595Y919135I0J1506D01*
G01X1796453Y927993D01*
G03X1796894Y929058I-1065J1065D01*
G01Y929081D01*
G02X1797094Y929281I200J0D01*
G01X1797110D01*
X1797126Y929278D01*
G03X1797363Y929259I238J1483D01*
G01X1797365D01*
G03Y932263I0J1502D01*
G01X1797364D01*
G03X1796873Y932180I1J-1502D01*
G01X1796857Y932175D01*
X1796821Y932169D01*
G02X1796697Y932187I-35J197D01*
G01X1796643Y932213D01*
G02X1796577Y932267I91J178D01*
G01X1796576Y932268D01*
X1796575Y932269D01*
X1796568Y932278D01*
G03X1796453Y932408I-1184J-931D01*
G01X1795469Y933392D01*
G03X1794404Y933834I-1066J-1065D01*
G01X1791366D01*
G03X1790301Y933392I1J-1507D01*
G01X1788472Y931563D01*
G03X1788030Y930498I1065J-1066D01*
G03X1789158Y929040I1506J0D01*
G01X1789210Y929027D01*
X1789286Y928951D01*
X1789392Y928564D01*
G02X1789364Y928399I-193J-52D01*
G01X1789353Y928383D01*
X1784935Y923965D01*
G02X1784793Y923906I-142J141D01*
G01X1784308D01*
G02X1784166Y923965I0J200D01*
G01X1783465Y924666D01*
G02X1783406Y924808I141J142D01*
G01Y931500D01*
G03X1782965Y932565I-1506J0D01*
G01X1778906Y936624D01*
G02Y936906I142J141D01*
G01X1779755Y937755D01*
G02X1779897Y937814I142J-141D01*
G01X1812698D01*
G02X1812838Y937757I0J-200D01*
G01X1812839Y937756D01*
X1823836Y926759D01*
G02X1823895Y926617I-141J-142D01*
G01Y559540D01*
G02X1823836Y559398I-200J0D01*
G01X1822882Y558444D01*
G02X1822740Y558385I-142J141D01*
G01X1745404D01*
G02X1745364Y558389I0J200D01*
G01X1745325Y558397D01*
G02X1745289Y558408I40J196D01*
G03X1744795Y558506I-496J-1208D01*
G01X1625727D01*
G02X1625585Y558565I0J200D01*
G01X1624371Y559779D01*
G02X1624312Y559921I141J142D01*
G01Y562322D01*
X1624290Y562343D01*
Y637293D01*
G02X1624349Y637435I200J0D01*
G01X1628411Y641497D01*
G02X1628427Y641575I200J0D01*
G01X1628465Y641656D01*
G02X1628489Y641695I181J-85D01*
G01X1628502Y641711D01*
X1628517Y641724D01*
G03X1629226Y643252I-1292J1528D01*
G01Y679222D01*
G02X1629243Y679302I200J-1D01*
G01X1629256Y679333D01*
X1629275Y679352D01*
Y681460D01*
G03X1629216Y681602I-200J0D01*
G01X1617751Y693067D01*
G02X1617708Y693284I142J141D01*
G01X1617731Y693341D01*
X1617832Y693408D01*
G37*
G36*
G01X1669437Y932794D02*
X1691789D01*
G02X1691974Y932670I0J-200D01*
G01X1691998Y932613D01*
X1691974Y932496D01*
X1642265Y882786D01*
G02X1642123Y882728I-141J142D01*
G01X1500910D01*
G02X1500768Y882786I-1J200D01*
G01X1491689Y891865D01*
G02X1491630Y892007I141J142D01*
G01Y899576D01*
G03X1491189Y900641I-1506J0D01*
G01X1485943Y905888D01*
G02X1485884Y906029I141J142D01*
G01Y912270D01*
G02X1486084Y912470I200J0D01*
G01X1509338D01*
G03X1510969Y913145I1J2306D01*
G01X1513059Y915235D01*
G02X1513200Y915294I142J-141D01*
G01X1546972D01*
X1547075Y915222D01*
X1547097Y915163D01*
G03X1549911I1407J526D01*
G01X1549933Y915222D01*
X1550036Y915294D01*
X1631962D01*
G02X1632103Y915235I-1J-200D01*
G01X1633469Y913869D01*
G03X1635100Y913194I1630J1631D01*
G01X1648799D01*
G03X1650430Y913869I1J2306D01*
G01X1669296Y932735D01*
G02X1669437Y932794I142J-141D01*
G37*
G36*
G01X1487033Y932563D02*
X1489726Y935256D01*
G02X1489888Y935313I141J-142D01*
G01X1490242Y935276D01*
X1490319Y935229D01*
X1490344Y935191D01*
G03X1490515Y934980I1095J713D01*
G01X1500409Y925086D01*
G03X1501333Y924704I923J924D01*
G01X1525567D01*
G02X1525708Y924645I-1J-200D01*
G01X1529141Y921212D01*
G02X1529200Y921070I-141J-142D01*
G01Y920106D01*
G02X1529000Y919906I-200J0D01*
G01X1522816D01*
G02X1522648Y919998I0J200D01*
G01X1522438Y920324D01*
X1522431Y920426D01*
X1522452Y920472D01*
G03X1522587Y921094I-1367J622D01*
G03X1519583I-1502J0D01*
G03X1519718Y920472I1502J0D01*
G01X1519739Y920426D01*
X1519732Y920324D01*
X1519522Y919998D01*
G02X1519354Y919906I-168J108D01*
G01X1516910D01*
G02X1516742Y919998I0J200D01*
G01X1516532Y920324D01*
X1516525Y920426D01*
X1516546Y920472D01*
G03X1516681Y921094I-1367J622D01*
G03X1513677I-1502J0D01*
G03X1513812Y920472I1502J0D01*
G01X1513833Y920426D01*
X1513826Y920324D01*
X1513616Y919998D01*
G02X1513448Y919906I-168J108D01*
G01X1512162D01*
G03X1510531Y919231I-1J-2306D01*
G01X1508441Y917141D01*
G02X1508300Y917082I-142J141D01*
G01X1486084D01*
G02X1485884Y917282I0J200D01*
G01Y922809D01*
G02X1485984Y922982I200J0D01*
G01X1486331Y923182D01*
X1486439D01*
X1486485Y923155D01*
G03X1487240Y922951I756J1298D01*
G03Y925955I0J1502D01*
G03X1486485Y925751I1J-1502D01*
G01X1486439Y925724D01*
X1486331D01*
X1485984Y925924D01*
G02X1485884Y926097I100J173D01*
G01Y926218D01*
X1485910Y926286D01*
X1485936Y926314D01*
G03Y928334I-1113J1010D01*
G02X1485884Y928468I148J134D01*
G01Y930965D01*
X1485955Y931067D01*
X1486015Y931089D01*
G03X1487001Y932454I-515J1411D01*
G01X1487002Y932493D01*
X1487033Y932563D01*
G37*
G36*
G01X1510031Y402291D02*
G03I-577J0D01*
G37*
G36*
G01Y397335D02*
G03I-577J0D01*
G37*
G36*
G01X1512623Y411509D02*
G03I-577J0D01*
G37*
G36*
G01X1507631Y416465D02*
G03I-577J0D01*
G37*
G36*
G01Y411509D02*
G03I-577J0D01*
G37*
G36*
G01X1512623Y425682D02*
G03I-577J0D01*
G37*
G36*
G01X1507631D02*
G03I-577J0D01*
G37*
G36*
G01X1512623Y416465D02*
G03I-577J0D01*
G37*
G36*
G01Y439855D02*
G03I-577J0D01*
G37*
G36*
G01X1507631D02*
G03I-577J0D01*
G37*
G36*
G01X1512623Y430638D02*
G03I-577J0D01*
G37*
G36*
G01X1507631D02*
G03I-577J0D01*
G37*
G36*
G01Y444811D02*
G03I-577J0D01*
G37*
G36*
G01X1512623D02*
G03I-577J0D01*
G37*
G36*
G01X1507631Y473565D02*
G03I-577J0D01*
G37*
G36*
G01X1512623D02*
G03I-577J0D01*
G37*
G36*
G01X1507631Y468609D02*
G03I-577J0D01*
G37*
G36*
G01X1512623D02*
G03I-577J0D01*
G37*
G36*
G01Y487738D02*
G03I-577J0D01*
G37*
G36*
G01X1507631D02*
G03I-577J0D01*
G37*
G36*
G01Y482782D02*
G03I-577J0D01*
G37*
G36*
G01X1512623D02*
G03I-577J0D01*
G37*
G36*
G01X1507631Y517699D02*
G03I-577J0D01*
G37*
G36*
G01X1512623D02*
G03I-577J0D01*
G37*
G36*
G01X1507631Y512743D02*
G03I-577J0D01*
G37*
G36*
G01X1512623D02*
G03I-577J0D01*
G37*
G36*
G01X1507631Y526916D02*
G03I-577J0D01*
G37*
G36*
G01X1512623Y531872D02*
G03I-577J0D01*
G37*
G36*
G01X1507631D02*
G03I-577J0D01*
G37*
G36*
G01X1512623Y526916D02*
G03I-577J0D01*
G37*
G36*
G01X1516356Y351594D02*
G03I-577J0D01*
G37*
G36*
G01X1518033Y390223D02*
G03I-577J0D01*
G37*
G36*
G01X1523025D02*
G03I-577J0D01*
G37*
G36*
G01X1515023Y402291D02*
G03I-577J0D01*
G37*
G36*
G01Y397335D02*
G03I-577J0D01*
G37*
G36*
G01X1518033Y395179D02*
G03I-577J0D01*
G37*
G36*
G01Y404396D02*
G03I-577J0D01*
G37*
G36*
G01Y409352D02*
G03I-577J0D01*
G37*
G36*
G01X1523025Y395179D02*
G03I-577J0D01*
G37*
G36*
G01Y404396D02*
G03I-577J0D01*
G37*
G36*
G01Y409352D02*
G03I-577J0D01*
G37*
G36*
G01X1518033Y418569D02*
G03I-577J0D01*
G37*
G36*
G01Y423525D02*
G03I-577J0D01*
G37*
G36*
G01X1523025D02*
G03I-577J0D01*
G37*
G36*
G01Y418569D02*
G03I-577J0D01*
G37*
G36*
G01X1518033Y437699D02*
G03I-577J0D01*
G37*
G36*
G01X1523025Y432743D02*
G03I-577J0D01*
G37*
G36*
G01Y437699D02*
G03I-577J0D01*
G37*
G36*
G01X1518033Y432743D02*
G03I-577J0D01*
G37*
G36*
G01Y489895D02*
G03I-577J0D01*
G37*
G36*
G01X1523025D02*
G03I-577J0D01*
G37*
G36*
G01Y480677D02*
G03I-577J0D01*
G37*
G36*
G01Y475721D02*
G03I-577J0D01*
G37*
G36*
G01X1518033Y480677D02*
G03I-577J0D01*
G37*
G36*
G01Y475721D02*
G03I-577J0D01*
G37*
G36*
G01Y494851D02*
G03I-577J0D01*
G37*
G36*
G01X1523025D02*
G03I-577J0D01*
G37*
G36*
G01X1518033Y519855D02*
G03I-577J0D01*
G37*
G36*
G01X1523025D02*
G03I-577J0D01*
G37*
G36*
G01Y538984D02*
G03I-577J0D01*
G37*
G36*
G01X1518033D02*
G03I-577J0D01*
G37*
G36*
G01Y524811D02*
G03I-577J0D01*
G37*
G36*
G01Y534028D02*
G03I-577J0D01*
G37*
G36*
G01X1523025D02*
G03I-577J0D01*
G37*
G36*
G01Y524811D02*
G03I-577J0D01*
G37*
G36*
G01X1606702Y681478D02*
X1622135D01*
G02X1622276Y681419I-1J-200D01*
G01X1623225Y680470D01*
G02X1623284Y680329I-141J-142D01*
G01Y582069D01*
G02X1623225Y581927I-200J0D01*
G01X1597374Y556076D01*
X1597346Y556048D01*
X1597273Y556017D01*
X1596911Y556016D01*
X1596839Y556045D01*
X1596811Y556073D01*
G03X1595760Y556502I-1051J-1073D01*
G03X1594258Y555000I0J-1502D01*
G03X1594687Y553949I1502J0D01*
G01X1594715Y553921D01*
X1594744Y553849D01*
X1594743Y553527D01*
G02X1594684Y553386I-200J1D01*
G01X1591093Y549795D01*
X1591065Y549766D01*
X1590991Y549736D01*
X1584097D01*
G02X1584069Y549738I0J200D01*
G01X1581923Y551884D01*
G03X1580999Y552266I-923J-924D01*
G01X1579024D01*
G02X1578835Y552401I0J200D01*
G01X1578705Y552779D01*
X1578741Y552901D01*
X1578791Y552941D01*
G03X1579364Y554121I-929J1180D01*
G03X1577862Y555623I-1502J0D01*
G03X1576566Y554880I0J-1502D01*
G01X1576538Y554833D01*
X1576444Y554780D01*
X1575986Y554790D01*
X1575894Y554847D01*
X1575868Y554895D01*
G03X1574540Y555695I-1328J-702D01*
G03Y552691I0J-1502D01*
G03X1575836Y553434I0J1502D01*
G01X1575864Y553481D01*
X1575958Y553534D01*
X1576416Y553524D01*
X1576508Y553467D01*
X1576534Y553419D01*
G03X1576819Y553040I1328J702D01*
G03X1576933Y552941I1041J1083D01*
G01X1576983Y552901D01*
X1577019Y552779D01*
X1576889Y552401D01*
G02X1576700Y552266I-189J65D01*
G01X1566381D01*
G03X1565457Y551884I-1J-1306D01*
G01X1563368Y549795D01*
G02X1563226Y549736I-142J141D01*
G01X1558938D01*
G02X1558797Y549794I0J200D01*
G01X1558568Y550021D01*
X1558538Y550092D01*
Y550133D01*
G03X1558024Y551255I-1502J-9D01*
G01X1557994Y551281D01*
X1557976Y551317D01*
G02X1557955Y551397I179J90D01*
G01X1557943Y551687D01*
G02X1557955Y551765I200J9D01*
G01X1557969Y551803D01*
G03X1558416Y552872I-1055J1069D01*
G03X1555412I-1502J0D01*
G03X1555926Y551740I1502J-1D01*
G01X1555956Y551714D01*
X1555974Y551678D01*
G02X1555995Y551598I-179J-90D01*
G01X1556007Y551308D01*
G02X1555995Y551230I-200J-9D01*
G01X1555981Y551192D01*
G03X1555534Y550133I1055J-1069D01*
G01Y550092D01*
X1555504Y550021D01*
X1555275Y549794D01*
G02X1555134Y549736I-141J142D01*
G01X1525703D01*
G02X1525561Y549795I0J200D01*
G01X1514421Y560935D01*
X1514392Y560963D01*
X1514362Y561037D01*
Y623131D01*
G02X1514419Y623271I200J0D01*
G01X1514420Y623272D01*
X1517041Y625893D01*
G02X1517043Y625895I142J-140D01*
G02X1517183Y625952I140J-143D01*
G01X1530102D01*
G03X1530244Y626011I0J200D01*
G01X1537366Y633133D01*
G02X1537508Y633192I142J-141D01*
G01X1550621D01*
G02X1550792Y633095I0J-200D01*
G01X1550997Y632757D01*
X1551000Y632653D01*
X1550975Y632606D01*
G03X1558480Y632477I3720J-1956D01*
G01X1558457Y632524D01*
X1558462Y632625D01*
X1558670Y632957D01*
G02X1558840Y633050I169J-107D01*
G01X1565235D01*
G03X1566223Y633185I-3J3702D01*
G01X1566249Y633192D01*
X1567084D01*
G03X1567226Y633251I0J200D01*
G01X1575862Y641887D01*
G02X1576003Y641946I142J-141D01*
G01X1577974D01*
G03X1578898Y642328I1J1306D01*
G01X1597735Y661165D01*
G03X1598118Y662089I-923J924D01*
G01Y664060D01*
G02X1598176Y664201I200J0D01*
G01X1598549Y664574D01*
G03X1598608Y664716I-141J142D01*
G01Y673384D01*
G02X1598667Y673526I200J0D01*
G01X1606560Y681419D01*
G02X1606702Y681478I142J-141D01*
G37*
G36*
G01X1523820Y937814D02*
X1636673D01*
G02X1636814Y937755I-1J-200D01*
G01X1640035Y934535D01*
G03X1641100Y934094I1065J1065D01*
G01X1646093D01*
G02X1646235Y934035I0J-200D01*
G01X1648640Y931630D01*
G02X1648698Y931488I-142J-141D01*
G01Y926206D01*
G02X1648498Y926006I-200J0D01*
G01X1549884D01*
G02X1549696Y926136I0J200D01*
G01X1549542Y926546D01*
X1549572Y926665D01*
X1549620Y926707D01*
G03X1550131Y927836I-992J1129D01*
G03X1547127I-1502J0D01*
G03X1547638Y926707I1503J0D01*
G01X1547686Y926665D01*
X1547716Y926546D01*
X1547562Y926136D01*
G02X1547374Y926006I-188J70D01*
G01X1539058D01*
G02X1538917Y926065I1J200D01*
G01X1532622Y932360D01*
G03X1530991Y933036I-1632J-1631D01*
G01X1528801D01*
X1528698Y933107D01*
X1528676Y933166D01*
G03X1525858I-1409J-518D01*
G01X1525836Y933107D01*
X1525733Y933036D01*
X1524246D01*
G02X1524105Y933094I0J200D01*
G01X1521701Y935498D01*
G02X1521642Y935640I141J142D01*
G01Y935951D01*
G02X1521707Y936099I200J0D01*
G01X1521956Y936327D01*
X1522034Y936354D01*
X1522077Y936350D01*
G03X1522209Y936344I134J1496D01*
G03X1523697Y937641I0J1502D01*
G01X1523707Y937716D01*
X1523820Y937814D01*
G37*
G36*
G01X1611280Y54588D02*
X1639405D01*
X1639599Y54394D01*
Y52785D01*
X1639405Y52591D01*
X1611280D01*
G03X1605343Y46654I0J-5937D01*
G01Y7874D01*
G02X1599469Y2000I-5874J0D01*
G01X1552224D01*
G02X1546350Y7874I0J5874D01*
G01Y46654D01*
G03X1545263Y50079I-5939J0D01*
G01Y50191D01*
X1545272Y50200D01*
X1547511D01*
G02X1548348Y46654I-7097J-3547D01*
G01Y7874D01*
G03X1552224Y3998I3876J0D01*
G01X1599469D01*
G03X1603346Y7874I0J3877D01*
G01Y46654D01*
G02X1611280Y54588I7934J0D01*
G37*
G36*
G01X1578768Y677470D02*
X1593647D01*
G02X1593847Y677270I0J-200D01*
G01Y662651D01*
G02X1593788Y662509I-200J0D01*
G01X1582575Y651296D01*
G02X1582433Y651237I-142J141D01*
G01X1577251D01*
G03X1577109Y651178I0J-200D01*
G01X1577036Y651148D01*
X1565851D01*
G02X1565712Y651204I0J200D01*
G03X1563628I-1042J-1083D01*
G02X1563489Y651148I-139J144D01*
G01X1541979D01*
G02X1541837Y651207I0J200D01*
G01X1535367Y657677D01*
G02X1535308Y657819I141J142D01*
G01Y665094D01*
G02X1535508Y665294I200J0D01*
G01X1558500D01*
G03X1559500Y665521I2J2306D01*
G01X1559542Y665542D01*
X1559637Y665540D01*
X1560006Y665347D01*
X1560061Y665270D01*
X1560068Y665223D01*
G03X1561552Y663953I1484J232D01*
G03X1563054Y665455I0J1502D01*
G03X1561925Y666910I-1502J0D01*
G01X1561873Y666923D01*
X1561796Y666999D01*
X1561690Y667386D01*
G02X1561742Y667580I193J52D01*
G01X1563792Y669630D01*
G02X1563933Y669688I141J-142D01*
G01X1564077D01*
G02X1564277Y669488I0J-200D01*
G01Y669442D01*
X1564238Y669361D01*
X1564201Y669332D01*
G03X1563630Y668153I932J-1179D01*
G03X1566634I1502J0D01*
G03X1566337Y669050I-1503J0D01*
G01X1566303Y669096D01*
X1566293Y669208D01*
X1566479Y669578D01*
G02X1566658Y669688I178J-90D01*
G01X1571395D01*
G03X1573026Y670364I-1J2307D01*
G01X1577231Y674569D01*
G03X1577906Y676200I-1631J1630D01*
G01Y676998D01*
G02X1577961Y677135I200J-1D01*
G01X1578042Y677221D01*
G02X1578165Y677283I146J-137D01*
G03X1578699Y677447I-166J1493D01*
G01X1578721Y677458D01*
X1578768Y677470D01*
G37*
G36*
G01X1613938Y752829D02*
X1616984Y755875D01*
G02X1617202Y755919I142J-141D01*
G01X1617259Y755895D01*
X1617326Y755795D01*
Y749969D01*
G03X1618001Y748338I2306J-1D01*
G01X1622535Y743804D01*
G02X1622594Y743663I-141J-142D01*
G01Y723800D01*
G03X1623269Y722169I2306J-1D01*
G01X1628487Y716951D01*
G02X1628546Y716810I-141J-142D01*
G01Y713318D01*
G02X1628489Y713179I-200J1D01*
G01X1628267Y712951D01*
X1628196Y712920D01*
X1628157Y712918D01*
G03X1626698Y711417I43J-1501D01*
G03X1628200Y709915I1502J0D01*
G03X1628249Y709916I-6J1502D01*
G02X1628391Y709863I6J-200D01*
G01X1628481Y709781D01*
G02X1628546Y709633I-135J-148D01*
G01Y709553D01*
G02X1628487Y709412I-200J1D01*
G01X1619440Y700365D01*
G02X1619299Y700306I-142J141D01*
G01X1609901D01*
G03X1608270Y699631I-1J-2306D01*
G01X1594204Y685565D01*
G02X1594063Y685506I-142J141D01*
G01X1574701D01*
G03X1573070Y684831I-1J-2306D01*
G01X1571869Y683630D01*
G03X1571194Y681999I1631J-1630D01*
G01Y678239D01*
G02X1571135Y678098I-200J1D01*
G01X1571134Y678097D01*
G02X1570987Y678038I-142J141D01*
G01X1570654Y678047D01*
X1570581Y678081D01*
X1570553Y678113D01*
G03X1569434Y678613I-1119J-1002D01*
G03X1567932Y677111I0J-1502D01*
G03X1567951Y676871I1502J-2D01*
G01X1567958Y676827D01*
X1567935Y676743D01*
X1567709Y676477D01*
G02X1567557Y676406I-153J129D01*
G01X1562203D01*
G03X1560572Y675731I-1J-2306D01*
G01X1557306Y672465D01*
G02X1557165Y672406I-142J141D01*
G01X1535508D01*
G02X1535308Y672606I0J200D01*
G01Y674116D01*
G02X1535367Y674258I200J0D01*
G01X1579208Y718099D01*
G02X1579349Y718158I142J-141D01*
G01X1608672D01*
G02X1608813Y718099I-1J-200D01*
G01X1611435Y715477D01*
G02X1611494Y715336I-141J-142D01*
G01Y706668D01*
X1611482Y706621D01*
X1611471Y706599D01*
G03X1611298Y705900I1329J-700D01*
G03X1614302I1502J0D01*
G03X1614129Y706599I-1502J-1D01*
G01X1614118Y706621D01*
X1614106Y706668D01*
Y715960D01*
G03X1613724Y716884I-1306J1D01*
G01X1610220Y720388D01*
G03X1609296Y720770I-923J-924D01*
G01X1607180D01*
G02X1606995Y720894I0J200D01*
G01X1606972Y720951D01*
X1606995Y721068D01*
X1608855Y722928D01*
G02X1609083Y722967I142J-141D01*
G01X1609481Y722774D01*
X1609542Y722663D01*
X1609535Y722599D01*
G03X1609525Y722427I1492J-173D01*
G03X1611027Y723929I1502J0D01*
G03X1610855Y723919I1J-1502D01*
G01X1610791Y723912D01*
X1610680Y723973D01*
X1610487Y724371D01*
G02X1610526Y724599I180J86D01*
G01X1615111Y729184D01*
G03X1615494Y730108I-923J924D01*
G01Y738019D01*
G03X1615111Y738943I-1306J0D01*
G01X1613938Y740116D01*
G02X1613880Y740257I142J141D01*
G01Y752688D01*
G02X1613938Y752829I200J0D01*
G37*
G36*
G01X1600414Y1217993D02*
G03X1600492Y1217990I85J1199D01*
G03X1601693Y1219134I0J1202D01*
G01X1601696Y1219190D01*
X1601763Y1219290D01*
G02X1601765Y1219292I140J-138D01*
G01X1601806Y1219351D01*
X1601851Y1219387D01*
X1601879Y1219398D01*
G03X1602853Y1219959I-1387J3534D01*
G02X1602889Y1219982I125J-156D01*
G03X1603443Y1220535I-526J1081D01*
G02X1603466Y1220572I180J-86D01*
G03X1604285Y1222786I-2975J2359D01*
G01X1604288Y1222867D01*
X1604403Y1222978D01*
X1606424D01*
G02X1606575Y1222909I0J-200D01*
G03X1606668Y1222806I2864J2493D01*
G03X1606737Y1222734I2776J2591D01*
G01X1606738Y1222733D01*
X1606755Y1222715D01*
X1606809Y1222626D01*
X1606816Y1222600D01*
G03X1606887Y1222413I1156J332D01*
G02X1606620Y1222147I-181J-86D01*
G03X1606102Y1222264I-517J-1085D01*
G03Y1219860I0J-1202D01*
G03X1606324Y1219881I-2J1202D01*
G01X1606373Y1219890D01*
X1606466Y1219861D01*
X1606771Y1219556D01*
X1606800Y1219463D01*
X1606791Y1219414D01*
G03X1606770Y1219192I1181J-224D01*
G03X1607972Y1217990I1202J0D01*
G03X1608194Y1218011I-2J1202D01*
G01X1608243Y1218020D01*
X1608336Y1217991D01*
X1608641Y1217686D01*
X1608670Y1217593D01*
X1608661Y1217544D01*
G03X1608640Y1217322I1181J-224D01*
G03X1608661Y1217100I1202J2D01*
G01X1608670Y1217051D01*
X1608641Y1216958D01*
X1608336Y1216653D01*
X1608243Y1216624D01*
X1608194Y1216633D01*
G03X1607972Y1216654I-224J-1181D01*
G03X1609174Y1215452I0J-1202D01*
G03X1609153Y1215674I-1202J-2D01*
G01X1609144Y1215723D01*
X1609173Y1215816D01*
X1609478Y1216121D01*
X1609571Y1216150D01*
X1609620Y1216141D01*
G03X1609842Y1216120I224J1181D01*
G03X1610064Y1216141I-2J1202D01*
G01X1610113Y1216150D01*
X1610206Y1216121D01*
X1610511Y1215816D01*
X1610540Y1215723D01*
X1610531Y1215674D01*
G03X1610510Y1215452I1181J-224D01*
G03X1612914I1202J0D01*
G03X1612893Y1215674I-1202J-2D01*
G01X1612884Y1215723D01*
X1612913Y1215816D01*
X1613218Y1216121D01*
X1613311Y1216150D01*
X1613360Y1216141D01*
G03X1613582Y1216120I224J1181D01*
G03X1613804Y1216141I-2J1202D01*
G01X1613853Y1216150D01*
X1613946Y1216121D01*
X1614251Y1215816D01*
X1614280Y1215723D01*
X1614271Y1215674D01*
G03X1614250Y1215452I1181J-224D01*
G03X1615452Y1216654I1202J0D01*
G03X1615230Y1216633I2J-1202D01*
G01X1615181Y1216624D01*
X1615088Y1216653D01*
X1614783Y1216958D01*
X1614754Y1217051D01*
X1614763Y1217100D01*
G03X1614784Y1217322I-1181J224D01*
G03X1614763Y1217544I-1202J-2D01*
G01X1614754Y1217593D01*
X1614783Y1217686D01*
X1615088Y1217991D01*
X1615181Y1218020D01*
X1615230Y1218011D01*
G03X1615452Y1217990I224J1181D01*
G03X1616654Y1219192I0J1202D01*
G03X1616650Y1219292I-1202J2D01*
G01X1616645Y1219348D01*
X1616695Y1219447D01*
X1616894Y1219572D01*
X1617094Y1219696D01*
X1617205Y1219697D01*
X1617254Y1219668D01*
G03X1617565Y1219502I1941J3263D01*
G01X1617567D01*
X1617628Y1219473D01*
X1617632Y1219470D01*
G03X1617804Y1219398I1552J3466D01*
G01X1617832Y1219387D01*
X1617878Y1219350D01*
X1617955Y1219240D01*
G02X1617990Y1219142I-164J-114D01*
G01X1617991Y1219135D01*
Y1219132D01*
G03X1619192Y1217990I1201J61D01*
G03X1620393Y1219134I0J1202D01*
G01X1620394Y1219163D01*
X1620403Y1219190D01*
X1620412Y1219218D01*
X1620495Y1219338D01*
X1620514Y1219354D01*
G03X1620518Y1219358I-139J143D01*
G02X1620580Y1219397I136J-147D01*
G03X1621132Y1219668I-1392J3533D01*
G02X1621340Y1219666I102J-172D01*
G01X1621412Y1219621D01*
X1621689Y1219447D01*
X1621738Y1219349D01*
X1621734Y1219293D01*
G03X1621731Y1219215I1200J-85D01*
G01Y1219188D01*
G03X1624135I1202J4D01*
G01Y1219215D01*
G03X1624131Y1219290I-1202J-26D01*
G01X1624126Y1219347D01*
X1624176Y1219446D01*
X1624574Y1219696D01*
X1624685Y1219697D01*
X1624734Y1219668D01*
G03X1625130Y1219463I1940J3263D01*
G03X1625292Y1219395I1550J3466D01*
G01X1625321Y1219383D01*
X1625367Y1219346D01*
X1625420Y1219267D01*
G02X1625454Y1219161I-166J-112D01*
G03X1627892I1219J31D01*
G02X1627926Y1219267I200J-6D01*
G01X1628014Y1219397D01*
G02X1628207Y1219484I166J-111D01*
G01X1628250Y1219478D01*
G03X1628590Y1219655I-1581J3452D01*
G01X1628612Y1219668D01*
X1628691Y1219690D01*
X1628723D01*
G02X1628827Y1219661I0J-200D01*
G01X1628855Y1219644D01*
X1629169Y1219447D01*
X1629218Y1219349D01*
X1629214Y1219293D01*
G03X1629211Y1219215I1200J-85D01*
G01Y1219188D01*
G03X1631615I1202J4D01*
G01Y1219193D01*
G03X1631612Y1219283I-1202J5D01*
G02X1631705Y1219478I198J25D01*
G01X1631952Y1219632D01*
X1632054Y1219696D01*
X1632165Y1219697D01*
X1632214Y1219668D01*
G03X1632821Y1219377I1938J3264D01*
G02X1632951Y1219190I-70J-187D01*
G03X1635355I1202J2D01*
G02X1635485Y1219377I200J0D01*
G03X1636092Y1219668I-1331J3555D01*
G01X1636141Y1219697D01*
X1636252Y1219696D01*
X1636602Y1219478D01*
G02X1636695Y1219288I-106J-170D01*
G01X1636694Y1219283D01*
G03X1636691Y1219198I1199J-85D01*
G01Y1219188D01*
G03X1639095I1202J4D01*
G01Y1219193D01*
G03X1639092Y1219283I-1202J5D01*
G01X1639091Y1219288D01*
G02X1639197Y1219486I199J21D01*
G01X1639494Y1219671D01*
G02X1639699Y1219665I97J-175D01*
G03X1639706Y1219661I103J171D01*
G03X1640302Y1219377I1925J3272D01*
G02X1640432Y1219190I-70J-187D01*
G03X1641634Y1217990I1202J2D01*
G03X1642836Y1219191I0J1202D01*
G02X1642966Y1219378I200J0D01*
G03X1643546Y1219653I-1331J3555D01*
G01X1643573Y1219669D01*
X1643627Y1219684D01*
G02X1643787Y1219661I54J-192D01*
G01X1644131Y1219447D01*
X1644181Y1219348D01*
X1644176Y1219291D01*
G03X1644172Y1219192I1198J-98D01*
G03X1645374Y1217990I1202J0D01*
G03X1646576Y1219188I0J1202D01*
G01Y1219193D01*
G03X1646573Y1219283I-1202J5D01*
G02X1646666Y1219478I198J25D01*
G01X1646913Y1219632D01*
X1647015Y1219696D01*
X1647126Y1219697D01*
X1647175Y1219668D01*
G03X1647782Y1219377I1938J3264D01*
G02X1647912Y1219190I-70J-187D01*
G03X1650316I1202J2D01*
G02X1650446Y1219377I200J0D01*
G03X1651053Y1219668I-1331J3555D01*
G01X1651102Y1219697D01*
X1651213Y1219696D01*
X1651563Y1219478D01*
G02X1651656Y1219288I-106J-170D01*
G01X1651655Y1219283D01*
G03X1651652Y1219198I1199J-85D01*
G01Y1219188D01*
G03X1654056I1202J4D01*
G01Y1219193D01*
G03X1654053Y1219283I-1202J5D01*
G02X1654146Y1219478I198J25D01*
G01X1654393Y1219632D01*
X1654495Y1219696D01*
X1654606Y1219697D01*
X1654655Y1219668D01*
G03X1655262Y1219377I1938J3264D01*
G02X1655392Y1219190I-70J-187D01*
G03X1657796I1202J2D01*
G02X1657926Y1219377I200J0D01*
G03X1658533Y1219668I-1331J3555D01*
G01X1658582Y1219697D01*
X1658693Y1219696D01*
X1659043Y1219478D01*
G02X1659136Y1219288I-106J-170D01*
G01X1659135Y1219283D01*
G03X1659132Y1219198I1199J-85D01*
G01Y1219188D01*
G03X1660334Y1217990I1202J4D01*
G03X1661536Y1219192I0J1202D01*
G03X1661515Y1219414I-1202J-2D01*
G01X1661506Y1219463D01*
X1661535Y1219556D01*
X1661840Y1219861D01*
X1661933Y1219890D01*
X1661982Y1219881D01*
G03X1662204Y1219860I224J1181D01*
G03X1663406Y1221062I0J1202D01*
G03X1663398Y1221204I-1202J3D01*
G01X1663392Y1221252D01*
X1663423Y1221339D01*
X1663724Y1221626D01*
X1663813Y1221654D01*
X1663861Y1221646D01*
G03X1664075Y1221628I216J1285D01*
G03X1664289Y1221646I-2J1303D01*
G01X1664336Y1221653D01*
X1664425Y1221626D01*
X1664726Y1221339D01*
X1664757Y1221251D01*
X1664751Y1221204D01*
G03X1664743Y1221062I1194J-139D01*
G03X1667147I1202J0D01*
G03X1667127Y1221283I-1202J3D01*
G01X1667117Y1221332D01*
X1667146Y1221425D01*
X1667451Y1221730D01*
X1667544Y1221758D01*
X1667593Y1221749D01*
G03X1668037I222J1183D01*
G01X1668086Y1221758D01*
X1668179Y1221730D01*
X1668484Y1221425D01*
X1668513Y1221332D01*
X1668503Y1221283D01*
G03X1668483Y1221062I1182J-218D01*
G03X1670887I1202J0D01*
G03X1670879Y1221204I-1202J3D01*
G01X1670873Y1221251D01*
X1670904Y1221339D01*
X1671205Y1221626D01*
X1671294Y1221653D01*
X1671341Y1221646D01*
G03X1671555Y1221628I216J1285D01*
G03X1671769Y1221646I-2J1303D01*
G01X1671816Y1221653D01*
X1671905Y1221626D01*
X1672206Y1221339D01*
X1672237Y1221251D01*
X1672231Y1221204D01*
G03X1672223Y1221062I1194J-139D01*
G03X1674627I1202J0D01*
G03X1674607Y1221283I-1202J3D01*
G01X1674597Y1221332D01*
X1674626Y1221425D01*
X1674931Y1221730D01*
X1675024Y1221758D01*
X1675073Y1221749D01*
G03X1675517I222J1183D01*
G01X1675566Y1221758D01*
X1675659Y1221730D01*
X1675964Y1221425D01*
X1675993Y1221332D01*
X1675983Y1221283D01*
G03X1675963Y1221062I1182J-218D01*
G03X1678367I1202J0D01*
G03X1678359Y1221204I-1202J3D01*
G01X1678353Y1221251D01*
X1678384Y1221339D01*
X1678685Y1221626D01*
X1678774Y1221653D01*
X1678821Y1221646D01*
G03X1679035Y1221628I216J1285D01*
G03X1679249Y1221646I-2J1303D01*
G01X1679296Y1221653D01*
X1679385Y1221626D01*
X1679686Y1221339D01*
X1679717Y1221251D01*
X1679711Y1221204D01*
G03X1679703Y1221062I1194J-139D01*
G03X1682107I1202J0D01*
G03X1682087Y1221283I-1202J3D01*
G01X1682077Y1221332D01*
X1682106Y1221425D01*
X1682411Y1221730D01*
X1682504Y1221758D01*
X1682553Y1221749D01*
G03X1682997I222J1183D01*
G01X1683046Y1221758D01*
X1683139Y1221730D01*
X1683444Y1221425D01*
X1683473Y1221332D01*
X1683463Y1221283D01*
G03X1683443Y1221062I1182J-218D01*
G03X1685847I1202J0D01*
G03X1685839Y1221204I-1202J3D01*
G01X1685833Y1221251D01*
X1685864Y1221339D01*
X1686165Y1221626D01*
X1686254Y1221653D01*
X1686301Y1221646D01*
G03X1686515Y1221628I216J1285D01*
G03X1686729Y1221646I-2J1303D01*
G01X1686776Y1221653D01*
X1686865Y1221626D01*
X1687166Y1221339D01*
X1687197Y1221251D01*
X1687191Y1221204D01*
G03X1687183Y1221062I1194J-139D01*
G03X1689587I1202J0D01*
G03X1689567Y1221283I-1202J3D01*
G01X1689557Y1221332D01*
X1689586Y1221425D01*
X1689891Y1221730D01*
X1689984Y1221759D01*
X1690034Y1221749D01*
G03X1690411Y1221739I220J1183D01*
G01X1690458Y1221745D01*
X1690547Y1221713D01*
X1690836Y1221413D01*
X1690864Y1221323D01*
X1690856Y1221276D01*
G03X1690838Y1221062I1270J-215D01*
G03X1693414I1288J0D01*
G03X1693395Y1221277I-1288J-5D01*
G01X1693387Y1221325D01*
X1693415Y1221415D01*
X1693704Y1221716D01*
X1693794Y1221747D01*
X1693841Y1221741D01*
G03X1694151I155J1193D01*
G01X1694198Y1221747D01*
X1694288Y1221716D01*
X1694577Y1221415D01*
X1694605Y1221325D01*
X1694597Y1221277D01*
G03X1694578Y1221062I1269J-220D01*
G03X1697154I1288J0D01*
G03X1697135Y1221277I-1288J-5D01*
G01X1697127Y1221325D01*
X1697155Y1221415D01*
X1697444Y1221716D01*
X1697534Y1221747D01*
X1697581Y1221741D01*
G03X1697959Y1221752I154J1193D01*
G01X1698007Y1221761D01*
X1698102Y1221732D01*
X1698406Y1221428D01*
X1698435Y1221333D01*
X1698426Y1221285D01*
G03X1698405Y1221062I1181J-224D01*
G03X1699607Y1222264I1202J0D01*
G03X1699385Y1222243I2J-1202D01*
G01X1699336Y1222234D01*
X1699241Y1222263D01*
X1698938Y1222567D01*
X1698908Y1222662D01*
X1698918Y1222711D01*
G03X1698929Y1222786I-1184J212D01*
G01X1698931Y1222800D01*
X1698939Y1222830D01*
G02X1699132Y1222978I193J-52D01*
G01X1724818D01*
G02X1724860Y1222974I2J-200D01*
G01Y1222973D01*
G02X1725012Y1222826I-42J-195D01*
G01X1725013Y1222824D01*
Y1222823D01*
G03X1727937Y1222824I1462J346D01*
G01X1727953Y1222892D01*
X1728062Y1222978D01*
X1750199D01*
G02X1750375Y1222872I0J-200D01*
G01X1750454Y1222725D01*
X1750536Y1222572D01*
G02X1750551Y1222419I-176J-95D01*
G01X1750532Y1222357D01*
X1750516Y1222333D01*
G03X1748312Y1215000I11097J-7333D01*
G03X1761614Y1201698I13302J0D01*
G01X1764722D01*
G02X1764862Y1201641I0J-200D01*
G01X1764863Y1201640D01*
X1770098Y1196405D01*
G03X1770240Y1196346I142J141D01*
G01X1825588D01*
G02X1825728Y1196289I0J-200D01*
G01X1825729Y1196288D01*
X1828490Y1193527D01*
G02X1828492Y1193525I-140J-142D01*
G02X1828549Y1193385I-143J-140D01*
G01Y1116248D01*
G02X1828490Y1116106I-200J0D01*
G01X1820287Y1107903D01*
G03X1820228Y1107761I141J-142D01*
G01Y1023855D01*
G02X1820169Y1023713I-200J0D01*
G01X1799535Y1003079D01*
X1799507Y1003050D01*
X1799433Y1003020D01*
X1569408D01*
G02X1569266Y1003079I0J200D01*
G01X1565394Y1006951D01*
X1565365Y1006979D01*
X1565335Y1007053D01*
Y1029728D01*
G03X1565320Y1029805I-200J1D01*
G01X1565291Y1029873D01*
G02X1565276Y1029950I185J76D01*
G01Y1069714D01*
G02X1565401Y1069899I200J0D01*
G01X1565803Y1070061D01*
X1565922Y1070036D01*
X1565965Y1069991D01*
G03X1566830Y1069624I865J836D01*
G03X1567869Y1070222I0J1202D01*
G02X1567978Y1070311I173J-101D01*
G01X1568096Y1070350D01*
G02X1568237Y1070345I64J-189D01*
G03X1568699Y1070253I461J1110D01*
G03Y1072657I0J1202D01*
G03X1568556Y1072648I4J-1202D01*
G01X1568508Y1072643D01*
X1568421Y1072674D01*
X1568134Y1072975D01*
X1568106Y1073064D01*
X1568114Y1073112D01*
G03X1568132Y1073325I-1285J216D01*
G01Y1073517D01*
G02X1568198Y1073665I200J0D01*
G01X1568449Y1073893D01*
X1568529Y1073919D01*
X1568572Y1073915D01*
G03X1568700Y1073908I134J1281D01*
G03Y1076484I0J1288D01*
G03X1568572Y1076477I6J-1288D01*
G01X1568529Y1076473D01*
X1568449Y1076499D01*
X1568198Y1076727D01*
G02X1568132Y1076875I134J148D01*
G01Y1077066D01*
G03X1568124Y1077213I-1302J3D01*
G01X1568118Y1077259D01*
X1568148Y1077344D01*
X1568433Y1077630D01*
X1568518Y1077661D01*
X1568564Y1077656D01*
G03X1568700Y1077648I144J1280D01*
G03Y1080224I0J1288D01*
G03X1568485Y1080205I5J-1288D01*
G01X1568438Y1080197D01*
X1568348Y1080225D01*
X1568047Y1080515D01*
X1568016Y1080604D01*
X1568022Y1080652D01*
G03X1568032Y1080807I-1192J155D01*
G03X1568011Y1081029I-1202J-2D01*
G01X1568002Y1081078D01*
X1568031Y1081171D01*
X1568336Y1081476D01*
X1568429Y1081505D01*
X1568478Y1081496D01*
G03X1568700Y1081475I224J1181D01*
G03Y1083879I0J1202D01*
G03X1568478Y1083858I2J-1202D01*
G01X1568429Y1083849D01*
X1568336Y1083878D01*
X1568031Y1084183D01*
X1568002Y1084276D01*
X1568011Y1084325D01*
G03X1568032Y1084547I-1181J224D01*
G03X1568011Y1084769I-1202J-2D01*
G01X1568002Y1084818D01*
X1568031Y1084911D01*
X1568336Y1085216D01*
X1568429Y1085245D01*
X1568478Y1085236D01*
G03X1568700Y1085215I224J1181D01*
G03Y1087619I0J1202D01*
G03X1568478Y1087598I2J-1202D01*
G01X1568429Y1087589D01*
X1568336Y1087618D01*
X1568031Y1087923D01*
X1568002Y1088016D01*
X1568011Y1088065D01*
G03X1568032Y1088287I-1181J224D01*
G03X1568011Y1088509I-1202J-2D01*
G01X1568002Y1088558D01*
X1568031Y1088651D01*
X1568336Y1088956D01*
X1568429Y1088985D01*
X1568478Y1088976D01*
G03X1568700Y1088955I224J1181D01*
G03Y1091359I0J1202D01*
G03X1568555Y1091350I2J-1202D01*
G01X1568507Y1091344D01*
X1568420Y1091376D01*
X1568132Y1091676D01*
X1568105Y1091765D01*
X1568112Y1091813D01*
G03X1568130Y1092025I-1284J216D01*
G01Y1092218D01*
G02X1568196Y1092366I200J0D01*
G01X1568448Y1092594D01*
X1568528Y1092620D01*
X1568570Y1092616D01*
G03X1568700Y1092610I124J1281D01*
G03Y1095184I0J1287D01*
G03X1568571Y1095178I-5J-1287D01*
G01X1568528Y1095174D01*
X1568448Y1095200D01*
X1568197Y1095428D01*
G02X1568131Y1095576I134J148D01*
G01Y1095767D01*
G03X1568123Y1095914I-1303J3D01*
G01X1568117Y1095960D01*
X1568147Y1096045D01*
X1568432Y1096332D01*
X1568517Y1096362D01*
X1568563Y1096357D01*
G03X1568700Y1096350I134J1280D01*
G03Y1098924I0J1287D01*
G03X1568485Y1098906I-1J-1287D01*
G01X1568438Y1098899D01*
X1568348Y1098926D01*
X1568047Y1099216D01*
X1568016Y1099305D01*
X1568022Y1099352D01*
G03X1568032Y1099507I-1192J155D01*
G03X1568011Y1099729I-1202J-2D01*
G01X1568002Y1099778D01*
X1568031Y1099871D01*
X1568336Y1100176D01*
X1568429Y1100205D01*
X1568478Y1100196D01*
G03X1568700Y1100175I224J1181D01*
G03Y1102579I0J1202D01*
G03X1568478Y1102558I2J-1202D01*
G01X1568429Y1102549D01*
X1568336Y1102578D01*
X1568031Y1102883D01*
X1568002Y1102976D01*
X1568011Y1103025D01*
G03X1568032Y1103247I-1181J224D01*
G03X1568011Y1103469I-1202J-2D01*
G01X1568002Y1103518D01*
X1568031Y1103611D01*
X1568336Y1103916D01*
X1568429Y1103945D01*
X1568478Y1103936D01*
G03X1568700Y1103915I224J1181D01*
G03Y1106319I0J1202D01*
G03X1568478Y1106298I2J-1202D01*
G01X1568429Y1106289D01*
X1568335Y1106318D01*
X1568031Y1106622D01*
X1568002Y1106717D01*
X1568011Y1106765D01*
G03X1568032Y1106988I-1181J224D01*
G03X1568011Y1107210I-1202J-2D01*
G01X1568002Y1107259D01*
X1568031Y1107352D01*
X1568336Y1107657D01*
X1568429Y1107686D01*
X1568478Y1107677D01*
G03X1568700Y1107656I224J1181D01*
G03Y1110060I0J1202D01*
G03X1568478Y1110039I2J-1202D01*
G01X1568429Y1110030D01*
X1568336Y1110059D01*
X1568031Y1110364D01*
X1568002Y1110457D01*
X1568011Y1110506D01*
G03X1568032Y1110728I-1181J224D01*
G03X1566838Y1111930I-1202J0D01*
G01X1566622Y1111913D01*
G03X1565964Y1111563I208J-1185D01*
G01X1565921Y1111518D01*
X1565803Y1111493D01*
X1565401Y1111655D01*
G02X1565276Y1111840I75J185D01*
G01Y1113356D01*
G02X1565401Y1113541I200J0D01*
G01X1565803Y1113703D01*
X1565922Y1113678D01*
X1565965Y1113633D01*
G03X1566830Y1113266I865J836D01*
G03Y1115670I0J1202D01*
G03X1566649Y1115656I2J-1202D01*
G01X1566634Y1115654D01*
X1566630D01*
G03X1565964Y1115303I200J-1186D01*
G01X1565921Y1115258D01*
X1565803Y1115233D01*
X1565401Y1115395D01*
G02X1565276Y1115580I75J185D01*
G01Y1117096D01*
G02X1565401Y1117281I200J0D01*
G01X1565803Y1117443D01*
X1565922Y1117418D01*
X1565965Y1117373D01*
G03X1566830Y1117006I865J836D01*
G03Y1119410I0J1202D01*
G03X1566649Y1119396I2J-1202D01*
G01X1566634Y1119394D01*
X1566630D01*
G03X1565964Y1119043I200J-1186D01*
G01X1565921Y1118998D01*
X1565803Y1118973D01*
X1565401Y1119135D01*
G02X1565276Y1119320I75J185D01*
G01Y1120836D01*
G02X1565401Y1121021I200J0D01*
G01X1565803Y1121183D01*
X1565922Y1121158D01*
X1565965Y1121113D01*
G03X1566830Y1120746I865J836D01*
G03Y1123150I0J1202D01*
G03X1566649Y1123136I2J-1202D01*
G01X1566634Y1123134D01*
X1566630D01*
G03X1565964Y1122783I200J-1186D01*
G01X1565921Y1122738D01*
X1565803Y1122713D01*
X1565401Y1122875D01*
G02X1565276Y1123060I75J185D01*
G01Y1124576D01*
G02X1565401Y1124761I200J0D01*
G01X1565803Y1124923D01*
X1565922Y1124898D01*
X1565965Y1124853D01*
G03X1566830Y1124486I865J836D01*
G03Y1126890I0J1202D01*
G03X1566649Y1126876I2J-1202D01*
G01X1566634Y1126874D01*
X1566630D01*
G03X1565964Y1126523I200J-1186D01*
G01X1565921Y1126478D01*
X1565803Y1126453D01*
X1565401Y1126615D01*
G02X1565276Y1126800I75J185D01*
G01Y1127529D01*
G03X1565217Y1127671I-200J0D01*
G01X1564953Y1127935D01*
G02X1564894Y1128077I141J142D01*
G01Y1130370D01*
G02X1565094Y1130570I200J0D01*
G01X1565632D01*
G03X1565761Y1130577I-1J1202D01*
G01X1565810Y1130582D01*
X1565858Y1130563D01*
G02X1565970Y1130305I-74J-185D01*
G01X1565948Y1130246D01*
X1565925Y1130220D01*
G03X1565628Y1129429I905J-791D01*
G03X1568032I1202J0D01*
G03X1567735Y1130220I-1202J0D01*
G01X1567712Y1130246D01*
X1567540Y1130688D01*
G03X1567895Y1130577I532J1077D01*
G01X1567899D01*
X1567909Y1130576D01*
G03X1568028Y1130570I120J1196D01*
G01X1569363D01*
G03X1570244Y1130955I0J1201D01*
G01X1570273Y1130986D01*
X1570384Y1131034D01*
G02X1570464Y1131051I81J-183D01*
G01X1570658D01*
G02X1570699Y1131047I1J-200D01*
G01X1570740Y1131038D01*
X1570762Y1131034D01*
X1570869Y1130986D01*
X1570897Y1130956D01*
G03X1571779Y1130570I882J815D01*
G01X1573103D01*
G03X1573984Y1130955I0J1201D01*
G01X1574013Y1130986D01*
X1574124Y1131034D01*
G02X1574204Y1131051I81J-183D01*
G01X1574398D01*
G02X1574439Y1131047I1J-200D01*
G01X1574480Y1131038D01*
X1574502Y1131034D01*
X1574609Y1130986D01*
X1574637Y1130956D01*
G03X1575519Y1130570I882J815D01*
G01X1576843D01*
G03X1577724Y1130955I0J1201D01*
G01X1577753Y1130986D01*
X1577864Y1131034D01*
G02X1577944Y1131051I81J-183D01*
G01X1578138D01*
G02X1578179Y1131047I1J-200D01*
G01X1578220Y1131038D01*
X1578242Y1131034D01*
X1578349Y1130986D01*
X1578377Y1130956D01*
G03X1579259Y1130570I882J815D01*
G01X1580583D01*
G03X1581464Y1130955I0J1201D01*
G01X1581493Y1130986D01*
X1581604Y1131034D01*
G02X1581684Y1131051I81J-183D01*
G01X1581878D01*
G02X1581919Y1131047I1J-200D01*
G01X1581960Y1131038D01*
X1581982Y1131034D01*
X1582089Y1130986D01*
X1582117Y1130956D01*
G03X1582999Y1130570I882J815D01*
G01X1584323D01*
G03X1585204Y1130955I0J1201D01*
G01X1585233Y1130986D01*
X1585344Y1131034D01*
G02X1585424Y1131051I81J-183D01*
G01X1585618D01*
G02X1585659Y1131047I1J-200D01*
G01X1585700Y1131038D01*
X1585722Y1131034D01*
X1585829Y1130986D01*
X1585857Y1130956D01*
G03X1586739Y1130570I882J815D01*
G01X1588063D01*
G03X1588944Y1130955I0J1201D01*
G01X1588973Y1130986D01*
X1589084Y1131034D01*
G02X1589164Y1131051I81J-183D01*
G01X1589358D01*
G02X1589399Y1131047I1J-200D01*
G01X1589440Y1131038D01*
X1589462Y1131034D01*
X1589569Y1130986D01*
X1589597Y1130956D01*
G03X1590479Y1130570I882J815D01*
G01X1591803D01*
G03X1592684Y1130955I0J1201D01*
G01X1592713Y1130986D01*
X1592824Y1131034D01*
G02X1592904Y1131051I81J-183D01*
G01X1593098D01*
G02X1593139Y1131047I1J-200D01*
G01X1593180Y1131038D01*
X1593202Y1131034D01*
X1593309Y1130986D01*
X1593337Y1130956D01*
G03X1594219Y1130570I882J815D01*
G01X1595544D01*
G03X1596425Y1130955I0J1201D01*
G01X1596454Y1130986D01*
X1596565Y1131034D01*
G02X1596645Y1131051I81J-183D01*
G01X1596839D01*
G02X1596880Y1131047I1J-200D01*
G01X1596921Y1131038D01*
X1596943Y1131034D01*
X1597050Y1130986D01*
X1597078Y1130956D01*
G03X1597960Y1130570I882J815D01*
G01X1599043D01*
G03X1600053Y1131122I-1J1201D01*
G01X1600231Y1131396D01*
G02X1600414Y1131487I168J-108D01*
G01X1600425Y1131486D01*
X1600431Y1131485D01*
G03X1600589Y1131475I155J1192D01*
G01X1600591D01*
G03X1600749Y1131485I3J1202D01*
G01X1600755Y1131486D01*
X1600766Y1131487D01*
G02X1600949Y1131396I15J-199D01*
G01X1601127Y1131122D01*
G03X1602137Y1130570I1011J649D01*
G01X1610504D01*
G03X1611385Y1130955I0J1201D01*
G01X1611414Y1130986D01*
X1611525Y1131034D01*
G02X1611605Y1131051I81J-183D01*
G01X1611799D01*
G02X1611840Y1131047I1J-200D01*
G01X1611881Y1131038D01*
X1611903Y1131034D01*
X1612010Y1130986D01*
X1612038Y1130956D01*
G03X1612920Y1130570I882J815D01*
G01X1614244D01*
G03X1615125Y1130955I0J1201D01*
G01X1615154Y1130986D01*
X1615265Y1131034D01*
G02X1615345Y1131051I81J-183D01*
G01X1615539D01*
G02X1615580Y1131047I1J-200D01*
G01X1615621Y1131038D01*
X1615643Y1131034D01*
X1615750Y1130986D01*
X1615778Y1130956D01*
G03X1616660Y1130570I882J815D01*
G01X1617985D01*
G03X1618866Y1130955I0J1201D01*
G01X1618895Y1130986D01*
X1619006Y1131034D01*
G02X1619086Y1131051I81J-183D01*
G01X1619280D01*
G02X1619321Y1131047I1J-200D01*
G01X1619362Y1131038D01*
X1619384Y1131034D01*
X1619491Y1130986D01*
X1619519Y1130956D01*
G03X1620401Y1130570I882J815D01*
G01X1621725D01*
G03X1622606Y1130955I0J1201D01*
G01X1622635Y1130986D01*
X1622746Y1131034D01*
G02X1622826Y1131051I81J-183D01*
G01X1623020D01*
G02X1623061Y1131047I1J-200D01*
G01X1623102Y1131038D01*
X1623124Y1131034D01*
X1623231Y1130986D01*
X1623259Y1130956D01*
G03X1624141Y1130570I882J815D01*
G01X1625465D01*
G03X1626346Y1130955I0J1201D01*
G01X1626375Y1130986D01*
X1626486Y1131034D01*
G02X1626566Y1131051I81J-183D01*
G01X1626760D01*
G02X1626801Y1131047I1J-200D01*
G01X1626842Y1131038D01*
X1626864Y1131034D01*
X1626971Y1130986D01*
X1626999Y1130956D01*
G03X1627881Y1130570I882J815D01*
G01X1629205D01*
G03X1630086Y1130955I0J1201D01*
G01X1630115Y1130986D01*
X1630226Y1131034D01*
G02X1630306Y1131051I81J-183D01*
G01X1630500D01*
G02X1630541Y1131047I1J-200D01*
G01X1630582Y1131038D01*
X1630604Y1131034D01*
X1630711Y1130986D01*
X1630739Y1130956D01*
G03X1631621Y1130570I882J815D01*
G01X1632945D01*
G03X1633826Y1130955I0J1201D01*
G01X1633855Y1130986D01*
X1633966Y1131034D01*
G02X1634046Y1131051I81J-183D01*
G01X1634240D01*
G02X1634281Y1131047I1J-200D01*
G01X1634322Y1131038D01*
X1634344Y1131034D01*
X1634451Y1130986D01*
X1634479Y1130956D01*
G03X1635361Y1130570I882J815D01*
G01X1636685D01*
G03X1637566Y1130955I0J1201D01*
G01X1637595Y1130986D01*
X1637706Y1131034D01*
G02X1637786Y1131051I81J-183D01*
G01X1637980D01*
G02X1638021Y1131047I1J-200D01*
G01X1638062Y1131038D01*
X1638084Y1131034D01*
X1638191Y1130986D01*
X1638219Y1130956D01*
G03X1639101Y1130570I882J815D01*
G01X1640211D01*
G02X1640382Y1130474I0J-200D01*
G01X1640560Y1130181D01*
G02X1640566Y1129984I-171J-104D01*
G01X1640560Y1129972D01*
X1640553Y1129957D01*
X1640552Y1129955D01*
X1640551Y1129953D01*
G03X1640431Y1129429I1082J-524D01*
G01Y1129408D01*
G03X1641633Y1128227I1202J21D01*
G03X1642835Y1129429I0J1202D01*
G03X1642694Y1129993I-1202J-1D01*
G01X1642687Y1130007D01*
G03X1641874Y1130607I-1054J-578D01*
G01X1641871D01*
X1641860Y1130610D01*
X1641843Y1130615D01*
G02X1641705Y1130758I56J192D01*
G01Y1130759D01*
G02X1641756Y1130947I194J48D01*
G01X1641793Y1130985D01*
X1641794Y1130986D01*
G03X1642140Y1131940I-851J848D01*
G02X1642238Y1132131I199J18D01*
G03X1642835Y1133163I-605J1039D01*
G01Y1133167D01*
G03Y1133173I-1202J3D01*
G01Y1133194D01*
G03X1642827Y1133308I-1202J-27D01*
G03X1642710Y1133704I-1194J-138D01*
G01X1642695Y1133734D01*
X1642686Y1133800D01*
X1642693Y1133834D01*
G02X1642756Y1133942I195J-42D01*
G01X1642795Y1133978D01*
G03X1643186Y1134863I-811J887D01*
G01Y1135215D01*
G03X1642795Y1136100I-1202J-2D01*
G01X1642777Y1136116D01*
G02X1642710Y1136265I133J149D01*
G01Y1136373D01*
X1642728Y1136413D01*
G03X1642835Y1136909I-1096J496D01*
G01Y1136949D01*
X1642834Y1136956D01*
Y1136962D01*
G03X1642803Y1137189I-1201J-48D01*
G01X1642802Y1137190D01*
G03X1642710Y1137443I-1169J-282D01*
G01X1642697Y1137468D01*
X1642687Y1137523D01*
X1642690Y1137554D01*
G02X1642756Y1137682I199J-21D01*
G01X1642795Y1137718D01*
G03X1643186Y1138603I-811J887D01*
G01Y1138955D01*
G03X1642912Y1139714I-1201J-5D01*
G01X1642890Y1139741D01*
X1642864Y1139812D01*
X1642866Y1139851D01*
Y1139854D01*
X1642880Y1140124D01*
G02X1642938Y1140255I200J-10D01*
G01X1643494Y1140811D01*
G02X1643705Y1140857I141J-141D01*
G01X1644045Y1140730D01*
G02X1644175Y1140558I-69J-187D01*
G03X1645374Y1139447I1199J91D01*
G03X1646576Y1140649I0J1202D01*
G03X1645381Y1141851I-1202J0D01*
G01X1645371D01*
G03X1644953Y1141775I3J-1202D01*
G01X1644907Y1141758D01*
X1644810Y1141770D01*
X1644498Y1141985D01*
G02X1644412Y1142149I114J164D01*
G01Y1142889D01*
G02X1644498Y1143053I200J0D01*
G01X1644807Y1143266D01*
X1644904Y1143278D01*
X1644950Y1143261D01*
G03X1645373Y1143184I424J1128D01*
G01X1645374D01*
G03Y1145594I0J1205D01*
G01X1645373D01*
G03X1644950Y1145517I1J-1205D01*
G01X1644904Y1145500D01*
X1644807Y1145512D01*
X1644498Y1145725D01*
G02X1644412Y1145889I114J164D01*
G01Y1146629D01*
G02X1644498Y1146793I200J0D01*
G01X1644807Y1147006D01*
X1644904Y1147018D01*
X1644950Y1147001D01*
G03X1645373Y1146924I424J1128D01*
G01X1645374D01*
G03Y1149334I0J1205D01*
G01X1645373D01*
G03X1644950Y1149257I1J-1205D01*
G01X1644904Y1149240D01*
X1644807Y1149252D01*
X1644498Y1149465D01*
G02X1644412Y1149629I114J164D01*
G01Y1150369D01*
G02X1644498Y1150533I200J0D01*
G01X1644807Y1150746D01*
X1644904Y1150758D01*
X1644950Y1150741D01*
G03X1645373Y1150664I424J1128D01*
G01X1645374D01*
G03Y1153074I0J1205D01*
G01X1645373D01*
G03X1644950Y1152997I1J-1205D01*
G01X1644904Y1152980D01*
X1644807Y1152992D01*
X1644498Y1153205D01*
G02X1644412Y1153369I114J164D01*
G01Y1154110D01*
G02X1644498Y1154274I200J0D01*
G01X1644807Y1154487D01*
X1644904Y1154499D01*
X1644950Y1154482D01*
G03X1645373Y1154405I424J1128D01*
G01X1645374D01*
G03Y1156815I0J1205D01*
G01X1645373D01*
G03X1644950Y1156738I1J-1205D01*
G01X1644904Y1156721D01*
X1644807Y1156733D01*
X1644498Y1156946D01*
G02X1644412Y1157110I114J164D01*
G01Y1157850D01*
G02X1644498Y1158014I200J0D01*
G01X1644807Y1158227D01*
X1644904Y1158239D01*
X1644950Y1158222D01*
G03X1645373Y1158145I424J1128D01*
G01X1645374D01*
G03Y1160555I0J1205D01*
G01X1645373D01*
G03X1644950Y1160478I1J-1205D01*
G01X1644904Y1160461D01*
X1644807Y1160473D01*
X1644498Y1160686D01*
G02X1644412Y1160850I114J164D01*
G01Y1165330D01*
G02X1644498Y1165494I200J0D01*
G01X1644807Y1165707D01*
X1644904Y1165719D01*
X1644950Y1165702D01*
G03X1645373Y1165625I424J1128D01*
G01X1645374D01*
G03Y1168035I0J1205D01*
G01X1645373D01*
G03X1644950Y1167958I1J-1205D01*
G01X1644904Y1167941D01*
X1644807Y1167953D01*
X1644498Y1168166D01*
G02X1644412Y1168330I114J164D01*
G01Y1169070D01*
G02X1644498Y1169234I200J0D01*
G01X1644807Y1169447D01*
X1644904Y1169459D01*
X1644950Y1169442D01*
G03X1645373Y1169365I424J1128D01*
G01X1645374D01*
G03Y1171775I0J1205D01*
G01X1645373D01*
G03X1644950Y1171698I1J-1205D01*
G01X1644904Y1171681D01*
X1644807Y1171693D01*
X1644498Y1171906D01*
G02X1644412Y1172070I114J164D01*
G01Y1172810D01*
G02X1644498Y1172974I200J0D01*
G01X1644807Y1173187D01*
X1644904Y1173199D01*
X1644950Y1173182D01*
G03X1645373Y1173105I424J1128D01*
G01X1645374D01*
G03Y1175515I0J1205D01*
G03X1644349Y1174944I0J-1205D01*
G01X1644338Y1174926D01*
X1644305Y1174892D01*
G02X1644186Y1174833I-143J139D01*
G01X1643841Y1174790D01*
X1643757Y1174818D01*
X1643724Y1174848D01*
G03X1643720Y1174852I-143J-139D01*
G01X1643716Y1174856D01*
X1642176Y1176396D01*
G02X1642119Y1176562I141J141D01*
G01X1642129Y1176643D01*
X1642162Y1176919D01*
X1642212Y1176996D01*
X1642252Y1177020D01*
G03X1642835Y1178051I-620J1031D01*
G03X1641633Y1179253I-1202J0D01*
G03X1640431Y1178054I0J-1202D01*
G01Y1178051D01*
G03X1640440Y1177904I1202J0D01*
G01X1640442Y1177891D01*
Y1177879D01*
G02X1640242Y1177679I-200J0D01*
G01X1640224D01*
X1640188Y1177664D01*
G03X1640123Y1177621I76J-185D01*
G01X1640083Y1177581D01*
G02X1639941Y1177522I-142J141D01*
G01X1639490D01*
G02X1639412Y1177538I0J200D01*
G01X1639371Y1177555D01*
X1639115Y1177834D01*
X1639088Y1177912D01*
X1639091Y1177954D01*
G03X1639095Y1178051I-1198J98D01*
G03X1636691I-1202J0D01*
G03X1636695Y1177954I1202J1D01*
G01X1636698Y1177912D01*
X1636671Y1177834D01*
X1636444Y1177587D01*
X1636416Y1177556D01*
X1636339Y1177522D01*
X1635750D01*
G02X1635672Y1177538I0J200D01*
G01X1635631Y1177555D01*
X1635375Y1177834D01*
X1635348Y1177912D01*
X1635351Y1177954D01*
G03X1635355Y1178051I-1198J98D01*
G03X1632951I-1202J0D01*
G03X1632955Y1177954I1202J1D01*
G01X1632958Y1177912D01*
X1632931Y1177834D01*
X1632704Y1177587D01*
X1632676Y1177556D01*
X1632599Y1177522D01*
X1632010D01*
G02X1631932Y1177538I0J200D01*
G01X1631891Y1177555D01*
X1631635Y1177834D01*
X1631608Y1177912D01*
X1631611Y1177954D01*
G03X1631615Y1178051I-1198J98D01*
G03X1629211I-1202J0D01*
G03X1629215Y1177954I1202J1D01*
G01X1629218Y1177912D01*
X1629191Y1177834D01*
X1628964Y1177587D01*
X1628936Y1177556D01*
X1628859Y1177522D01*
X1628270D01*
G02X1628192Y1177538I0J200D01*
G01X1628151Y1177555D01*
X1627895Y1177834D01*
X1627868Y1177912D01*
X1627871Y1177954D01*
G03X1627875Y1178051I-1198J98D01*
G03X1625471I-1202J0D01*
G03X1625475Y1177954I1202J1D01*
G01X1625478Y1177912D01*
X1625451Y1177834D01*
X1625224Y1177587D01*
X1625196Y1177556D01*
X1625119Y1177522D01*
X1624530D01*
G02X1624452Y1177538I0J200D01*
G01X1624411Y1177555D01*
X1624155Y1177834D01*
X1624128Y1177912D01*
X1624131Y1177954D01*
G03X1624135Y1178051I-1198J98D01*
G03X1621731I-1202J0D01*
G03X1621735Y1177954I1202J1D01*
G01X1621738Y1177912D01*
X1621711Y1177834D01*
X1621484Y1177587D01*
X1621456Y1177556D01*
X1621379Y1177522D01*
X1620790D01*
G02X1620712Y1177538I0J200D01*
G01X1620671Y1177555D01*
X1620415Y1177834D01*
X1620388Y1177912D01*
X1620391Y1177954D01*
G03X1620395Y1178051I-1198J98D01*
G03X1617991I-1202J0D01*
G03X1617995Y1177954I1202J1D01*
G01X1617998Y1177912D01*
X1617971Y1177834D01*
X1617744Y1177587D01*
X1617716Y1177556D01*
X1617639Y1177522D01*
X1617049D01*
G02X1616971Y1177538I0J200D01*
G01X1616930Y1177555D01*
X1616674Y1177834D01*
X1616647Y1177912D01*
X1616650Y1177954D01*
G03X1616654Y1178051I-1198J98D01*
G03X1614250I-1202J0D01*
G03X1614254Y1177954I1202J1D01*
G01X1614257Y1177912D01*
X1614230Y1177834D01*
X1614003Y1177587D01*
X1613975Y1177556D01*
X1613898Y1177522D01*
X1613309D01*
G02X1613231Y1177538I0J200D01*
G01X1613190Y1177555D01*
X1612934Y1177834D01*
X1612907Y1177912D01*
X1612910Y1177954D01*
G03X1612914Y1178051I-1198J98D01*
G03X1610510I-1202J0D01*
G03X1610514Y1177954I1202J1D01*
G01X1610517Y1177912D01*
X1610490Y1177834D01*
X1610263Y1177587D01*
X1610235Y1177556D01*
X1610158Y1177522D01*
X1609569D01*
G02X1609491Y1177538I0J200D01*
G01X1609450Y1177555D01*
X1609194Y1177834D01*
X1609167Y1177912D01*
X1609170Y1177954D01*
G03X1609174Y1178051I-1198J98D01*
G03X1606770I-1202J0D01*
G03X1606774Y1177954I1202J1D01*
G01X1606777Y1177912D01*
X1606750Y1177834D01*
X1606523Y1177587D01*
X1606495Y1177556D01*
X1606418Y1177522D01*
X1602089D01*
G02X1602011Y1177538I0J200D01*
G01X1601970Y1177555D01*
X1601714Y1177834D01*
X1601687Y1177912D01*
X1601690Y1177954D01*
G03X1601694Y1178051I-1198J98D01*
G03X1599290I-1202J0D01*
G03X1599294Y1177954I1202J1D01*
G01X1599297Y1177912D01*
X1599270Y1177834D01*
X1599043Y1177587D01*
X1599015Y1177556D01*
X1598938Y1177522D01*
X1598349D01*
G02X1598271Y1177538I0J200D01*
G01X1598230Y1177555D01*
X1597974Y1177834D01*
X1597947Y1177912D01*
X1597950Y1177954D01*
G03X1597954Y1178051I-1198J98D01*
G03X1595550I-1202J0D01*
G03X1595554Y1177954I1202J1D01*
G01X1595557Y1177912D01*
X1595530Y1177834D01*
X1595303Y1177587D01*
X1595275Y1177556D01*
X1595198Y1177522D01*
X1594608D01*
G02X1594530Y1177538I0J200D01*
G01X1594489Y1177555D01*
X1594233Y1177834D01*
X1594206Y1177912D01*
X1594209Y1177954D01*
G03X1594213Y1178051I-1198J98D01*
G03X1591809I-1202J0D01*
G03X1591813Y1177954I1202J1D01*
G01X1591816Y1177912D01*
X1591789Y1177834D01*
X1591562Y1177587D01*
X1591534Y1177556D01*
X1591457Y1177522D01*
X1590868D01*
G02X1590790Y1177538I0J200D01*
G01X1590749Y1177555D01*
X1590493Y1177834D01*
X1590466Y1177912D01*
X1590469Y1177954D01*
G03X1590473Y1178051I-1198J98D01*
G03X1588069I-1202J0D01*
G03X1588073Y1177954I1202J1D01*
G01X1588076Y1177912D01*
X1588049Y1177834D01*
X1587822Y1177587D01*
X1587794Y1177556D01*
X1587717Y1177522D01*
X1587128D01*
G02X1587050Y1177538I0J200D01*
G01X1587009Y1177555D01*
X1586753Y1177834D01*
X1586726Y1177912D01*
X1586729Y1177954D01*
G03X1586733Y1178051I-1198J98D01*
G03X1584329I-1202J0D01*
G03X1584333Y1177954I1202J1D01*
G01X1584336Y1177912D01*
X1584309Y1177834D01*
X1584082Y1177587D01*
X1584054Y1177556D01*
X1583977Y1177522D01*
X1583388D01*
G02X1583310Y1177538I0J200D01*
G01X1583269Y1177555D01*
X1583013Y1177834D01*
X1582986Y1177912D01*
X1582989Y1177954D01*
G03X1582993Y1178051I-1198J98D01*
G03X1580589I-1202J0D01*
G03X1580593Y1177954I1202J1D01*
G01X1580596Y1177912D01*
X1580569Y1177834D01*
X1580342Y1177587D01*
X1580314Y1177556D01*
X1580237Y1177522D01*
X1579648D01*
G02X1579570Y1177538I0J200D01*
G01X1579529Y1177555D01*
X1579273Y1177834D01*
X1579246Y1177912D01*
X1579249Y1177954D01*
G03X1579253Y1178051I-1198J98D01*
G03X1576849I-1202J0D01*
G03X1576853Y1177954I1202J1D01*
G01X1576856Y1177912D01*
X1576829Y1177834D01*
X1576602Y1177587D01*
X1576574Y1177556D01*
X1576497Y1177522D01*
X1575908D01*
G02X1575830Y1177538I0J200D01*
G01X1575789Y1177555D01*
X1575533Y1177834D01*
X1575506Y1177912D01*
X1575509Y1177954D01*
G03X1575513Y1178051I-1198J98D01*
G03X1573109I-1202J0D01*
G03X1573113Y1177954I1202J1D01*
G01X1573116Y1177912D01*
X1573089Y1177834D01*
X1572862Y1177587D01*
X1572834Y1177556D01*
X1572757Y1177522D01*
X1572168D01*
G02X1572090Y1177538I0J200D01*
G01X1572049Y1177555D01*
X1571793Y1177834D01*
X1571766Y1177912D01*
X1571769Y1177954D01*
G03X1571773Y1178051I-1198J98D01*
G03X1570580Y1179253I-1202J0D01*
G01X1570573D01*
G03X1569819Y1178989I-2J-1202D01*
G01X1569793Y1178968D01*
X1569731Y1178945D01*
G02X1569502Y1179013I-69J188D01*
G01X1569463Y1179066D01*
X1569462Y1179197D01*
X1569466Y1179203D01*
Y1179221D01*
Y1180351D01*
G02X1569536Y1180504I200J1D01*
G01X1569552Y1180517D01*
X1569816Y1180681D01*
G02X1569921Y1180711I105J-170D01*
G01X1570041D01*
X1570080Y1180694D01*
G03X1570509Y1180591I490J1097D01*
G03X1570558Y1180589I74J1200D01*
G01X1570579D01*
G03X1571773Y1181791I-8J1202D01*
G03X1570576Y1182993I-1202J0D01*
G01X1570565D01*
G03X1570081Y1182888I7J-1202D01*
G01X1570042Y1182871D01*
X1569920D01*
G02X1569814Y1182902I1J200D01*
G01X1569539Y1183074D01*
X1569519Y1183099D01*
X1569518Y1183100D01*
X1569493Y1183127D01*
X1569466Y1183196D01*
Y1184361D01*
G03X1569464Y1184436I-1201J5D01*
G01X1569462Y1184476D01*
X1569475Y1184514D01*
G02X1569730Y1184636I189J-67D01*
G01X1569791Y1184615D01*
X1569817Y1184593D01*
G03X1570570Y1184329I752J940D01*
G01X1570603D01*
G03X1571741Y1185809I-32J1202D01*
G01X1571739Y1185815D01*
X1571737Y1185823D01*
G03X1571365Y1186434I-1166J-291D01*
G03X1570792Y1186713I-794J-903D01*
G01X1570786Y1186714D01*
X1570776Y1186716D01*
G03X1570585Y1186733I-202J-1185D01*
G01X1570573D01*
G03X1570569I-2J-1202D01*
G01X1570552D01*
G03X1569819Y1186469I19J-1202D01*
G01X1569793Y1186448D01*
X1569731Y1186425D01*
G02X1569502Y1186493I-69J188D01*
G01X1569463Y1186546D01*
X1569462Y1186677D01*
X1569466Y1186683D01*
Y1186701D01*
Y1187433D01*
G03X1569114Y1188282I-1201J-1D01*
G01X1568521Y1188874D01*
G03X1568339Y1189025I-855J-845D01*
G01X1568331Y1189030D01*
X1568305Y1189052D01*
G02X1568286Y1189070I128J154D01*
G01X1568273Y1189084D01*
G02X1568220Y1189219I147J136D01*
G01Y1192272D01*
G03X1568205Y1192348I-200J0D01*
G01X1568193Y1192377D01*
G02X1568178Y1192453I185J76D01*
G01Y1219465D01*
G02X1568242Y1219611I200J-1D01*
G01X1568488Y1219840D01*
X1568566Y1219867D01*
X1568608Y1219863D01*
G03X1568700Y1219860I85J1199D01*
G03X1569902Y1221062I0J1202D01*
G03X1569894Y1221204I-1202J3D01*
G01X1569888Y1221251D01*
X1569919Y1221339D01*
X1570220Y1221626D01*
X1570309Y1221653D01*
X1570356Y1221646D01*
G03X1570570Y1221628I216J1285D01*
G03X1570784Y1221646I-2J1303D01*
G01X1570832Y1221654D01*
X1570921Y1221626D01*
X1571222Y1221339D01*
X1571253Y1221252D01*
X1571247Y1221204D01*
G03X1571239Y1221062I1194J-139D01*
G03X1573643I1202J0D01*
G03X1573623Y1221283I-1202J3D01*
G01X1573613Y1221332D01*
X1573642Y1221425D01*
X1573947Y1221730D01*
X1574040Y1221758D01*
X1574089Y1221749D01*
G03X1574533I222J1183D01*
G01X1574582Y1221758D01*
X1574675Y1221730D01*
X1574980Y1221425D01*
X1575009Y1221332D01*
X1574999Y1221283D01*
G03X1574979Y1221062I1182J-218D01*
G03X1577383I1202J0D01*
G03X1577375Y1221204I-1202J3D01*
G01X1577369Y1221251D01*
X1577400Y1221339D01*
X1577701Y1221626D01*
X1577790Y1221653D01*
X1577837Y1221646D01*
G03X1578050Y1221628I216J1285D01*
G03X1578264Y1221646I-2J1303D01*
G01X1578312Y1221654D01*
X1578401Y1221626D01*
X1578702Y1221339D01*
X1578733Y1221252D01*
X1578727Y1221204D01*
G03X1578719Y1221062I1194J-139D01*
G03X1581123I1202J0D01*
G03X1581103Y1221283I-1202J3D01*
G01X1581093Y1221332D01*
X1581122Y1221425D01*
X1581427Y1221730D01*
X1581520Y1221758D01*
X1581569Y1221749D01*
G03X1582013I222J1183D01*
G01X1582062Y1221758D01*
X1582155Y1221730D01*
X1582460Y1221425D01*
X1582489Y1221332D01*
X1582479Y1221283D01*
G03X1582459Y1221062I1182J-218D01*
G03X1584863I1202J0D01*
G03X1584855Y1221204I-1202J3D01*
G01X1584849Y1221251D01*
X1584880Y1221339D01*
X1585181Y1221626D01*
X1585270Y1221653D01*
X1585317Y1221646D01*
G03X1585530Y1221628I216J1285D01*
G03X1585744Y1221646I-2J1303D01*
G01X1585792Y1221654D01*
X1585881Y1221626D01*
X1586182Y1221339D01*
X1586213Y1221252D01*
X1586207Y1221204D01*
G03X1586199Y1221062I1194J-139D01*
G03X1588603I1202J0D01*
G03X1588583Y1221283I-1202J3D01*
G01X1588573Y1221332D01*
X1588602Y1221425D01*
X1588907Y1221730D01*
X1589000Y1221758D01*
X1589049Y1221749D01*
G03X1589493I222J1183D01*
G01X1589542Y1221758D01*
X1589635Y1221730D01*
X1589940Y1221425D01*
X1589969Y1221332D01*
X1589959Y1221283D01*
G03X1589939Y1221062I1182J-218D01*
G03X1591141Y1219860I1202J0D01*
G03X1591363Y1219881I-2J1202D01*
G01X1591412Y1219890D01*
X1591505Y1219861D01*
X1591810Y1219556D01*
X1591839Y1219463D01*
X1591830Y1219414D01*
G03X1591809Y1219192I1181J-224D01*
G03X1591830Y1218970I1202J2D01*
G01X1591839Y1218921D01*
X1591810Y1218828D01*
X1591505Y1218523D01*
X1591412Y1218494D01*
X1591363Y1218503D01*
G03X1591141Y1218524I-224J-1181D01*
G03X1589939Y1217322I0J-1202D01*
G03X1589960Y1217100I1202J2D01*
G01X1589969Y1217051D01*
X1589940Y1216958D01*
X1589635Y1216653D01*
X1589542Y1216624D01*
X1589493Y1216633D01*
G03X1589271Y1216654I-224J-1181D01*
G03X1590473Y1215452I0J-1202D01*
G03X1590452Y1215674I-1202J-2D01*
G01X1590443Y1215723D01*
X1590472Y1215816D01*
X1590777Y1216121D01*
X1590870Y1216150D01*
X1590919Y1216141D01*
G03X1591141Y1216120I224J1181D01*
G03X1591364Y1216141I-1J1202D01*
G01X1591412Y1216150D01*
X1591507Y1216121D01*
X1591811Y1215817D01*
X1591840Y1215723D01*
X1591831Y1215674D01*
G03X1591810Y1215452I1181J-224D01*
G03X1593012Y1216654I1202J0D01*
G03X1592789Y1216633I1J-1202D01*
G01X1592741Y1216624D01*
X1592646Y1216653D01*
X1592342Y1216957D01*
X1592313Y1217051D01*
X1592322Y1217100D01*
G03X1592343Y1217322I-1181J224D01*
G03X1592322Y1217544I-1202J-2D01*
G01X1592313Y1217593D01*
X1592342Y1217686D01*
X1592647Y1217991D01*
X1592740Y1218020D01*
X1592789Y1218011D01*
G03X1593011Y1217990I224J1181D01*
G03X1594213Y1219192I0J1202D01*
G03X1594192Y1219414I-1202J-2D01*
G01X1594183Y1219463D01*
X1594212Y1219557D01*
X1594516Y1219861D01*
X1594611Y1219890D01*
X1594659Y1219881D01*
G03X1594882Y1219860I224J1181D01*
G03X1595104Y1219881I-2J1202D01*
G01X1595153Y1219890D01*
X1595246Y1219861D01*
X1595551Y1219556D01*
X1595580Y1219463D01*
X1595571Y1219414D01*
G03X1595550Y1219192I1181J-224D01*
G03X1596752Y1217990I1202J0D01*
G03X1597954Y1219188I0J1202D01*
G01Y1219206D01*
G03X1597951Y1219294I-1202J3D01*
G01X1597947Y1219351D01*
X1597997Y1219449D01*
X1598195Y1219572D01*
X1598393Y1219695D01*
X1598504Y1219696D01*
X1598553Y1219668D01*
G03X1598796Y1219535I1943J3261D01*
G03X1598941Y1219466I1703J3393D01*
G01X1598980Y1219449D01*
G03X1599104Y1219397I1530J3475D01*
G01X1599132Y1219386D01*
X1599157Y1219366D01*
G02X1599197Y1219324I-123J-157D01*
G01X1599255Y1219242D01*
G02X1599291Y1219137I-164J-115D01*
G01Y1219136D01*
G03X1599320Y1218923I1201J55D01*
G03X1599871Y1218162I1172J269D01*
G01X1599872D01*
X1599890Y1218151D01*
G03X1600234Y1218018I600J1041D01*
G03X1600355Y1217998I256J1174D01*
G03X1600384Y1217995I138J1194D01*
G01X1600390D01*
X1600406Y1217993D01*
X1600414D01*
G37*
G36*
G01X1587217Y389152D02*
G03I-577J0D01*
G37*
G36*
G01X1582417D02*
G03I-577J0D01*
G37*
G36*
G01Y511672D02*
G03I-577J0D01*
G37*
G36*
G01X1587217D02*
G03I-577J0D01*
G37*
G36*
G01X1579917Y518759D02*
G03I-577J0D01*
G37*
G36*
G01X1587217D02*
G03I-577J0D01*
G37*
G36*
G01X1582417D02*
G03I-577J0D01*
G37*
G36*
G01X1579917Y532932D02*
G03I-577J0D01*
G37*
G36*
G01Y525845D02*
G03I-577J0D01*
G37*
G36*
G01X1587217D02*
G03I-577J0D01*
G37*
G36*
G01Y532932D02*
G03I-577J0D01*
G37*
G36*
G01X1582417D02*
G03I-577J0D01*
G37*
G36*
G01Y525845D02*
G03I-577J0D01*
G37*
G36*
G01X1579917Y540019D02*
G03I-577J0D01*
G37*
G36*
G01X1599704Y375586D02*
G03I-577J0D01*
G37*
G36*
G01X1713642Y54588D02*
X1742687D01*
X1742830Y54445D01*
Y52734D01*
X1742687Y52591D01*
X1713642D01*
G03X1707705Y46654I0J-5937D01*
G01Y7874D01*
G02X1701831Y2000I-5874J0D01*
G01X1654587D01*
G02X1648713Y7874I0J5874D01*
G01Y46509D01*
X1650710D01*
Y7874D01*
G03X1654585Y3998I3876J0D01*
G01X1701831D01*
G03X1705708Y7874I0J3877D01*
G01Y46654D01*
G02X1713642Y54588I7934J0D01*
G37*
G36*
G01X1650148Y983857D02*
G03I-577J0D01*
G37*
G36*
G01X1836948Y1225604D02*
X1838945D01*
Y970426D01*
G02X1837225Y966273I-5874J0D01*
G01X1826876Y955925D01*
G03X1823984Y948944I6982J-6982D01*
G01Y344836D01*
G03X1826876Y337855I9873J0D01*
G01X1837225Y327506D01*
G02X1838945Y323354I-4153J-4153D01*
G01Y7874D01*
G02X1833071Y2000I-5874J0D01*
G01X1756949D01*
G02X1751075Y7874I0J5874D01*
G01Y46654D01*
G03X1749600Y50571I-5938J0D01*
G01Y50666D01*
X1749606Y50672D01*
X1751979D01*
G02X1753072Y46654I-6841J-4019D01*
G01Y7874D01*
G03X1756947Y3998I3876J0D01*
G01X1833071D01*
G03X1836948Y7874I0J3877D01*
G01Y323354D01*
G03X1835813Y326094I-3876J0D01*
G01X1825464Y336443D01*
G02X1821987Y344836I8393J8394D01*
G01X1821986D01*
Y948944D01*
X1821987D01*
G02X1825464Y957337I11871J-1D01*
G01X1835813Y967685D01*
G03X1836948Y970426I-2742J2741D01*
G01Y1225604D01*
G37*
G36*
G01X1756769Y996132D02*
G03I-577J0D01*
G37*
G36*
G01X1768372Y1266009D02*
X1821032D01*
G02X1821172Y1265952I0J-200D01*
G01X1821173Y1265951D01*
X1822477Y1264647D01*
G02X1822479Y1264645I-140J-142D01*
G02X1822536Y1264505I-143J-140D01*
G01Y1248239D01*
G02X1822408Y1248052I-200J0D01*
G03Y1223208I4757J-12422D01*
G02X1822536Y1223021I-72J-187D01*
G01Y1220346D01*
G02X1822336Y1220146I-200J0D01*
G01X1819625D01*
G02X1819484Y1220204I0J200D01*
G01X1815032Y1224656D01*
X1815007Y1224698D01*
X1814999Y1224721D01*
G03X1814674Y1225263I-1250J-381D01*
G01X1812808Y1227128D01*
X1812795Y1227153D01*
G03X1811482Y1227925I-1313J-731D01*
G03X1809980Y1226423I0J-1502D01*
G03X1811248Y1224939I1502J0D01*
G01X1811280Y1224934D01*
X1811336Y1224905D01*
X1812468Y1223773D01*
X1812493Y1223731D01*
X1812501Y1223708D01*
G03X1812826Y1223166I1250J381D01*
G01X1818077Y1217915D01*
G03X1819001Y1217532I924J923D01*
G01X1825168D01*
G02X1825309Y1217474I0J-200D01*
G01X1830045Y1212738D01*
G02X1830104Y1212596I-141J-142D01*
G01Y1199929D01*
G02X1830045Y1199787I-200J0D01*
G01X1829632Y1199374D01*
G02X1829490Y1199315I-142J141D01*
G01X1770149D01*
G02X1770007Y1199374I0J200D01*
G01X1767170Y1202211D01*
G02X1767111Y1202353I141J142D01*
G01Y1202700D01*
G02X1767143Y1202808I200J0D01*
G01X1767211Y1202915D01*
X1767253Y1202952D01*
X1767279Y1202964D01*
G03Y1227036I-5665J12036D01*
G01X1767253Y1227048D01*
X1767211Y1227085D01*
X1767143Y1227192D01*
G02X1767111Y1227300I168J108D01*
G01Y1264748D01*
G02X1767168Y1264888I200J0D01*
G01X1767169Y1264889D01*
X1768230Y1265950D01*
G02X1768232Y1265952I142J-140D01*
G02X1768372Y1266009I140J-143D01*
G37*
%LPC*%
G75*
G36*
G01X1337658Y174764D02*
X1328799D01*
G02Y178566I0J1901D01*
G01X1336784D01*
G03X1336926Y178625I0J200D01*
G01X1337749Y179449D01*
G03X1337808Y179591I-141J142D01*
G01Y198669D01*
G03X1337749Y198811I-200J0D01*
G01X1333657Y202903D01*
G03X1333515Y202962I-142J-141D01*
G01X1328831D01*
G02Y206766I0J1902D01*
G01X1334386D01*
G02X1335731Y206209I0J-1902D01*
G01X1341055Y200885D01*
G02X1341612Y199540I-1345J-1345D01*
G01Y178720D01*
G02X1341055Y177375I-1902J0D01*
G01X1339000Y175320D01*
G02X1337658Y174764I-1344J1346D01*
G37*
G36*
G01X880478D02*
X871713D01*
G02Y178566I0J1901D01*
G01X879604D01*
G03X879746Y178625I0J200D01*
G01X880589Y179469D01*
G03X880648Y179611I-141J142D01*
G01Y198743D01*
G03X880589Y198885I-200J0D01*
G01X876571Y202903D01*
G03X876429Y202962I-142J-141D01*
G01X871745D01*
G02Y206766I0J1902D01*
G01X877300D01*
G02X878645Y206209I0J-1902D01*
G01X883895Y200959D01*
G02X884452Y199614I-1345J-1345D01*
G01Y178740D01*
G02X883895Y177395I-1902J0D01*
G01X881820Y175320D01*
G02X880478Y174764I-1344J1346D01*
G37*
G36*
G01X198512Y1361602D02*
X201912D01*
G02Y1358596I0J-1503D01*
G01X198512D01*
G02Y1361602I0J1503D01*
G37*
G36*
G01X186272Y1349690D02*
X189672D01*
G02Y1346684I0J-1503D01*
G01X186272D01*
G02Y1349690I0J1503D01*
G37*
G36*
G01Y1361602D02*
X189672D01*
G02Y1358596I0J-1503D01*
G01X186272D01*
G02Y1361602I0J1503D01*
G37*
G36*
G01X174032Y1349690D02*
X177432D01*
G02Y1346684I0J-1503D01*
G01X174032D01*
G02Y1349690I0J1503D01*
G37*
G36*
G01Y1361602D02*
X177432D01*
G02Y1358596I0J-1503D01*
G01X174032D01*
G02Y1361602I0J1503D01*
G37*
G36*
G01X161792D02*
X165192D01*
G02Y1358596I0J-1503D01*
G01X161792D01*
G02Y1361602I0J1503D01*
G37*
G36*
G01Y1349690D02*
X165192D01*
G02Y1346684I0J-1503D01*
G01X161792D01*
G02Y1349690I0J1503D01*
G37*
G36*
G01X149552D02*
X152952D01*
G02Y1346684I0J-1503D01*
G01X149552D01*
G02Y1349690I0J1503D01*
G37*
G36*
G01Y1361602D02*
X152952D01*
G02Y1358596I0J-1503D01*
G01X149552D01*
G02Y1361602I0J1503D01*
G37*
G36*
G01X137312Y1349690D02*
X140712D01*
G02Y1346684I0J-1503D01*
G01X137312D01*
G02Y1349690I0J1503D01*
G37*
G36*
G01Y1361602D02*
X140712D01*
G02Y1358596I0J-1503D01*
G01X137312D01*
G02Y1361602I0J1503D01*
G37*
G36*
G01X125072Y1349690D02*
X128472D01*
G02Y1346684I0J-1503D01*
G01X125072D01*
G02Y1349690I0J1503D01*
G37*
G36*
G01Y1361602D02*
X128472D01*
G02Y1358596I0J-1503D01*
G01X125072D01*
G02Y1361602I0J1503D01*
G37*
G36*
G01X112832D02*
X116232D01*
G02Y1358596I0J-1503D01*
G01X112832D01*
G02Y1361602I0J1503D01*
G37*
G36*
G01Y1349690D02*
X116232D01*
G02Y1346684I0J-1503D01*
G01X112832D01*
G02Y1349690I0J1503D01*
G37*
G36*
G01X100592D02*
X103992D01*
G02Y1346684I0J-1503D01*
G01X100592D01*
G02Y1349690I0J1503D01*
G37*
G36*
G01Y1361602D02*
X103992D01*
G02Y1358596I0J-1503D01*
G01X100592D01*
G02Y1361602I0J1503D01*
G37*
G36*
G01X88352D02*
X91752D01*
G02Y1358596I0J-1503D01*
G01X88352D01*
G02Y1361602I0J1503D01*
G37*
G36*
G01Y1349690D02*
X91752D01*
G02Y1346684I0J-1503D01*
G01X88352D01*
G02Y1349690I0J1503D01*
G37*
G36*
G01X76112D02*
X79512D01*
G02Y1346684I0J-1503D01*
G01X76112D01*
G02Y1349690I0J1503D01*
G37*
G36*
G01Y1361602D02*
X79512D01*
G02Y1358596I0J-1503D01*
G01X76112D01*
G02Y1361602I0J1503D01*
G37*
G36*
G01Y1373888D02*
X79512D01*
G02Y1370882I0J-1503D01*
G01X76112D01*
G02Y1373888I0J1503D01*
G37*
G36*
G01Y1385800D02*
X79512D01*
G02Y1382794I0J-1503D01*
G01X76112D01*
G02Y1385800I0J1503D01*
G37*
G36*
G01X88352D02*
X91752D01*
G02Y1382794I0J-1503D01*
G01X88352D01*
G02Y1385800I0J1503D01*
G37*
G36*
G01X100592D02*
X103992D01*
G02Y1382794I0J-1503D01*
G01X100592D01*
G02Y1385800I0J1503D01*
G37*
G36*
G01X88352Y1373888D02*
X91752D01*
G02Y1370882I0J-1503D01*
G01X88352D01*
G02Y1373888I0J1503D01*
G37*
G36*
G01X100592D02*
X103992D01*
G02Y1370882I0J-1503D01*
G01X100592D01*
G02Y1373888I0J1503D01*
G37*
G36*
G01X112832D02*
X116232D01*
G02Y1370882I0J-1503D01*
G01X112832D01*
G02Y1373888I0J1503D01*
G37*
G36*
G01Y1385800D02*
X116232D01*
G02Y1382794I0J-1503D01*
G01X112832D01*
G02Y1385800I0J1503D01*
G37*
G36*
G01X125072D02*
X128472D01*
G02Y1382794I0J-1503D01*
G01X125072D01*
G02Y1385800I0J1503D01*
G37*
G36*
G01Y1373888D02*
X128472D01*
G02Y1370882I0J-1503D01*
G01X125072D01*
G02Y1373888I0J1503D01*
G37*
G36*
G01X137312D02*
X140712D01*
G02Y1370882I0J-1503D01*
G01X137312D01*
G02Y1373888I0J1503D01*
G37*
G36*
G01Y1385800D02*
X140712D01*
G02Y1382794I0J-1503D01*
G01X137312D01*
G02Y1385800I0J1503D01*
G37*
G36*
G01X149552D02*
X152952D01*
G02Y1382794I0J-1503D01*
G01X149552D01*
G02Y1385800I0J1503D01*
G37*
G36*
G01Y1373888D02*
X152952D01*
G02Y1370882I0J-1503D01*
G01X149552D01*
G02Y1373888I0J1503D01*
G37*
G36*
G01X161792D02*
X165192D01*
G02Y1370882I0J-1503D01*
G01X161792D01*
G02Y1373888I0J1503D01*
G37*
G36*
G01Y1385800D02*
X165192D01*
G02Y1382794I0J-1503D01*
G01X161792D01*
G02Y1385800I0J1503D01*
G37*
G36*
G01X174032Y1373888D02*
X177432D01*
G02Y1370882I0J-1503D01*
G01X174032D01*
G02Y1373888I0J1503D01*
G37*
G36*
G01Y1385800D02*
X177432D01*
G02Y1382794I0J-1503D01*
G01X174032D01*
G02Y1385800I0J1503D01*
G37*
G36*
G01X186272Y1373888D02*
X189672D01*
G02Y1370882I0J-1503D01*
G01X186272D01*
G02Y1373888I0J1503D01*
G37*
G36*
G01Y1385800D02*
X189672D01*
G02Y1382794I0J-1503D01*
G01X186272D01*
G02Y1385800I0J1503D01*
G37*
G36*
G01X198512Y1373888D02*
X201912D01*
G02Y1370882I0J-1503D01*
G01X198512D01*
G02Y1373888I0J1503D01*
G37*
G36*
G01Y1385800D02*
X201912D01*
G02Y1382794I0J-1503D01*
G01X198512D01*
G02Y1385800I0J1503D01*
G37*
G36*
G01Y1398086D02*
X201912D01*
G02Y1395080I0J-1503D01*
G01X198512D01*
G02Y1398086I0J1503D01*
G37*
G36*
G01X186272D02*
X189672D01*
G02Y1395080I0J-1503D01*
G01X186272D01*
G02Y1398086I0J1503D01*
G37*
G36*
G01Y1409998D02*
X189672D01*
G02Y1406992I0J-1503D01*
G01X186272D01*
G02Y1409998I0J1503D01*
G37*
G36*
G01X174032Y1398086D02*
X177432D01*
G02Y1395080I0J-1503D01*
G01X174032D01*
G02Y1398086I0J1503D01*
G37*
G36*
G01Y1409998D02*
X177432D01*
G02Y1406992I0J-1503D01*
G01X174032D01*
G02Y1409998I0J1503D01*
G37*
G36*
G01X161792Y1398086D02*
X165192D01*
G02Y1395080I0J-1503D01*
G01X161792D01*
G02Y1398086I0J1503D01*
G37*
G36*
G01Y1409998D02*
X165192D01*
G02Y1406992I0J-1503D01*
G01X161792D01*
G02Y1409998I0J1503D01*
G37*
G36*
G01X149552Y1398086D02*
X152952D01*
G02Y1395080I0J-1503D01*
G01X149552D01*
G02Y1398086I0J1503D01*
G37*
G36*
G01Y1409998D02*
X152952D01*
G02Y1406992I0J-1503D01*
G01X149552D01*
G02Y1409998I0J1503D01*
G37*
G36*
G01X137312D02*
X140712D01*
G02Y1406992I0J-1503D01*
G01X137312D01*
G02Y1409998I0J1503D01*
G37*
G36*
G01Y1398086D02*
X140712D01*
G02Y1395080I0J-1503D01*
G01X137312D01*
G02Y1398086I0J1503D01*
G37*
G36*
G01X125072D02*
X128472D01*
G02Y1395080I0J-1503D01*
G01X125072D01*
G02Y1398086I0J1503D01*
G37*
G36*
G01Y1409998D02*
X128472D01*
G02Y1406992I0J-1503D01*
G01X125072D01*
G02Y1409998I0J1503D01*
G37*
G36*
G01X112832Y1398086D02*
X116232D01*
G02Y1395080I0J-1503D01*
G01X112832D01*
G02Y1398086I0J1503D01*
G37*
G36*
G01X100592D02*
X103992D01*
G02Y1395080I0J-1503D01*
G01X100592D01*
G02Y1398086I0J1503D01*
G37*
G36*
G01X112832Y1409998D02*
X116232D01*
G02Y1406992I0J-1503D01*
G01X112832D01*
G02Y1409998I0J1503D01*
G37*
G36*
G01X100592D02*
X103992D01*
G02Y1406992I0J-1503D01*
G01X100592D01*
G02Y1409998I0J1503D01*
G37*
G36*
G01X88352Y1398086D02*
X91752D01*
G02Y1395080I0J-1503D01*
G01X88352D01*
G02Y1398086I0J1503D01*
G37*
G36*
G01Y1409998D02*
X91752D01*
G02Y1406992I0J-1503D01*
G01X88352D01*
G02Y1409998I0J1503D01*
G37*
G36*
G01X26772Y1559218D02*
X20472D01*
G02Y1575428I0J8105D01*
G01X26772D01*
G02Y1559218I0J-8105D01*
G37*
G36*
G01X35825Y1466648D02*
X39225D01*
G02Y1463044I0J-1802D01*
G01X35825D01*
G02Y1466648I0J1802D01*
G37*
G36*
G01X205848Y59011D02*
G02Y62015I0J1502D01*
G02X207005Y61471I0J-1502D01*
G01X207032Y61439D01*
X207106Y61402D01*
X207442Y61384D01*
G03X207593Y61441I11J200D01*
G02X208645Y61871I1052J-1072D01*
G02Y58867I0J-1502D01*
G02X207488Y59411I0J1502D01*
G01X207461Y59443D01*
X207387Y59480D01*
X207051Y59498D01*
G03X206900Y59441I-11J-200D01*
G02X205848Y59011I-1052J1072D01*
G37*
G36*
G01X560573D02*
G02Y62015I0J1502D01*
G02X561728Y61473I0J-1502D01*
G01X561756Y61439D01*
X561833Y61402D01*
X562179Y61393D01*
G03X562329Y61456I4J200D01*
G01X562330Y61457D01*
G02X563433Y61940I1103J-1018D01*
G02Y58936I0J-1502D01*
G02X562278Y59478I0J1502D01*
G01X562250Y59512D01*
X562173Y59549D01*
X561827Y59558D01*
G03X561677Y59495I-4J-200D01*
G01X561676Y59494D01*
G02X560573Y59011I-1103J1018D01*
G37*
G36*
G01X662935D02*
G02Y62015I0J1502D01*
G02X664090Y61473I0J-1502D01*
G01X664118Y61439D01*
X664195Y61402D01*
X664541Y61393D01*
G03X664691Y61456I4J200D01*
G01X664692Y61457D01*
G02X665795Y61940I1103J-1018D01*
G02Y58936I0J-1502D01*
G02X664640Y59478I0J1502D01*
G01X664612Y59512D01*
X664535Y59549D01*
X664189Y59558D01*
G03X664039Y59495I-4J-200D01*
G01X664038Y59494D01*
G02X662935Y59011I-1103J1018D01*
G37*
G36*
G01X765297D02*
G02Y62015I0J1502D01*
G02X766452Y61473I0J-1502D01*
G01X766480Y61439D01*
X766557Y61402D01*
X766903Y61393D01*
G03X767053Y61456I4J200D01*
G01X767054Y61457D01*
G02X768157Y61940I1103J-1018D01*
G02Y58936I0J-1502D01*
G02X767002Y59478I0J1502D01*
G01X766974Y59512D01*
X766897Y59549D01*
X766551Y59558D01*
G03X766401Y59495I-4J-200D01*
G01X766400Y59494D01*
G02X765297Y59011I-1103J1018D01*
G37*
G36*
G01X867659D02*
G02Y62015I0J1502D01*
G02X868814Y61473I0J-1502D01*
G01X868842Y61439D01*
X868919Y61402D01*
X869265Y61393D01*
G03X869415Y61456I4J200D01*
G01X869416Y61457D01*
G02X870519Y61940I1103J-1018D01*
G02Y58936I0J-1502D01*
G02X869364Y59478I0J1502D01*
G01X869336Y59512D01*
X869259Y59549D01*
X868913Y59558D01*
G03X868763Y59495I-4J-200D01*
G01X868762Y59494D01*
G02X867659Y59011I-1103J1018D01*
G37*
G36*
G01X1017659D02*
G02Y62015I0J1502D01*
G02X1018814Y61473I0J-1502D01*
G01X1018842Y61439D01*
X1018919Y61402D01*
X1019265Y61393D01*
G03X1019415Y61456I4J200D01*
G01X1019416Y61457D01*
G02X1020519Y61940I1103J-1018D01*
G02Y58936I0J-1502D01*
G02X1019364Y59478I0J1502D01*
G01X1019336Y59512D01*
X1019259Y59549D01*
X1018913Y59558D01*
G03X1018763Y59495I-4J-200D01*
G01X1018762Y59494D01*
G02X1017659Y59011I-1103J1018D01*
G37*
G36*
G01X1120021D02*
G02Y62015I0J1502D01*
G02X1121176Y61473I0J-1502D01*
G01X1121204Y61439D01*
X1121281Y61402D01*
X1121627Y61393D01*
G03X1121777Y61456I4J200D01*
G01X1121778Y61457D01*
G02X1122881Y61940I1103J-1018D01*
G02Y58936I0J-1502D01*
G02X1121726Y59478I0J1502D01*
G01X1121698Y59512D01*
X1121621Y59549D01*
X1121275Y59558D01*
G03X1121125Y59495I-4J-200D01*
G01X1121124Y59494D01*
G02X1120021Y59011I-1103J1018D01*
G37*
G36*
G01X1222383D02*
G02Y62015I0J1502D01*
G02X1223538Y61473I0J-1502D01*
G01X1223566Y61439D01*
X1223643Y61402D01*
X1223989Y61393D01*
G03X1224139Y61456I4J200D01*
G01X1224140Y61457D01*
G02X1225243Y61940I1103J-1018D01*
G02Y58936I0J-1502D01*
G02X1224088Y59478I0J1502D01*
G01X1224060Y59512D01*
X1223983Y59549D01*
X1223637Y59558D01*
G03X1223487Y59495I-4J-200D01*
G01X1223486Y59494D01*
G02X1222383Y59011I-1103J1018D01*
G37*
G36*
G01X1474746D02*
G02Y62015I0J1502D01*
G02X1475901Y61473I0J-1502D01*
G01X1475929Y61439D01*
X1476006Y61402D01*
X1476352Y61393D01*
G03X1476502Y61456I4J200D01*
G01X1476503Y61457D01*
G02X1477606Y61940I1103J-1018D01*
G02Y58936I0J-1502D01*
G02X1476451Y59478I0J1502D01*
G01X1476423Y59512D01*
X1476346Y59549D01*
X1476000Y59558D01*
G03X1475850Y59495I-4J-200D01*
G01X1475849Y59494D01*
G02X1474746Y59011I-1103J1018D01*
G37*
G36*
G01X1577108D02*
G02Y62015I0J1502D01*
G02X1578263Y61473I0J-1502D01*
G01X1578291Y61439D01*
X1578368Y61402D01*
X1578714Y61393D01*
G03X1578864Y61456I4J200D01*
G01X1578865Y61457D01*
G02X1579968Y61940I1103J-1018D01*
G02Y58936I0J-1502D01*
G02X1578813Y59478I0J1502D01*
G01X1578785Y59512D01*
X1578708Y59549D01*
X1578362Y59558D01*
G03X1578212Y59495I-4J-200D01*
G01X1578211Y59494D01*
G02X1577108Y59011I-1103J1018D01*
G37*
G36*
G01X1679470D02*
G02Y62015I0J1502D01*
G02X1680625Y61473I0J-1502D01*
G01X1680653Y61439D01*
X1680730Y61402D01*
X1681076Y61393D01*
G03X1681226Y61456I4J200D01*
G01X1681227Y61457D01*
G02X1682330Y61940I1103J-1018D01*
G02Y58936I0J-1502D01*
G02X1681175Y59478I0J1502D01*
G01X1681147Y59512D01*
X1681070Y59549D01*
X1680724Y59558D01*
G03X1680574Y59495I-4J-200D01*
G01X1680573Y59494D01*
G02X1679470Y59011I-1103J1018D01*
G37*
G36*
G01X307916Y59027D02*
G02Y62031I0J1502D01*
G02X309107Y61444I0J-1502D01*
G01X309134Y61409D01*
X309211Y61369D01*
X309606Y61350D01*
X309687Y61383D01*
X309717Y61416D01*
G02X310817Y61895I1100J-1024D01*
G02Y58891I0J-1502D01*
G02X309626Y59478I0J1502D01*
G01X309599Y59513D01*
X309522Y59553D01*
X309127Y59572D01*
X309046Y59539D01*
X309016Y59506D01*
G02X307916Y59027I-1100J1024D01*
G37*
G36*
G01X63283Y85193D02*
G02X66287I1502J0D01*
G02X65881Y84166I-1502J0D01*
G01X65855Y84139D01*
X65827Y84068D01*
Y83718D01*
X65855Y83647D01*
X65881Y83620D01*
G02Y81566I-1096J-1027D01*
G01X65855Y81539D01*
X65827Y81468D01*
Y81118D01*
X65855Y81047D01*
X65881Y81020D01*
G02Y78966I-1096J-1027D01*
G01X65855Y78939D01*
X65827Y78868D01*
Y78518D01*
X65855Y78447D01*
X65881Y78420D01*
G02Y76366I-1096J-1027D01*
G01X65855Y76339D01*
X65827Y76268D01*
Y75918D01*
X65855Y75847D01*
X65881Y75820D01*
G02X66287Y74793I-1096J-1027D01*
G02X63283I-1502J0D01*
G02X63689Y75820I1502J0D01*
G01X63715Y75847D01*
X63743Y75918D01*
Y76268D01*
X63715Y76339D01*
X63689Y76366D01*
G02Y78420I1096J1027D01*
G01X63715Y78447D01*
X63743Y78518D01*
Y78868D01*
X63715Y78939D01*
X63689Y78966D01*
G02Y81020I1096J1027D01*
G01X63715Y81047D01*
X63743Y81118D01*
Y81468D01*
X63715Y81539D01*
X63689Y81566D01*
G02Y83620I1096J1027D01*
G01X63715Y83647D01*
X63743Y83718D01*
Y84068D01*
X63715Y84139D01*
X63689Y84166D01*
G02X63283Y85193I1096J1027D01*
G37*
G36*
G01X165645D02*
G02X168649I1502J0D01*
G02X168243Y84166I-1502J0D01*
G01X168217Y84139D01*
X168189Y84068D01*
Y83718D01*
X168217Y83647D01*
X168243Y83620D01*
G02Y81566I-1096J-1027D01*
G01X168217Y81539D01*
X168189Y81468D01*
Y81118D01*
X168217Y81047D01*
X168243Y81020D01*
G02Y78966I-1096J-1027D01*
G01X168217Y78939D01*
X168189Y78868D01*
Y78518D01*
X168217Y78447D01*
X168243Y78420D01*
G02Y76366I-1096J-1027D01*
G01X168217Y76339D01*
X168189Y76268D01*
Y75918D01*
X168217Y75847D01*
X168243Y75820D01*
G02X168649Y74793I-1096J-1027D01*
G02X165645I-1502J0D01*
G02X166051Y75820I1502J0D01*
G01X166077Y75847D01*
X166105Y75918D01*
Y76268D01*
X166077Y76339D01*
X166051Y76366D01*
G02Y78420I1096J1027D01*
G01X166077Y78447D01*
X166105Y78518D01*
Y78868D01*
X166077Y78939D01*
X166051Y78966D01*
G02Y81020I1096J1027D01*
G01X166077Y81047D01*
X166105Y81118D01*
Y81468D01*
X166077Y81539D01*
X166051Y81566D01*
G02Y83620I1096J1027D01*
G01X166077Y83647D01*
X166105Y83718D01*
Y84068D01*
X166077Y84139D01*
X166051Y84166D01*
G02X165645Y85193I1096J1027D01*
G37*
G36*
G01X268007D02*
G02X271011I1502J0D01*
G02X270605Y84166I-1502J0D01*
G01X270579Y84139D01*
X270551Y84068D01*
Y83718D01*
X270579Y83647D01*
X270605Y83620D01*
G02Y81566I-1096J-1027D01*
G01X270579Y81539D01*
X270551Y81468D01*
Y81118D01*
X270579Y81047D01*
X270605Y81020D01*
G02Y78966I-1096J-1027D01*
G01X270579Y78939D01*
X270551Y78868D01*
Y78518D01*
X270579Y78447D01*
X270605Y78420D01*
G02Y76366I-1096J-1027D01*
G01X270579Y76339D01*
X270551Y76268D01*
Y75918D01*
X270579Y75847D01*
X270605Y75820D01*
G02X271011Y74793I-1096J-1027D01*
G02X268007I-1502J0D01*
G02X268413Y75820I1502J0D01*
G01X268439Y75847D01*
X268467Y75918D01*
Y76268D01*
X268439Y76339D01*
X268413Y76366D01*
G02Y78420I1096J1027D01*
G01X268439Y78447D01*
X268467Y78518D01*
Y78868D01*
X268439Y78939D01*
X268413Y78966D01*
G02Y81020I1096J1027D01*
G01X268439Y81047D01*
X268467Y81118D01*
Y81468D01*
X268439Y81539D01*
X268413Y81566D01*
G02Y83620I1096J1027D01*
G01X268439Y83647D01*
X268467Y83718D01*
Y84068D01*
X268439Y84139D01*
X268413Y84166D01*
G02X268007Y85193I1096J1027D01*
G37*
G36*
G01X370369D02*
G02X373373I1502J0D01*
G02X372967Y84166I-1502J0D01*
G01X372941Y84139D01*
X372913Y84068D01*
Y83718D01*
X372941Y83647D01*
X372967Y83620D01*
G02Y81566I-1096J-1027D01*
G01X372941Y81539D01*
X372913Y81468D01*
Y81118D01*
X372941Y81047D01*
X372967Y81020D01*
G02Y78966I-1096J-1027D01*
G01X372941Y78939D01*
X372913Y78868D01*
Y78518D01*
X372941Y78447D01*
X372967Y78420D01*
G02Y76366I-1096J-1027D01*
G01X372941Y76339D01*
X372913Y76268D01*
Y75918D01*
X372941Y75847D01*
X372967Y75820D01*
G02X373373Y74793I-1096J-1027D01*
G02X370369I-1502J0D01*
G02X370775Y75820I1502J0D01*
G01X370801Y75847D01*
X370829Y75918D01*
Y76268D01*
X370801Y76339D01*
X370775Y76366D01*
G02Y78420I1096J1027D01*
G01X370801Y78447D01*
X370829Y78518D01*
Y78868D01*
X370801Y78939D01*
X370775Y78966D01*
G02Y81020I1096J1027D01*
G01X370801Y81047D01*
X370829Y81118D01*
Y81468D01*
X370801Y81539D01*
X370775Y81566D01*
G02Y83620I1096J1027D01*
G01X370801Y83647D01*
X370829Y83718D01*
Y84068D01*
X370801Y84139D01*
X370775Y84166D01*
G02X370369Y85193I1096J1027D01*
G37*
G36*
G01X520370D02*
G02X523374I1502J0D01*
G02X522968Y84166I-1502J0D01*
G01X522942Y84139D01*
X522914Y84068D01*
Y83718D01*
X522942Y83647D01*
X522968Y83620D01*
G02Y81566I-1096J-1027D01*
G01X522942Y81539D01*
X522914Y81468D01*
Y81118D01*
X522942Y81047D01*
X522968Y81020D01*
G02Y78966I-1096J-1027D01*
G01X522942Y78939D01*
X522914Y78868D01*
Y78518D01*
X522942Y78447D01*
X522968Y78420D01*
G02Y76366I-1096J-1027D01*
G01X522942Y76339D01*
X522914Y76268D01*
Y75918D01*
X522942Y75847D01*
X522968Y75820D01*
G02X523374Y74793I-1096J-1027D01*
G02X520370I-1502J0D01*
G02X520776Y75820I1502J0D01*
G01X520802Y75847D01*
X520830Y75918D01*
Y76268D01*
X520802Y76339D01*
X520776Y76366D01*
G02Y78420I1096J1027D01*
G01X520802Y78447D01*
X520830Y78518D01*
Y78868D01*
X520802Y78939D01*
X520776Y78966D01*
G02Y81020I1096J1027D01*
G01X520802Y81047D01*
X520830Y81118D01*
Y81468D01*
X520802Y81539D01*
X520776Y81566D01*
G02Y83620I1096J1027D01*
G01X520802Y83647D01*
X520830Y83718D01*
Y84068D01*
X520802Y84139D01*
X520776Y84166D01*
G02X520370Y85193I1096J1027D01*
G37*
G36*
G01X622732D02*
G02X625736I1502J0D01*
G02X625330Y84166I-1502J0D01*
G01X625304Y84139D01*
X625276Y84068D01*
Y83718D01*
X625304Y83647D01*
X625330Y83620D01*
G02Y81566I-1096J-1027D01*
G01X625304Y81539D01*
X625276Y81468D01*
Y81118D01*
X625304Y81047D01*
X625330Y81020D01*
G02Y78966I-1096J-1027D01*
G01X625304Y78939D01*
X625276Y78868D01*
Y78518D01*
X625304Y78447D01*
X625330Y78420D01*
G02Y76366I-1096J-1027D01*
G01X625304Y76339D01*
X625276Y76268D01*
Y75918D01*
X625304Y75847D01*
X625330Y75820D01*
G02X625736Y74793I-1096J-1027D01*
G02X622732I-1502J0D01*
G02X623138Y75820I1502J0D01*
G01X623164Y75847D01*
X623192Y75918D01*
Y76268D01*
X623164Y76339D01*
X623138Y76366D01*
G02Y78420I1096J1027D01*
G01X623164Y78447D01*
X623192Y78518D01*
Y78868D01*
X623164Y78939D01*
X623138Y78966D01*
G02Y81020I1096J1027D01*
G01X623164Y81047D01*
X623192Y81118D01*
Y81468D01*
X623164Y81539D01*
X623138Y81566D01*
G02Y83620I1096J1027D01*
G01X623164Y83647D01*
X623192Y83718D01*
Y84068D01*
X623164Y84139D01*
X623138Y84166D01*
G02X622732Y85193I1096J1027D01*
G37*
G36*
G01X725094D02*
G02X728098I1502J0D01*
G02X727692Y84166I-1502J0D01*
G01X727666Y84139D01*
X727638Y84068D01*
Y83718D01*
X727666Y83647D01*
X727692Y83620D01*
G02Y81566I-1096J-1027D01*
G01X727666Y81539D01*
X727638Y81468D01*
Y81118D01*
X727666Y81047D01*
X727692Y81020D01*
G02Y78966I-1096J-1027D01*
G01X727666Y78939D01*
X727638Y78868D01*
Y78518D01*
X727666Y78447D01*
X727692Y78420D01*
G02Y76366I-1096J-1027D01*
G01X727666Y76339D01*
X727638Y76268D01*
Y75918D01*
X727666Y75847D01*
X727692Y75820D01*
G02X728098Y74793I-1096J-1027D01*
G02X725094I-1502J0D01*
G02X725500Y75820I1502J0D01*
G01X725526Y75847D01*
X725554Y75918D01*
Y76268D01*
X725526Y76339D01*
X725500Y76366D01*
G02Y78420I1096J1027D01*
G01X725526Y78447D01*
X725554Y78518D01*
Y78868D01*
X725526Y78939D01*
X725500Y78966D01*
G02Y81020I1096J1027D01*
G01X725526Y81047D01*
X725554Y81118D01*
Y81468D01*
X725526Y81539D01*
X725500Y81566D01*
G02Y83620I1096J1027D01*
G01X725526Y83647D01*
X725554Y83718D01*
Y84068D01*
X725526Y84139D01*
X725500Y84166D01*
G02X725094Y85193I1096J1027D01*
G37*
G36*
G01X827456D02*
G02X830460I1502J0D01*
G02X830054Y84166I-1502J0D01*
G01X830028Y84139D01*
X830000Y84068D01*
Y83718D01*
X830028Y83647D01*
X830054Y83620D01*
G02Y81566I-1096J-1027D01*
G01X830028Y81539D01*
X830000Y81468D01*
Y81118D01*
X830028Y81047D01*
X830054Y81020D01*
G02Y78966I-1096J-1027D01*
G01X830028Y78939D01*
X830000Y78868D01*
Y78518D01*
X830028Y78447D01*
X830054Y78420D01*
G02Y76366I-1096J-1027D01*
G01X830028Y76339D01*
X830000Y76268D01*
Y75918D01*
X830028Y75847D01*
X830054Y75820D01*
G02X830460Y74793I-1096J-1027D01*
G02X827456I-1502J0D01*
G02X827862Y75820I1502J0D01*
G01X827888Y75847D01*
X827916Y75918D01*
Y76268D01*
X827888Y76339D01*
X827862Y76366D01*
G02Y78420I1096J1027D01*
G01X827888Y78447D01*
X827916Y78518D01*
Y78868D01*
X827888Y78939D01*
X827862Y78966D01*
G02Y81020I1096J1027D01*
G01X827888Y81047D01*
X827916Y81118D01*
Y81468D01*
X827888Y81539D01*
X827862Y81566D01*
G02Y83620I1096J1027D01*
G01X827888Y83647D01*
X827916Y83718D01*
Y84068D01*
X827888Y84139D01*
X827862Y84166D01*
G02X827456Y85193I1096J1027D01*
G37*
G36*
G01X977456D02*
G02X980460I1502J0D01*
G02X980054Y84166I-1502J0D01*
G01X980028Y84139D01*
X980000Y84068D01*
Y83718D01*
X980028Y83647D01*
X980054Y83620D01*
G02Y81566I-1096J-1027D01*
G01X980028Y81539D01*
X980000Y81468D01*
Y81118D01*
X980028Y81047D01*
X980054Y81020D01*
G02Y78966I-1096J-1027D01*
G01X980028Y78939D01*
X980000Y78868D01*
Y78518D01*
X980028Y78447D01*
X980054Y78420D01*
G02Y76366I-1096J-1027D01*
G01X980028Y76339D01*
X980000Y76268D01*
Y75918D01*
X980028Y75847D01*
X980054Y75820D01*
G02X980460Y74793I-1096J-1027D01*
G02X977456I-1502J0D01*
G02X977862Y75820I1502J0D01*
G01X977888Y75847D01*
X977916Y75918D01*
Y76268D01*
X977888Y76339D01*
X977862Y76366D01*
G02Y78420I1096J1027D01*
G01X977888Y78447D01*
X977916Y78518D01*
Y78868D01*
X977888Y78939D01*
X977862Y78966D01*
G02Y81020I1096J1027D01*
G01X977888Y81047D01*
X977916Y81118D01*
Y81468D01*
X977888Y81539D01*
X977862Y81566D01*
G02Y83620I1096J1027D01*
G01X977888Y83647D01*
X977916Y83718D01*
Y84068D01*
X977888Y84139D01*
X977862Y84166D01*
G02X977456Y85193I1096J1027D01*
G37*
G36*
G01X1079818D02*
G02X1082822I1502J0D01*
G02X1082416Y84166I-1502J0D01*
G01X1082390Y84139D01*
X1082362Y84068D01*
Y83718D01*
X1082390Y83647D01*
X1082416Y83620D01*
G02Y81566I-1096J-1027D01*
G01X1082390Y81539D01*
X1082362Y81468D01*
Y81118D01*
X1082390Y81047D01*
X1082416Y81020D01*
G02Y78966I-1096J-1027D01*
G01X1082390Y78939D01*
X1082362Y78868D01*
Y78518D01*
X1082390Y78447D01*
X1082416Y78420D01*
G02Y76366I-1096J-1027D01*
G01X1082390Y76339D01*
X1082362Y76268D01*
Y75918D01*
X1082390Y75847D01*
X1082416Y75820D01*
G02X1082822Y74793I-1096J-1027D01*
G02X1079818I-1502J0D01*
G02X1080224Y75820I1502J0D01*
G01X1080250Y75847D01*
X1080278Y75918D01*
Y76268D01*
X1080250Y76339D01*
X1080224Y76366D01*
G02Y78420I1096J1027D01*
G01X1080250Y78447D01*
X1080278Y78518D01*
Y78868D01*
X1080250Y78939D01*
X1080224Y78966D01*
G02Y81020I1096J1027D01*
G01X1080250Y81047D01*
X1080278Y81118D01*
Y81468D01*
X1080250Y81539D01*
X1080224Y81566D01*
G02Y83620I1096J1027D01*
G01X1080250Y83647D01*
X1080278Y83718D01*
Y84068D01*
X1080250Y84139D01*
X1080224Y84166D01*
G02X1079818Y85193I1096J1027D01*
G37*
G36*
G01X1182180D02*
G02X1185184I1502J0D01*
G02X1184778Y84166I-1502J0D01*
G01X1184752Y84139D01*
X1184724Y84068D01*
Y83718D01*
X1184752Y83647D01*
X1184778Y83620D01*
G02Y81566I-1096J-1027D01*
G01X1184752Y81539D01*
X1184724Y81468D01*
Y81118D01*
X1184752Y81047D01*
X1184778Y81020D01*
G02Y78966I-1096J-1027D01*
G01X1184752Y78939D01*
X1184724Y78868D01*
Y78518D01*
X1184752Y78447D01*
X1184778Y78420D01*
G02Y76366I-1096J-1027D01*
G01X1184752Y76339D01*
X1184724Y76268D01*
Y75918D01*
X1184752Y75847D01*
X1184778Y75820D01*
G02X1185184Y74793I-1096J-1027D01*
G02X1182180I-1502J0D01*
G02X1182586Y75820I1502J0D01*
G01X1182612Y75847D01*
X1182640Y75918D01*
Y76268D01*
X1182612Y76339D01*
X1182586Y76366D01*
G02Y78420I1096J1027D01*
G01X1182612Y78447D01*
X1182640Y78518D01*
Y78868D01*
X1182612Y78939D01*
X1182586Y78966D01*
G02Y81020I1096J1027D01*
G01X1182612Y81047D01*
X1182640Y81118D01*
Y81468D01*
X1182612Y81539D01*
X1182586Y81566D01*
G02Y83620I1096J1027D01*
G01X1182612Y83647D01*
X1182640Y83718D01*
Y84068D01*
X1182612Y84139D01*
X1182586Y84166D01*
G02X1182180Y85193I1096J1027D01*
G37*
G36*
G01X1434543D02*
G02X1437547I1502J0D01*
G02X1437141Y84166I-1502J0D01*
G01X1437115Y84139D01*
X1437087Y84068D01*
Y83718D01*
X1437115Y83647D01*
X1437141Y83620D01*
G02Y81566I-1096J-1027D01*
G01X1437115Y81539D01*
X1437087Y81468D01*
Y81118D01*
X1437115Y81047D01*
X1437141Y81020D01*
G02Y78966I-1096J-1027D01*
G01X1437115Y78939D01*
X1437087Y78868D01*
Y78518D01*
X1437115Y78447D01*
X1437141Y78420D01*
G02Y76366I-1096J-1027D01*
G01X1437115Y76339D01*
X1437087Y76268D01*
Y75918D01*
X1437115Y75847D01*
X1437141Y75820D01*
G02X1437547Y74793I-1096J-1027D01*
G02X1434543I-1502J0D01*
G02X1434949Y75820I1502J0D01*
G01X1434975Y75847D01*
X1435003Y75918D01*
Y76268D01*
X1434975Y76339D01*
X1434949Y76366D01*
G02Y78420I1096J1027D01*
G01X1434975Y78447D01*
X1435003Y78518D01*
Y78868D01*
X1434975Y78939D01*
X1434949Y78966D01*
G02Y81020I1096J1027D01*
G01X1434975Y81047D01*
X1435003Y81118D01*
Y81468D01*
X1434975Y81539D01*
X1434949Y81566D01*
G02Y83620I1096J1027D01*
G01X1434975Y83647D01*
X1435003Y83718D01*
Y84068D01*
X1434975Y84139D01*
X1434949Y84166D01*
G02X1434543Y85193I1096J1027D01*
G37*
G36*
G01X1284542Y85539D02*
G02X1287546I1502J0D01*
G02X1287140Y84512I-1502J0D01*
G01X1287114Y84485D01*
X1287086Y84414D01*
Y84064D01*
X1287114Y83993D01*
X1287140Y83966D01*
G02Y81912I-1096J-1027D01*
G01X1287114Y81885D01*
X1287086Y81814D01*
Y81464D01*
X1287114Y81393D01*
X1287140Y81366D01*
G02Y79312I-1096J-1027D01*
G01X1287114Y79285D01*
X1287086Y79214D01*
Y78864D01*
X1287114Y78793D01*
X1287140Y78766D01*
G02Y76712I-1096J-1027D01*
G01X1287114Y76685D01*
X1287086Y76614D01*
Y76264D01*
X1287114Y76193D01*
X1287140Y76166D01*
G02X1287546Y75139I-1096J-1027D01*
G02X1284542I-1502J0D01*
G02X1284948Y76166I1502J0D01*
G01X1284974Y76193D01*
X1285002Y76264D01*
Y76614D01*
X1284974Y76685D01*
X1284948Y76712D01*
G02Y78766I1096J1027D01*
G01X1284974Y78793D01*
X1285002Y78864D01*
Y79214D01*
X1284974Y79285D01*
X1284948Y79312D01*
G02Y81366I1096J1027D01*
G01X1284974Y81393D01*
X1285002Y81464D01*
Y81814D01*
X1284974Y81885D01*
X1284948Y81912D01*
G02Y83966I1096J1027D01*
G01X1284974Y83993D01*
X1285002Y84064D01*
Y84414D01*
X1284974Y84485D01*
X1284948Y84512D01*
G02X1284542Y85539I1096J1027D01*
G37*
G36*
G01X1536905D02*
G02X1539909I1502J0D01*
G02X1539503Y84512I-1502J0D01*
G01X1539477Y84485D01*
X1539449Y84414D01*
Y84064D01*
X1539477Y83993D01*
X1539503Y83966D01*
G02Y81912I-1096J-1027D01*
G01X1539477Y81885D01*
X1539449Y81814D01*
Y81464D01*
X1539477Y81393D01*
X1539503Y81366D01*
G02Y79312I-1096J-1027D01*
G01X1539477Y79285D01*
X1539449Y79214D01*
Y78864D01*
X1539477Y78793D01*
X1539503Y78766D01*
G02Y76712I-1096J-1027D01*
G01X1539477Y76685D01*
X1539449Y76614D01*
Y76264D01*
X1539477Y76193D01*
X1539503Y76166D01*
G02X1539909Y75139I-1096J-1027D01*
G02X1536905I-1502J0D01*
G02X1537311Y76166I1502J0D01*
G01X1537337Y76193D01*
X1537365Y76264D01*
Y76614D01*
X1537337Y76685D01*
X1537311Y76712D01*
G02Y78766I1096J1027D01*
G01X1537337Y78793D01*
X1537365Y78864D01*
Y79214D01*
X1537337Y79285D01*
X1537311Y79312D01*
G02Y81366I1096J1027D01*
G01X1537337Y81393D01*
X1537365Y81464D01*
Y81814D01*
X1537337Y81885D01*
X1537311Y81912D01*
G02Y83966I1096J1027D01*
G01X1537337Y83993D01*
X1537365Y84064D01*
Y84414D01*
X1537337Y84485D01*
X1537311Y84512D01*
G02X1536905Y85539I1096J1027D01*
G37*
G36*
G01X1639267D02*
G02X1642271I1502J0D01*
G02X1641865Y84512I-1502J0D01*
G01X1641839Y84485D01*
X1641811Y84414D01*
Y84064D01*
X1641839Y83993D01*
X1641865Y83966D01*
G02Y81912I-1096J-1027D01*
G01X1641839Y81885D01*
X1641811Y81814D01*
Y81464D01*
X1641839Y81393D01*
X1641865Y81366D01*
G02Y79312I-1096J-1027D01*
G01X1641839Y79285D01*
X1641811Y79214D01*
Y78864D01*
X1641839Y78793D01*
X1641865Y78766D01*
G02Y76712I-1096J-1027D01*
G01X1641839Y76685D01*
X1641811Y76614D01*
Y76264D01*
X1641839Y76193D01*
X1641865Y76166D01*
G02X1642271Y75139I-1096J-1027D01*
G02X1639267I-1502J0D01*
G02X1639673Y76166I1502J0D01*
G01X1639699Y76193D01*
X1639727Y76264D01*
Y76614D01*
X1639699Y76685D01*
X1639673Y76712D01*
G02Y78766I1096J1027D01*
G01X1639699Y78793D01*
X1639727Y78864D01*
Y79214D01*
X1639699Y79285D01*
X1639673Y79312D01*
G02Y81366I1096J1027D01*
G01X1639699Y81393D01*
X1639727Y81464D01*
Y81814D01*
X1639699Y81885D01*
X1639673Y81912D01*
G02Y83966I1096J1027D01*
G01X1639699Y83993D01*
X1639727Y84064D01*
Y84414D01*
X1639699Y84485D01*
X1639673Y84512D01*
G02X1639267Y85539I1096J1027D01*
G37*
G36*
G01X1741629D02*
G02X1744633I1502J0D01*
G02X1744227Y84512I-1502J0D01*
G01X1744201Y84485D01*
X1744173Y84414D01*
Y84064D01*
X1744201Y83993D01*
X1744227Y83966D01*
G02Y81912I-1096J-1027D01*
G01X1744201Y81885D01*
X1744173Y81814D01*
Y81464D01*
X1744201Y81393D01*
X1744227Y81366D01*
G02Y79312I-1096J-1027D01*
G01X1744201Y79285D01*
X1744173Y79214D01*
Y78864D01*
X1744201Y78793D01*
X1744227Y78766D01*
G02Y76712I-1096J-1027D01*
G01X1744201Y76685D01*
X1744173Y76614D01*
Y76264D01*
X1744201Y76193D01*
X1744227Y76166D01*
G02X1744633Y75139I-1096J-1027D01*
G02X1741629I-1502J0D01*
G02X1742035Y76166I1502J0D01*
G01X1742061Y76193D01*
X1742089Y76264D01*
Y76614D01*
X1742061Y76685D01*
X1742035Y76712D01*
G02Y78766I1096J1027D01*
G01X1742061Y78793D01*
X1742089Y78864D01*
Y79214D01*
X1742061Y79285D01*
X1742035Y79312D01*
G02Y81366I1096J1027D01*
G01X1742061Y81393D01*
X1742089Y81464D01*
Y81814D01*
X1742061Y81885D01*
X1742035Y81912D01*
G02Y83966I1096J1027D01*
G01X1742061Y83993D01*
X1742089Y84064D01*
Y84414D01*
X1742061Y84485D01*
X1742035Y84512D01*
G02X1741629Y85539I1096J1027D01*
G37*
G36*
G01X106518Y117937D02*
Y118251D01*
G03X106441Y118409I-200J0D01*
G02X105862Y119594I923J1185D01*
G02X108866I1502J0D01*
G02X108287Y118409I-1502J0D01*
G03X108210Y118251I123J-158D01*
G01Y117937D01*
G03X108287Y117779I200J0D01*
G02X108866Y116594I-923J-1185D01*
G02X105862I-1502J0D01*
G02X106441Y117779I1502J0D01*
G03X106518Y117937I-123J158D01*
G37*
G36*
G01X118487D02*
Y118251D01*
G03X118410Y118409I-200J0D01*
G02X117831Y119594I923J1185D01*
G02X120835I1502J0D01*
G02X120256Y118409I-1502J0D01*
G03X120179Y118251I123J-158D01*
G01Y117937D01*
G03X120256Y117779I200J0D01*
G02X120835Y116594I-923J-1185D01*
G02X117831I-1502J0D01*
G02X118410Y117779I1502J0D01*
G03X118487Y117937I-123J158D01*
G37*
G36*
G01X208880D02*
Y118251D01*
G03X208803Y118409I-200J0D01*
G02X208224Y119594I923J1185D01*
G02X211228I1502J0D01*
G02X210649Y118409I-1502J0D01*
G03X210572Y118251I123J-158D01*
G01Y117937D01*
G03X210649Y117779I200J0D01*
G02X211228Y116594I-923J-1185D01*
G02X208224I-1502J0D01*
G02X208803Y117779I1502J0D01*
G03X208880Y117937I-123J158D01*
G37*
G36*
G01X220849D02*
Y118251D01*
G03X220772Y118409I-200J0D01*
G02X220193Y119594I923J1185D01*
G02X223197I1502J0D01*
G02X222618Y118409I-1502J0D01*
G03X222541Y118251I123J-158D01*
G01Y117937D01*
G03X222618Y117779I200J0D01*
G02X223197Y116594I-923J-1185D01*
G02X220193I-1502J0D01*
G02X220772Y117779I1502J0D01*
G03X220849Y117937I-123J158D01*
G37*
G36*
G01X311242D02*
Y118251D01*
G03X311165Y118409I-200J0D01*
G02X310586Y119594I923J1185D01*
G02X313590I1502J0D01*
G02X313011Y118409I-1502J0D01*
G03X312934Y118251I123J-158D01*
G01Y117937D01*
G03X313011Y117779I200J0D01*
G02X313590Y116594I-923J-1185D01*
G02X310586I-1502J0D01*
G02X311165Y117779I1502J0D01*
G03X311242Y117937I-123J158D01*
G37*
G36*
G01X323211D02*
Y118251D01*
G03X323134Y118409I-200J0D01*
G02X322555Y119594I923J1185D01*
G02X325559I1502J0D01*
G02X324980Y118409I-1502J0D01*
G03X324903Y118251I123J-158D01*
G01Y117937D01*
G03X324980Y117779I200J0D01*
G02X325559Y116594I-923J-1185D01*
G02X322555I-1502J0D01*
G02X323134Y117779I1502J0D01*
G03X323211Y117937I-123J158D01*
G37*
G36*
G01X461243D02*
Y118251D01*
G03X461166Y118409I-200J0D01*
G02X460587Y119594I923J1185D01*
G02X463591I1502J0D01*
G02X463012Y118409I-1502J0D01*
G03X462935Y118251I123J-158D01*
G01Y117937D01*
G03X463012Y117779I200J0D01*
G02X463591Y116594I-923J-1185D01*
G02X460587I-1502J0D01*
G02X461166Y117779I1502J0D01*
G03X461243Y117937I-123J158D01*
G37*
G36*
G01X473212D02*
Y118251D01*
G03X473135Y118409I-200J0D01*
G02X472556Y119594I923J1185D01*
G02X475560I1502J0D01*
G02X474981Y118409I-1502J0D01*
G03X474904Y118251I123J-158D01*
G01Y117937D01*
G03X474981Y117779I200J0D01*
G02X475560Y116594I-923J-1185D01*
G02X472556I-1502J0D01*
G02X473135Y117779I1502J0D01*
G03X473212Y117937I-123J158D01*
G37*
G36*
G01X563605D02*
Y118251D01*
G03X563528Y118409I-200J0D01*
G02X562949Y119594I923J1185D01*
G02X565953I1502J0D01*
G02X565374Y118409I-1502J0D01*
G03X565297Y118251I123J-158D01*
G01Y117937D01*
G03X565374Y117779I200J0D01*
G02X565953Y116594I-923J-1185D01*
G02X562949I-1502J0D01*
G02X563528Y117779I1502J0D01*
G03X563605Y117937I-123J158D01*
G37*
G36*
G01X575574D02*
Y118251D01*
G03X575497Y118409I-200J0D01*
G02X574918Y119594I923J1185D01*
G02X577922I1502J0D01*
G02X577343Y118409I-1502J0D01*
G03X577266Y118251I123J-158D01*
G01Y117937D01*
G03X577343Y117779I200J0D01*
G02X577922Y116594I-923J-1185D01*
G02X574918I-1502J0D01*
G02X575497Y117779I1502J0D01*
G03X575574Y117937I-123J158D01*
G37*
G36*
G01X665967D02*
Y118251D01*
G03X665890Y118409I-200J0D01*
G02X665311Y119594I923J1185D01*
G02X668315I1502J0D01*
G02X667736Y118409I-1502J0D01*
G03X667659Y118251I123J-158D01*
G01Y117937D01*
G03X667736Y117779I200J0D01*
G02X668315Y116594I-923J-1185D01*
G02X665311I-1502J0D01*
G02X665890Y117779I1502J0D01*
G03X665967Y117937I-123J158D01*
G37*
G36*
G01X677936D02*
Y118251D01*
G03X677859Y118409I-200J0D01*
G02X677280Y119594I923J1185D01*
G02X680284I1502J0D01*
G02X679705Y118409I-1502J0D01*
G03X679628Y118251I123J-158D01*
G01Y117937D01*
G03X679705Y117779I200J0D01*
G02X680284Y116594I-923J-1185D01*
G02X677280I-1502J0D01*
G02X677859Y117779I1502J0D01*
G03X677936Y117937I-123J158D01*
G37*
G36*
G01X768329D02*
Y118251D01*
G03X768252Y118409I-200J0D01*
G02X767673Y119594I923J1185D01*
G02X770677I1502J0D01*
G02X770098Y118409I-1502J0D01*
G03X770021Y118251I123J-158D01*
G01Y117937D01*
G03X770098Y117779I200J0D01*
G02X770677Y116594I-923J-1185D01*
G02X767673I-1502J0D01*
G02X768252Y117779I1502J0D01*
G03X768329Y117937I-123J158D01*
G37*
G36*
G01X780298D02*
Y118251D01*
G03X780221Y118409I-200J0D01*
G02X779642Y119594I923J1185D01*
G02X782646I1502J0D01*
G02X782067Y118409I-1502J0D01*
G03X781990Y118251I123J-158D01*
G01Y117937D01*
G03X782067Y117779I200J0D01*
G02X782646Y116594I-923J-1185D01*
G02X779642I-1502J0D01*
G02X780221Y117779I1502J0D01*
G03X780298Y117937I-123J158D01*
G37*
G36*
G01X918329D02*
Y118251D01*
G03X918252Y118409I-200J0D01*
G02X917673Y119594I923J1185D01*
G02X920677I1502J0D01*
G02X920098Y118409I-1502J0D01*
G03X920021Y118251I123J-158D01*
G01Y117937D01*
G03X920098Y117779I200J0D01*
G02X920677Y116594I-923J-1185D01*
G02X917673I-1502J0D01*
G02X918252Y117779I1502J0D01*
G03X918329Y117937I-123J158D01*
G37*
G36*
G01X930298D02*
Y118251D01*
G03X930221Y118409I-200J0D01*
G02X929642Y119594I923J1185D01*
G02X932646I1502J0D01*
G02X932067Y118409I-1502J0D01*
G03X931990Y118251I123J-158D01*
G01Y117937D01*
G03X932067Y117779I200J0D01*
G02X932646Y116594I-923J-1185D01*
G02X929642I-1502J0D01*
G02X930221Y117779I1502J0D01*
G03X930298Y117937I-123J158D01*
G37*
G36*
G01X1020691D02*
Y118251D01*
G03X1020614Y118409I-200J0D01*
G02X1020035Y119594I923J1185D01*
G02X1023039I1502J0D01*
G02X1022460Y118409I-1502J0D01*
G03X1022383Y118251I123J-158D01*
G01Y117937D01*
G03X1022460Y117779I200J0D01*
G02X1023039Y116594I-923J-1185D01*
G02X1020035I-1502J0D01*
G02X1020614Y117779I1502J0D01*
G03X1020691Y117937I-123J158D01*
G37*
G36*
G01X1032660D02*
Y118251D01*
G03X1032583Y118409I-200J0D01*
G02X1032004Y119594I923J1185D01*
G02X1035008I1502J0D01*
G02X1034429Y118409I-1502J0D01*
G03X1034352Y118251I123J-158D01*
G01Y117937D01*
G03X1034429Y117779I200J0D01*
G02X1035008Y116594I-923J-1185D01*
G02X1032004I-1502J0D01*
G02X1032583Y117779I1502J0D01*
G03X1032660Y117937I-123J158D01*
G37*
G36*
G01X1123053D02*
Y118251D01*
G03X1122976Y118409I-200J0D01*
G02X1122397Y119594I923J1185D01*
G02X1125401I1502J0D01*
G02X1124822Y118409I-1502J0D01*
G03X1124745Y118251I123J-158D01*
G01Y117937D01*
G03X1124822Y117779I200J0D01*
G02X1125401Y116594I-923J-1185D01*
G02X1122397I-1502J0D01*
G02X1122976Y117779I1502J0D01*
G03X1123053Y117937I-123J158D01*
G37*
G36*
G01X1135022D02*
Y118251D01*
G03X1134945Y118409I-200J0D01*
G02X1134366Y119594I923J1185D01*
G02X1137370I1502J0D01*
G02X1136791Y118409I-1502J0D01*
G03X1136714Y118251I123J-158D01*
G01Y117937D01*
G03X1136791Y117779I200J0D01*
G02X1137370Y116594I-923J-1185D01*
G02X1134366I-1502J0D01*
G02X1134945Y117779I1502J0D01*
G03X1135022Y117937I-123J158D01*
G37*
G36*
G01X1225415D02*
Y118251D01*
G03X1225338Y118409I-200J0D01*
G02X1224759Y119594I923J1185D01*
G02X1227763I1502J0D01*
G02X1227184Y118409I-1502J0D01*
G03X1227107Y118251I123J-158D01*
G01Y117937D01*
G03X1227184Y117779I200J0D01*
G02X1227763Y116594I-923J-1185D01*
G02X1224759I-1502J0D01*
G02X1225338Y117779I1502J0D01*
G03X1225415Y117937I-123J158D01*
G37*
G36*
G01X1237384D02*
Y118251D01*
G03X1237307Y118409I-200J0D01*
G02X1236728Y119594I923J1185D01*
G02X1239732I1502J0D01*
G02X1239153Y118409I-1502J0D01*
G03X1239076Y118251I123J-158D01*
G01Y117937D01*
G03X1239153Y117779I200J0D01*
G02X1239732Y116594I-923J-1185D01*
G02X1236728I-1502J0D01*
G02X1237307Y117779I1502J0D01*
G03X1237384Y117937I-123J158D01*
G37*
G36*
G01X1375416D02*
Y118251D01*
G03X1375339Y118409I-200J0D01*
G02X1374760Y119594I923J1185D01*
G02X1377764I1502J0D01*
G02X1377185Y118409I-1502J0D01*
G03X1377108Y118251I123J-158D01*
G01Y117937D01*
G03X1377185Y117779I200J0D01*
G02X1377764Y116594I-923J-1185D01*
G02X1374760I-1502J0D01*
G02X1375339Y117779I1502J0D01*
G03X1375416Y117937I-123J158D01*
G37*
G36*
G01X1387385D02*
Y118251D01*
G03X1387308Y118409I-200J0D01*
G02X1386729Y119594I923J1185D01*
G02X1389733I1502J0D01*
G02X1389154Y118409I-1502J0D01*
G03X1389077Y118251I123J-158D01*
G01Y117937D01*
G03X1389154Y117779I200J0D01*
G02X1389733Y116594I-923J-1185D01*
G02X1386729I-1502J0D01*
G02X1387308Y117779I1502J0D01*
G03X1387385Y117937I-123J158D01*
G37*
G36*
G01X1477778D02*
Y118251D01*
G03X1477701Y118409I-200J0D01*
G02X1477122Y119594I923J1185D01*
G02X1480126I1502J0D01*
G02X1479547Y118409I-1502J0D01*
G03X1479470Y118251I123J-158D01*
G01Y117937D01*
G03X1479547Y117779I200J0D01*
G02X1480126Y116594I-923J-1185D01*
G02X1477122I-1502J0D01*
G02X1477701Y117779I1502J0D01*
G03X1477778Y117937I-123J158D01*
G37*
G36*
G01X1489747D02*
Y118251D01*
G03X1489670Y118409I-200J0D01*
G02X1489091Y119594I923J1185D01*
G02X1492095I1502J0D01*
G02X1491516Y118409I-1502J0D01*
G03X1491439Y118251I123J-158D01*
G01Y117937D01*
G03X1491516Y117779I200J0D01*
G02X1492095Y116594I-923J-1185D01*
G02X1489091I-1502J0D01*
G02X1489670Y117779I1502J0D01*
G03X1489747Y117937I-123J158D01*
G37*
G36*
G01X1580140D02*
Y118251D01*
G03X1580063Y118409I-200J0D01*
G02X1579484Y119594I923J1185D01*
G02X1582488I1502J0D01*
G02X1581909Y118409I-1502J0D01*
G03X1581832Y118251I123J-158D01*
G01Y117937D01*
G03X1581909Y117779I200J0D01*
G02X1582488Y116594I-923J-1185D01*
G02X1579484I-1502J0D01*
G02X1580063Y117779I1502J0D01*
G03X1580140Y117937I-123J158D01*
G37*
G36*
G01X1592109D02*
Y118251D01*
G03X1592032Y118409I-200J0D01*
G02X1591453Y119594I923J1185D01*
G02X1594457I1502J0D01*
G02X1593878Y118409I-1502J0D01*
G03X1593801Y118251I123J-158D01*
G01Y117937D01*
G03X1593878Y117779I200J0D01*
G02X1594457Y116594I-923J-1185D01*
G02X1591453I-1502J0D01*
G02X1592032Y117779I1502J0D01*
G03X1592109Y117937I-123J158D01*
G37*
G36*
G01X1682502D02*
Y118251D01*
G03X1682425Y118409I-200J0D01*
G02X1681846Y119594I923J1185D01*
G02X1684850I1502J0D01*
G02X1684271Y118409I-1502J0D01*
G03X1684194Y118251I123J-158D01*
G01Y117937D01*
G03X1684271Y117779I200J0D01*
G02X1684850Y116594I-923J-1185D01*
G02X1681846I-1502J0D01*
G02X1682425Y117779I1502J0D01*
G03X1682502Y117937I-123J158D01*
G37*
G36*
G01X1694471D02*
Y118251D01*
G03X1694394Y118409I-200J0D01*
G02X1693815Y119594I923J1185D01*
G02X1696819I1502J0D01*
G02X1696240Y118409I-1502J0D01*
G03X1696163Y118251I123J-158D01*
G01Y117937D01*
G03X1696240Y117779I200J0D01*
G02X1696819Y116594I-923J-1185D01*
G02X1693815I-1502J0D01*
G02X1694394Y117779I1502J0D01*
G03X1694471Y117937I-123J158D01*
G37*
G36*
G01X10120Y160416D02*
Y160730D01*
G03X10043Y160888I-200J0D01*
G02X9464Y162073I923J1185D01*
G02X12468I1502J0D01*
G02X11889Y160888I-1502J0D01*
G03X11812Y160730I123J-158D01*
G01Y160416D01*
G03X11889Y160258I200J0D01*
G02X12468Y159073I-923J-1185D01*
G02X9464I-1502J0D01*
G02X10043Y160258I1502J0D01*
G03X10120Y160416I-123J158D01*
G37*
G36*
G01X22089D02*
Y160730D01*
G03X22012Y160888I-200J0D01*
G02X21433Y162073I923J1185D01*
G02X24437I1502J0D01*
G02X23858Y160888I-1502J0D01*
G03X23781Y160730I123J-158D01*
G01Y160416D01*
G03X23858Y160258I200J0D01*
G02X24437Y159073I-923J-1185D01*
G02X21433I-1502J0D01*
G02X22012Y160258I1502J0D01*
G03X22089Y160416I-123J158D01*
G37*
G36*
G01X63878Y160866D02*
G02Y163870I0J1502D01*
G02X64905Y163464I0J-1502D01*
G01X64932Y163438D01*
X65003Y163410D01*
X65353D01*
X65424Y163438D01*
X65451Y163464D01*
G02X66478Y163870I1027J-1096D01*
G02Y160866I0J-1502D01*
G02X65451Y161272I0J1502D01*
G01X65424Y161298D01*
X65353Y161326D01*
X65003D01*
X64932Y161298D01*
X64905Y161272D01*
G02X63878Y160866I-1027J1096D01*
G37*
G36*
G01X166240D02*
G02Y163870I0J1502D01*
G02X167267Y163464I0J-1502D01*
G01X167294Y163438D01*
X167365Y163410D01*
X167715D01*
X167786Y163438D01*
X167813Y163464D01*
G02X168840Y163870I1027J-1096D01*
G02Y160866I0J-1502D01*
G02X167813Y161272I0J1502D01*
G01X167786Y161298D01*
X167715Y161326D01*
X167365D01*
X167294Y161298D01*
X167267Y161272D01*
G02X166240Y160866I-1027J1096D01*
G37*
G36*
G01X268602D02*
G02Y163870I0J1502D01*
G02X269629Y163464I0J-1502D01*
G01X269656Y163438D01*
X269727Y163410D01*
X270077D01*
X270148Y163438D01*
X270175Y163464D01*
G02X271202Y163870I1027J-1096D01*
G02Y160866I0J-1502D01*
G02X270175Y161272I0J1502D01*
G01X270148Y161298D01*
X270077Y161326D01*
X269727D01*
X269656Y161298D01*
X269629Y161272D01*
G02X268602Y160866I-1027J1096D01*
G37*
G36*
G01X370964D02*
G02Y163870I0J1502D01*
G02X371991Y163464I0J-1502D01*
G01X372018Y163438D01*
X372089Y163410D01*
X372439D01*
X372510Y163438D01*
X372537Y163464D01*
G02X373564Y163870I1027J-1096D01*
G02Y160866I0J-1502D01*
G02X372537Y161272I0J1502D01*
G01X372510Y161298D01*
X372439Y161326D01*
X372089D01*
X372018Y161298D01*
X371991Y161272D01*
G02X370964Y160866I-1027J1096D01*
G37*
G36*
G01X520965D02*
G02Y163870I0J1502D01*
G02X521992Y163464I0J-1502D01*
G01X522019Y163438D01*
X522090Y163410D01*
X522440D01*
X522511Y163438D01*
X522538Y163464D01*
G02X523565Y163870I1027J-1096D01*
G02Y160866I0J-1502D01*
G02X522538Y161272I0J1502D01*
G01X522511Y161298D01*
X522440Y161326D01*
X522090D01*
X522019Y161298D01*
X521992Y161272D01*
G02X520965Y160866I-1027J1096D01*
G37*
G36*
G01X725689D02*
G02Y163870I0J1502D01*
G02X726716Y163464I0J-1502D01*
G01X726743Y163438D01*
X726814Y163410D01*
X727164D01*
X727235Y163438D01*
X727262Y163464D01*
G02X728289Y163870I1027J-1096D01*
G02Y160866I0J-1502D01*
G02X727262Y161272I0J1502D01*
G01X727235Y161298D01*
X727164Y161326D01*
X726814D01*
X726743Y161298D01*
X726716Y161272D01*
G02X725689Y160866I-1027J1096D01*
G37*
G36*
G01X828051D02*
G02Y163870I0J1502D01*
G02X829078Y163464I0J-1502D01*
G01X829105Y163438D01*
X829176Y163410D01*
X829526D01*
X829597Y163438D01*
X829624Y163464D01*
G02X830651Y163870I1027J-1096D01*
G02Y160866I0J-1502D01*
G02X829624Y161272I0J1502D01*
G01X829597Y161298D01*
X829526Y161326D01*
X829176D01*
X829105Y161298D01*
X829078Y161272D01*
G02X828051Y160866I-1027J1096D01*
G37*
G36*
G01X978051D02*
G02Y163870I0J1502D01*
G02X979078Y163464I0J-1502D01*
G01X979105Y163438D01*
X979176Y163410D01*
X979526D01*
X979597Y163438D01*
X979624Y163464D01*
G02X980651Y163870I1027J-1096D01*
G02Y160866I0J-1502D01*
G02X979624Y161272I0J1502D01*
G01X979597Y161298D01*
X979526Y161326D01*
X979176D01*
X979105Y161298D01*
X979078Y161272D01*
G02X978051Y160866I-1027J1096D01*
G37*
G36*
G01X1080413D02*
G02Y163870I0J1502D01*
G02X1081440Y163464I0J-1502D01*
G01X1081467Y163438D01*
X1081538Y163410D01*
X1081888D01*
X1081959Y163438D01*
X1081986Y163464D01*
G02X1083013Y163870I1027J-1096D01*
G02Y160866I0J-1502D01*
G02X1081986Y161272I0J1502D01*
G01X1081959Y161298D01*
X1081888Y161326D01*
X1081538D01*
X1081467Y161298D01*
X1081440Y161272D01*
G02X1080413Y160866I-1027J1096D01*
G37*
G36*
G01X1182775D02*
G02Y163870I0J1502D01*
G02X1183802Y163464I0J-1502D01*
G01X1183829Y163438D01*
X1183900Y163410D01*
X1184250D01*
X1184321Y163438D01*
X1184348Y163464D01*
G02X1185375Y163870I1027J-1096D01*
G02Y160866I0J-1502D01*
G02X1184348Y161272I0J1502D01*
G01X1184321Y161298D01*
X1184250Y161326D01*
X1183900D01*
X1183829Y161298D01*
X1183802Y161272D01*
G02X1182775Y160866I-1027J1096D01*
G37*
G36*
G01X1285137D02*
G02Y163870I0J1502D01*
G02X1286164Y163464I0J-1502D01*
G01X1286191Y163438D01*
X1286262Y163410D01*
X1286612D01*
X1286683Y163438D01*
X1286710Y163464D01*
G02X1287737Y163870I1027J-1096D01*
G02Y160866I0J-1502D01*
G02X1286710Y161272I0J1502D01*
G01X1286683Y161298D01*
X1286612Y161326D01*
X1286262D01*
X1286191Y161298D01*
X1286164Y161272D01*
G02X1285137Y160866I-1027J1096D01*
G37*
G36*
G01X1435138D02*
G02Y163870I0J1502D01*
G02X1436165Y163464I0J-1502D01*
G01X1436192Y163438D01*
X1436263Y163410D01*
X1436613D01*
X1436684Y163438D01*
X1436711Y163464D01*
G02X1437738Y163870I1027J-1096D01*
G02Y160866I0J-1502D01*
G02X1436711Y161272I0J1502D01*
G01X1436684Y161298D01*
X1436613Y161326D01*
X1436263D01*
X1436192Y161298D01*
X1436165Y161272D01*
G02X1435138Y160866I-1027J1096D01*
G37*
G36*
G01X1537500D02*
G02Y163870I0J1502D01*
G02X1538527Y163464I0J-1502D01*
G01X1538554Y163438D01*
X1538625Y163410D01*
X1538975D01*
X1539046Y163438D01*
X1539073Y163464D01*
G02X1540100Y163870I1027J-1096D01*
G02Y160866I0J-1502D01*
G02X1539073Y161272I0J1502D01*
G01X1539046Y161298D01*
X1538975Y161326D01*
X1538625D01*
X1538554Y161298D01*
X1538527Y161272D01*
G02X1537500Y160866I-1027J1096D01*
G37*
G36*
G01X1639862D02*
G02Y163870I0J1502D01*
G02X1640889Y163464I0J-1502D01*
G01X1640916Y163438D01*
X1640987Y163410D01*
X1641337D01*
X1641408Y163438D01*
X1641435Y163464D01*
G02X1642462Y163870I1027J-1096D01*
G02Y160866I0J-1502D01*
G02X1641435Y161272I0J1502D01*
G01X1641408Y161298D01*
X1641337Y161326D01*
X1640987D01*
X1640916Y161298D01*
X1640889Y161272D01*
G02X1639862Y160866I-1027J1096D01*
G37*
G36*
G01X1742224D02*
G02Y163870I0J1502D01*
G02X1743251Y163464I0J-1502D01*
G01X1743278Y163438D01*
X1743349Y163410D01*
X1743699D01*
X1743770Y163438D01*
X1743797Y163464D01*
G02X1744824Y163870I1027J-1096D01*
G02Y160866I0J-1502D01*
G02X1743797Y161272I0J1502D01*
G01X1743770Y161298D01*
X1743699Y161326D01*
X1743349D01*
X1743278Y161298D01*
X1743251Y161272D01*
G02X1742224Y160866I-1027J1096D01*
G37*
G36*
G01X72076Y170493D02*
G02X75080I1502J0D01*
G02X74710Y169506I-1501J0D01*
G01Y169505D01*
X74709D01*
G03X74661Y169375I152J-130D01*
G01Y169111D01*
G03X74709Y168981I200J0D01*
G01X74710Y168980D01*
G02X75080Y167993I-1131J-987D01*
G02X74674Y166966I-1502J0D01*
G01X74648Y166939D01*
X74620Y166868D01*
Y166518D01*
X74648Y166447D01*
X74674Y166420D01*
G02Y164366I-1096J-1027D01*
G01X74648Y164339D01*
X74620Y164268D01*
Y163918D01*
X74648Y163847D01*
X74674Y163820D01*
G02X75080Y162793I-1096J-1027D01*
G02X72076I-1502J0D01*
G02X72482Y163820I1502J0D01*
G01X72508Y163847D01*
X72536Y163918D01*
Y164268D01*
X72508Y164339D01*
X72482Y164366D01*
G02Y166420I1096J1027D01*
G01X72508Y166447D01*
X72536Y166518D01*
Y166868D01*
X72508Y166939D01*
X72482Y166966D01*
G02X72076Y167993I1096J1027D01*
G02X72446Y168980I1501J0D01*
G01Y168981D01*
X72447D01*
G03X72495Y169111I-152J130D01*
G01Y169375D01*
G03X72447Y169505I-200J0D01*
G01X72446Y169506D01*
G02X72076Y170493I1131J987D01*
G37*
G36*
G01X174438D02*
G02X177442I1502J0D01*
G02X177072Y169506I-1501J0D01*
G01Y169505D01*
X177071D01*
G03X177023Y169375I152J-130D01*
G01Y169111D01*
G03X177071Y168981I200J0D01*
G01X177072Y168980D01*
G02X177442Y167993I-1131J-987D01*
G02X177036Y166966I-1502J0D01*
G01X177010Y166939D01*
X176982Y166868D01*
Y166518D01*
X177010Y166447D01*
X177036Y166420D01*
G02Y164366I-1096J-1027D01*
G01X177010Y164339D01*
X176982Y164268D01*
Y163918D01*
X177010Y163847D01*
X177036Y163820D01*
G02X177442Y162793I-1096J-1027D01*
G02X174438I-1502J0D01*
G02X174844Y163820I1502J0D01*
G01X174870Y163847D01*
X174898Y163918D01*
Y164268D01*
X174870Y164339D01*
X174844Y164366D01*
G02Y166420I1096J1027D01*
G01X174870Y166447D01*
X174898Y166518D01*
Y166868D01*
X174870Y166939D01*
X174844Y166966D01*
G02X174438Y167993I1096J1027D01*
G02X174808Y168980I1501J0D01*
G01Y168981D01*
X174809D01*
G03X174857Y169111I-152J130D01*
G01Y169375D01*
G03X174809Y169505I-200J0D01*
G01X174808Y169506D01*
G02X174438Y170493I1131J987D01*
G37*
G36*
G01X276800D02*
G02X279804I1502J0D01*
G02X279434Y169506I-1501J0D01*
G01Y169505D01*
X279433D01*
G03X279385Y169375I152J-130D01*
G01Y169111D01*
G03X279433Y168981I200J0D01*
G01X279434Y168980D01*
G02X279804Y167993I-1131J-987D01*
G02X279398Y166966I-1502J0D01*
G01X279372Y166939D01*
X279344Y166868D01*
Y166518D01*
X279372Y166447D01*
X279398Y166420D01*
G02Y164366I-1096J-1027D01*
G01X279372Y164339D01*
X279344Y164268D01*
Y163918D01*
X279372Y163847D01*
X279398Y163820D01*
G02X279804Y162793I-1096J-1027D01*
G02X276800I-1502J0D01*
G02X277206Y163820I1502J0D01*
G01X277232Y163847D01*
X277260Y163918D01*
Y164268D01*
X277232Y164339D01*
X277206Y164366D01*
G02Y166420I1096J1027D01*
G01X277232Y166447D01*
X277260Y166518D01*
Y166868D01*
X277232Y166939D01*
X277206Y166966D01*
G02X276800Y167993I1096J1027D01*
G02X277170Y168980I1501J0D01*
G01Y168981D01*
X277171D01*
G03X277219Y169111I-152J130D01*
G01Y169375D01*
G03X277171Y169505I-200J0D01*
G01X277170Y169506D01*
G02X276800Y170493I1131J987D01*
G37*
G36*
G01X379162D02*
G02X382166I1502J0D01*
G02X381796Y169506I-1501J0D01*
G01Y169505D01*
X381795D01*
G03X381747Y169375I152J-130D01*
G01Y169111D01*
G03X381795Y168981I200J0D01*
G01X381796Y168980D01*
G02X382166Y167993I-1131J-987D01*
G02X381760Y166966I-1502J0D01*
G01X381734Y166939D01*
X381706Y166868D01*
Y166518D01*
X381734Y166447D01*
X381760Y166420D01*
G02Y164366I-1096J-1027D01*
G01X381734Y164339D01*
X381706Y164268D01*
Y163918D01*
X381734Y163847D01*
X381760Y163820D01*
G02X382166Y162793I-1096J-1027D01*
G02X379162I-1502J0D01*
G02X379568Y163820I1502J0D01*
G01X379594Y163847D01*
X379622Y163918D01*
Y164268D01*
X379594Y164339D01*
X379568Y164366D01*
G02Y166420I1096J1027D01*
G01X379594Y166447D01*
X379622Y166518D01*
Y166868D01*
X379594Y166939D01*
X379568Y166966D01*
G02X379162Y167993I1096J1027D01*
G02X379532Y168980I1501J0D01*
G01Y168981D01*
X379533D01*
G03X379581Y169111I-152J130D01*
G01Y169375D01*
G03X379533Y169505I-200J0D01*
G01X379532Y169506D01*
G02X379162Y170493I1131J987D01*
G37*
G36*
G01X529163D02*
G02X532167I1502J0D01*
G02X531797Y169506I-1501J0D01*
G01Y169505D01*
X531796D01*
G03X531748Y169375I152J-130D01*
G01Y169111D01*
G03X531796Y168981I200J0D01*
G01X531797Y168980D01*
G02X532167Y167993I-1131J-987D01*
G02X531761Y166966I-1502J0D01*
G01X531735Y166939D01*
X531707Y166868D01*
Y166518D01*
X531735Y166447D01*
X531761Y166420D01*
G02Y164366I-1096J-1027D01*
G01X531735Y164339D01*
X531707Y164268D01*
Y163918D01*
X531735Y163847D01*
X531761Y163820D01*
G02X532167Y162793I-1096J-1027D01*
G02X529163I-1502J0D01*
G02X529569Y163820I1502J0D01*
G01X529595Y163847D01*
X529623Y163918D01*
Y164268D01*
X529595Y164339D01*
X529569Y164366D01*
G02Y166420I1096J1027D01*
G01X529595Y166447D01*
X529623Y166518D01*
Y166868D01*
X529595Y166939D01*
X529569Y166966D01*
G02X529163Y167993I1096J1027D01*
G02X529533Y168980I1501J0D01*
G01Y168981D01*
X529534D01*
G03X529582Y169111I-152J130D01*
G01Y169375D01*
G03X529534Y169505I-200J0D01*
G01X529533Y169506D01*
G02X529163Y170493I1131J987D01*
G37*
G36*
G01X631525D02*
G02X634529I1502J0D01*
G02X634159Y169506I-1501J0D01*
G01Y169505D01*
X634158D01*
G03X634110Y169375I152J-130D01*
G01Y169111D01*
G03X634158Y168981I200J0D01*
G01X634159Y168980D01*
G02X634529Y167993I-1131J-987D01*
G02X634123Y166966I-1502J0D01*
G01X634097Y166939D01*
X634069Y166868D01*
Y166518D01*
X634097Y166447D01*
X634123Y166420D01*
G02Y164366I-1096J-1027D01*
G01X634097Y164339D01*
X634069Y164268D01*
Y163918D01*
X634097Y163847D01*
X634123Y163820D01*
G02X634529Y162793I-1096J-1027D01*
G02X631525I-1502J0D01*
G02X631931Y163820I1502J0D01*
G01X631957Y163847D01*
X631985Y163918D01*
Y164268D01*
X631957Y164339D01*
X631931Y164366D01*
G02Y166420I1096J1027D01*
G01X631957Y166447D01*
X631985Y166518D01*
Y166868D01*
X631957Y166939D01*
X631931Y166966D01*
G02X631525Y167993I1096J1027D01*
G02X631895Y168980I1501J0D01*
G01Y168981D01*
X631896D01*
G03X631944Y169111I-152J130D01*
G01Y169375D01*
G03X631896Y169505I-200J0D01*
G01X631895Y169506D01*
G02X631525Y170493I1131J987D01*
G37*
G36*
G01X733887D02*
G02X736891I1502J0D01*
G02X736521Y169506I-1501J0D01*
G01Y169505D01*
X736520D01*
G03X736472Y169375I152J-130D01*
G01Y169111D01*
G03X736520Y168981I200J0D01*
G01X736521Y168980D01*
G02X736891Y167993I-1131J-987D01*
G02X736485Y166966I-1502J0D01*
G01X736459Y166939D01*
X736431Y166868D01*
Y166518D01*
X736459Y166447D01*
X736485Y166420D01*
G02Y164366I-1096J-1027D01*
G01X736459Y164339D01*
X736431Y164268D01*
Y163918D01*
X736459Y163847D01*
X736485Y163820D01*
G02X736891Y162793I-1096J-1027D01*
G02X733887I-1502J0D01*
G02X734293Y163820I1502J0D01*
G01X734319Y163847D01*
X734347Y163918D01*
Y164268D01*
X734319Y164339D01*
X734293Y164366D01*
G02Y166420I1096J1027D01*
G01X734319Y166447D01*
X734347Y166518D01*
Y166868D01*
X734319Y166939D01*
X734293Y166966D01*
G02X733887Y167993I1096J1027D01*
G02X734257Y168980I1501J0D01*
G01Y168981D01*
X734258D01*
G03X734306Y169111I-152J130D01*
G01Y169375D01*
G03X734258Y169505I-200J0D01*
G01X734257Y169506D01*
G02X733887Y170493I1131J987D01*
G37*
G36*
G01X836249D02*
G02X839253I1502J0D01*
G02X838883Y169506I-1501J0D01*
G01Y169505D01*
X838882D01*
G03X838834Y169375I152J-130D01*
G01Y169111D01*
G03X838882Y168981I200J0D01*
G01X838883Y168980D01*
G02X839253Y167993I-1131J-987D01*
G02X838847Y166966I-1502J0D01*
G01X838821Y166939D01*
X838793Y166868D01*
Y166518D01*
X838821Y166447D01*
X838847Y166420D01*
G02Y164366I-1096J-1027D01*
G01X838821Y164339D01*
X838793Y164268D01*
Y163918D01*
X838821Y163847D01*
X838847Y163820D01*
G02X839253Y162793I-1096J-1027D01*
G02X836249I-1502J0D01*
G02X836655Y163820I1502J0D01*
G01X836681Y163847D01*
X836709Y163918D01*
Y164268D01*
X836681Y164339D01*
X836655Y164366D01*
G02Y166420I1096J1027D01*
G01X836681Y166447D01*
X836709Y166518D01*
Y166868D01*
X836681Y166939D01*
X836655Y166966D01*
G02X836249Y167993I1096J1027D01*
G02X836619Y168980I1501J0D01*
G01Y168981D01*
X836620D01*
G03X836668Y169111I-152J130D01*
G01Y169375D01*
G03X836620Y169505I-200J0D01*
G01X836619Y169506D01*
G02X836249Y170493I1131J987D01*
G37*
G36*
G01X986249D02*
G02X989253I1502J0D01*
G02X988883Y169506I-1501J0D01*
G01Y169505D01*
X988882D01*
G03X988834Y169375I152J-130D01*
G01Y169111D01*
G03X988882Y168981I200J0D01*
G01X988883Y168980D01*
G02X989253Y167993I-1131J-987D01*
G02X988847Y166966I-1502J0D01*
G01X988821Y166939D01*
X988793Y166868D01*
Y166518D01*
X988821Y166447D01*
X988847Y166420D01*
G02Y164366I-1096J-1027D01*
G01X988821Y164339D01*
X988793Y164268D01*
Y163918D01*
X988821Y163847D01*
X988847Y163820D01*
G02X989253Y162793I-1096J-1027D01*
G02X986249I-1502J0D01*
G02X986655Y163820I1502J0D01*
G01X986681Y163847D01*
X986709Y163918D01*
Y164268D01*
X986681Y164339D01*
X986655Y164366D01*
G02Y166420I1096J1027D01*
G01X986681Y166447D01*
X986709Y166518D01*
Y166868D01*
X986681Y166939D01*
X986655Y166966D01*
G02X986249Y167993I1096J1027D01*
G02X986619Y168980I1501J0D01*
G01Y168981D01*
X986620D01*
G03X986668Y169111I-152J130D01*
G01Y169375D01*
G03X986620Y169505I-200J0D01*
G01X986619Y169506D01*
G02X986249Y170493I1131J987D01*
G37*
G36*
G01X1088611D02*
G02X1091615I1502J0D01*
G02X1091245Y169506I-1501J0D01*
G01Y169505D01*
X1091244D01*
G03X1091196Y169375I152J-130D01*
G01Y169111D01*
G03X1091244Y168981I200J0D01*
G01X1091245Y168980D01*
G02X1091615Y167993I-1131J-987D01*
G02X1091209Y166966I-1502J0D01*
G01X1091183Y166939D01*
X1091155Y166868D01*
Y166518D01*
X1091183Y166447D01*
X1091209Y166420D01*
G02Y164366I-1096J-1027D01*
G01X1091183Y164339D01*
X1091155Y164268D01*
Y163918D01*
X1091183Y163847D01*
X1091209Y163820D01*
G02X1091615Y162793I-1096J-1027D01*
G02X1088611I-1502J0D01*
G02X1089017Y163820I1502J0D01*
G01X1089043Y163847D01*
X1089071Y163918D01*
Y164268D01*
X1089043Y164339D01*
X1089017Y164366D01*
G02Y166420I1096J1027D01*
G01X1089043Y166447D01*
X1089071Y166518D01*
Y166868D01*
X1089043Y166939D01*
X1089017Y166966D01*
G02X1088611Y167993I1096J1027D01*
G02X1088981Y168980I1501J0D01*
G01Y168981D01*
X1088982D01*
G03X1089030Y169111I-152J130D01*
G01Y169375D01*
G03X1088982Y169505I-200J0D01*
G01X1088981Y169506D01*
G02X1088611Y170493I1131J987D01*
G37*
G36*
G01X1190973D02*
G02X1193977I1502J0D01*
G02X1193607Y169506I-1501J0D01*
G01Y169505D01*
X1193606D01*
G03X1193558Y169375I152J-130D01*
G01Y169111D01*
G03X1193606Y168981I200J0D01*
G01X1193607Y168980D01*
G02X1193977Y167993I-1131J-987D01*
G02X1193571Y166966I-1502J0D01*
G01X1193545Y166939D01*
X1193517Y166868D01*
Y166518D01*
X1193545Y166447D01*
X1193571Y166420D01*
G02Y164366I-1096J-1027D01*
G01X1193545Y164339D01*
X1193517Y164268D01*
Y163918D01*
X1193545Y163847D01*
X1193571Y163820D01*
G02X1193977Y162793I-1096J-1027D01*
G02X1190973I-1502J0D01*
G02X1191379Y163820I1502J0D01*
G01X1191405Y163847D01*
X1191433Y163918D01*
Y164268D01*
X1191405Y164339D01*
X1191379Y164366D01*
G02Y166420I1096J1027D01*
G01X1191405Y166447D01*
X1191433Y166518D01*
Y166868D01*
X1191405Y166939D01*
X1191379Y166966D01*
G02X1190973Y167993I1096J1027D01*
G02X1191343Y168980I1501J0D01*
G01Y168981D01*
X1191344D01*
G03X1191392Y169111I-152J130D01*
G01Y169375D01*
G03X1191344Y169505I-200J0D01*
G01X1191343Y169506D01*
G02X1190973Y170493I1131J987D01*
G37*
G36*
G01X1293335D02*
G02X1296339I1502J0D01*
G02X1295969Y169506I-1501J0D01*
G01Y169505D01*
X1295968D01*
G03X1295920Y169375I152J-130D01*
G01Y169111D01*
G03X1295968Y168981I200J0D01*
G01X1295969Y168980D01*
G02X1296339Y167993I-1131J-987D01*
G02X1295933Y166966I-1502J0D01*
G01X1295907Y166939D01*
X1295879Y166868D01*
Y166518D01*
X1295907Y166447D01*
X1295933Y166420D01*
G02Y164366I-1096J-1027D01*
G01X1295907Y164339D01*
X1295879Y164268D01*
Y163918D01*
X1295907Y163847D01*
X1295933Y163820D01*
G02X1296339Y162793I-1096J-1027D01*
G02X1293335I-1502J0D01*
G02X1293741Y163820I1502J0D01*
G01X1293767Y163847D01*
X1293795Y163918D01*
Y164268D01*
X1293767Y164339D01*
X1293741Y164366D01*
G02Y166420I1096J1027D01*
G01X1293767Y166447D01*
X1293795Y166518D01*
Y166868D01*
X1293767Y166939D01*
X1293741Y166966D01*
G02X1293335Y167993I1096J1027D01*
G02X1293705Y168980I1501J0D01*
G01Y168981D01*
X1293706D01*
G03X1293754Y169111I-152J130D01*
G01Y169375D01*
G03X1293706Y169505I-200J0D01*
G01X1293705Y169506D01*
G02X1293335Y170493I1131J987D01*
G37*
G36*
G01X1443336D02*
G02X1446340I1502J0D01*
G02X1445970Y169506I-1501J0D01*
G01Y169505D01*
X1445969D01*
G03X1445921Y169375I152J-130D01*
G01Y169111D01*
G03X1445969Y168981I200J0D01*
G01X1445970Y168980D01*
G02X1446340Y167993I-1131J-987D01*
G02X1445934Y166966I-1502J0D01*
G01X1445908Y166939D01*
X1445880Y166868D01*
Y166518D01*
X1445908Y166447D01*
X1445934Y166420D01*
G02Y164366I-1096J-1027D01*
G01X1445908Y164339D01*
X1445880Y164268D01*
Y163918D01*
X1445908Y163847D01*
X1445934Y163820D01*
G02X1446340Y162793I-1096J-1027D01*
G02X1443336I-1502J0D01*
G02X1443742Y163820I1502J0D01*
G01X1443768Y163847D01*
X1443796Y163918D01*
Y164268D01*
X1443768Y164339D01*
X1443742Y164366D01*
G02Y166420I1096J1027D01*
G01X1443768Y166447D01*
X1443796Y166518D01*
Y166868D01*
X1443768Y166939D01*
X1443742Y166966D01*
G02X1443336Y167993I1096J1027D01*
G02X1443706Y168980I1501J0D01*
G01Y168981D01*
X1443707D01*
G03X1443755Y169111I-152J130D01*
G01Y169375D01*
G03X1443707Y169505I-200J0D01*
G01X1443706Y169506D01*
G02X1443336Y170493I1131J987D01*
G37*
G36*
G01X1545698D02*
G02X1548702I1502J0D01*
G02X1548332Y169506I-1501J0D01*
G01Y169505D01*
X1548331D01*
G03X1548283Y169375I152J-130D01*
G01Y169111D01*
G03X1548331Y168981I200J0D01*
G01X1548332Y168980D01*
G02X1548702Y167993I-1131J-987D01*
G02X1548296Y166966I-1502J0D01*
G01X1548270Y166939D01*
X1548242Y166868D01*
Y166518D01*
X1548270Y166447D01*
X1548296Y166420D01*
G02Y164366I-1096J-1027D01*
G01X1548270Y164339D01*
X1548242Y164268D01*
Y163918D01*
X1548270Y163847D01*
X1548296Y163820D01*
G02X1548702Y162793I-1096J-1027D01*
G02X1545698I-1502J0D01*
G02X1546104Y163820I1502J0D01*
G01X1546130Y163847D01*
X1546158Y163918D01*
Y164268D01*
X1546130Y164339D01*
X1546104Y164366D01*
G02Y166420I1096J1027D01*
G01X1546130Y166447D01*
X1546158Y166518D01*
Y166868D01*
X1546130Y166939D01*
X1546104Y166966D01*
G02X1545698Y167993I1096J1027D01*
G02X1546068Y168980I1501J0D01*
G01Y168981D01*
X1546069D01*
G03X1546117Y169111I-152J130D01*
G01Y169375D01*
G03X1546069Y169505I-200J0D01*
G01X1546068Y169506D01*
G02X1545698Y170493I1131J987D01*
G37*
G36*
G01X1648060D02*
G02X1651064I1502J0D01*
G02X1650694Y169506I-1501J0D01*
G01Y169505D01*
X1650693D01*
G03X1650645Y169375I152J-130D01*
G01Y169111D01*
G03X1650693Y168981I200J0D01*
G01X1650694Y168980D01*
G02X1651064Y167993I-1131J-987D01*
G02X1650658Y166966I-1502J0D01*
G01X1650632Y166939D01*
X1650604Y166868D01*
Y166518D01*
X1650632Y166447D01*
X1650658Y166420D01*
G02Y164366I-1096J-1027D01*
G01X1650632Y164339D01*
X1650604Y164268D01*
Y163918D01*
X1650632Y163847D01*
X1650658Y163820D01*
G02X1651064Y162793I-1096J-1027D01*
G02X1648060I-1502J0D01*
G02X1648466Y163820I1502J0D01*
G01X1648492Y163847D01*
X1648520Y163918D01*
Y164268D01*
X1648492Y164339D01*
X1648466Y164366D01*
G02Y166420I1096J1027D01*
G01X1648492Y166447D01*
X1648520Y166518D01*
Y166868D01*
X1648492Y166939D01*
X1648466Y166966D01*
G02X1648060Y167993I1096J1027D01*
G02X1648430Y168980I1501J0D01*
G01Y168981D01*
X1648431D01*
G03X1648479Y169111I-152J130D01*
G01Y169375D01*
G03X1648431Y169505I-200J0D01*
G01X1648430Y169506D01*
G02X1648060Y170493I1131J987D01*
G37*
G36*
G01X1750422D02*
G02X1753426I1502J0D01*
G02X1753056Y169506I-1501J0D01*
G01Y169505D01*
X1753055D01*
G03X1753007Y169375I152J-130D01*
G01Y169111D01*
G03X1753055Y168981I200J0D01*
G01X1753056Y168980D01*
G02X1753426Y167993I-1131J-987D01*
G02X1753020Y166966I-1502J0D01*
G01X1752994Y166939D01*
X1752966Y166868D01*
Y166518D01*
X1752994Y166447D01*
X1753020Y166420D01*
G02Y164366I-1096J-1027D01*
G01X1752994Y164339D01*
X1752966Y164268D01*
Y163918D01*
X1752994Y163847D01*
X1753020Y163820D01*
G02X1753426Y162793I-1096J-1027D01*
G02X1750422I-1502J0D01*
G02X1750828Y163820I1502J0D01*
G01X1750854Y163847D01*
X1750882Y163918D01*
Y164268D01*
X1750854Y164339D01*
X1750828Y164366D01*
G02Y166420I1096J1027D01*
G01X1750854Y166447D01*
X1750882Y166518D01*
Y166868D01*
X1750854Y166939D01*
X1750828Y166966D01*
G02X1750422Y167993I1096J1027D01*
G02X1750792Y168980I1501J0D01*
G01Y168981D01*
X1750793D01*
G03X1750841Y169111I-152J130D01*
G01Y169375D01*
G03X1750793Y169505I-200J0D01*
G01X1750792Y169506D01*
G02X1750422Y170493I1131J987D01*
G37*
G36*
G01X946393Y181479D02*
X946394Y181478D01*
G03X946524Y181430I130J152D01*
G01X946788D01*
G03X946918Y181478I0J200D01*
G01X946919Y181479D01*
G02X947906Y181849I987J-1131D01*
G02Y178845I0J-1502D01*
G02X946919Y179215I0J1501D01*
G01X946918D01*
Y179216D01*
G03X946788Y179264I-130J-152D01*
G01X946524D01*
G03X946394Y179216I0J-200D01*
G01X946393Y179215D01*
G02X944419I-987J1131D01*
G01X944418D01*
Y179216D01*
G03X944288Y179264I-130J-152D01*
G01X944024D01*
G03X943894Y179216I0J-200D01*
G01X943893Y179215D01*
G02X941919I-987J1131D01*
G01X941918D01*
Y179216D01*
G03X941788Y179264I-130J-152D01*
G01X941524D01*
G03X941394Y179216I0J-200D01*
G01X941393Y179215D01*
G02X940406Y178845I-987J1131D01*
G02Y181849I0J1502D01*
G02X941393Y181479I0J-1501D01*
G01X941394D01*
Y181478D01*
G03X941524Y181430I130J152D01*
G01X941788D01*
G03X941918Y181478I0J200D01*
G01X941919Y181479D01*
G02X943893I987J-1131D01*
G01X943894D01*
Y181478D01*
G03X944024Y181430I130J152D01*
G01X944288D01*
G03X944418Y181478I0J200D01*
G01X944419Y181479D01*
G02X946393I987J-1131D01*
G37*
G36*
G01X98137Y186629D02*
G02X101141I1502J0D01*
G02X100138Y185212I-1502J0D01*
G01X100137D01*
G03X100015Y185090I67J-189D01*
G01X99912Y184796D01*
G03X99929Y184625I188J-68D01*
G01X99930Y184624D01*
G02X100155Y183834I-1277J-791D01*
G02X97151I-1502J0D01*
G02X98154Y185251I1502J0D01*
G01X98155D01*
G03X98277Y185373I-67J189D01*
G01X98380Y185667D01*
G03X98363Y185838I-188J68D01*
G01X98362Y185839D01*
G02X98137Y186629I1277J791D01*
G37*
G36*
G01X200499D02*
G02X203503I1502J0D01*
G02X202500Y185212I-1502J0D01*
G01X202499D01*
G03X202377Y185090I67J-189D01*
G01X202274Y184796D01*
G03X202291Y184625I188J-68D01*
G01X202292Y184624D01*
G02X202517Y183834I-1277J-791D01*
G02X199513I-1502J0D01*
G02X200516Y185251I1502J0D01*
G01X200517D01*
G03X200639Y185373I-67J189D01*
G01X200742Y185667D01*
G03X200725Y185838I-188J68D01*
G01X200724Y185839D01*
G02X200499Y186629I1277J791D01*
G37*
G36*
G01X302861D02*
G02X305865I1502J0D01*
G02X304862Y185212I-1502J0D01*
G01X304861D01*
G03X304739Y185090I67J-189D01*
G01X304636Y184796D01*
G03X304653Y184625I188J-68D01*
G01X304654Y184624D01*
G02X304879Y183834I-1277J-791D01*
G02X301875I-1502J0D01*
G02X302878Y185251I1502J0D01*
G01X302879D01*
G03X303001Y185373I-67J189D01*
G01X303104Y185667D01*
G03X303087Y185838I-188J68D01*
G01X303086Y185839D01*
G02X302861Y186629I1277J791D01*
G37*
G36*
G01X555224D02*
G02X558228I1502J0D01*
G02X557225Y185212I-1502J0D01*
G01X557224D01*
G03X557102Y185090I67J-189D01*
G01X556999Y184796D01*
G03X557016Y184625I188J-68D01*
G01X557017Y184624D01*
G02X557242Y183834I-1277J-791D01*
G02X554238I-1502J0D01*
G02X555241Y185251I1502J0D01*
G01X555242D01*
G03X555364Y185373I-67J189D01*
G01X555467Y185667D01*
G03X555450Y185838I-188J68D01*
G01X555449Y185839D01*
G02X555224Y186629I1277J791D01*
G37*
G36*
G01X657586D02*
G02X660590I1502J0D01*
G02X659587Y185212I-1502J0D01*
G01X659586D01*
G03X659464Y185090I67J-189D01*
G01X659361Y184796D01*
G03X659378Y184625I188J-68D01*
G01X659379Y184624D01*
G02X659604Y183834I-1277J-791D01*
G02X656600I-1502J0D01*
G02X657603Y185251I1502J0D01*
G01X657604D01*
G03X657726Y185373I-67J189D01*
G01X657829Y185667D01*
G03X657812Y185838I-188J68D01*
G01X657811Y185839D01*
G02X657586Y186629I1277J791D01*
G37*
G36*
G01X759948D02*
G02X762952I1502J0D01*
G02X761949Y185212I-1502J0D01*
G01X761948D01*
G03X761826Y185090I67J-189D01*
G01X761723Y184796D01*
G03X761740Y184625I188J-68D01*
G01X761741Y184624D01*
G02X761966Y183834I-1277J-791D01*
G02X758962I-1502J0D01*
G02X759965Y185251I1502J0D01*
G01X759966D01*
G03X760088Y185373I-67J189D01*
G01X760191Y185667D01*
G03X760174Y185838I-188J68D01*
G01X760173Y185839D01*
G02X759948Y186629I1277J791D01*
G37*
G36*
G01X862310D02*
G02X865314I1502J0D01*
G02X864311Y185212I-1502J0D01*
G01X864310D01*
G03X864188Y185090I67J-189D01*
G01X864085Y184796D01*
G03X864102Y184625I188J-68D01*
G01X864103Y184624D01*
G02X864328Y183834I-1277J-791D01*
G02X861324I-1502J0D01*
G02X862327Y185251I1502J0D01*
G01X862328D01*
G03X862450Y185373I-67J189D01*
G01X862553Y185667D01*
G03X862536Y185838I-188J68D01*
G01X862535Y185839D01*
G02X862310Y186629I1277J791D01*
G37*
G36*
G01X1012310D02*
G02X1015314I1502J0D01*
G02X1014311Y185212I-1502J0D01*
G01X1014310D01*
G03X1014188Y185090I67J-189D01*
G01X1014085Y184796D01*
G03X1014102Y184625I188J-68D01*
G01X1014103Y184624D01*
G02X1014328Y183834I-1277J-791D01*
G02X1011324I-1502J0D01*
G02X1012327Y185251I1502J0D01*
G01X1012328D01*
G03X1012450Y185373I-67J189D01*
G01X1012553Y185667D01*
G03X1012536Y185838I-188J68D01*
G01X1012535Y185839D01*
G02X1012310Y186629I1277J791D01*
G37*
G36*
G01X1114672D02*
G02X1117676I1502J0D01*
G02X1116673Y185212I-1502J0D01*
G01X1116672D01*
G03X1116550Y185090I67J-189D01*
G01X1116447Y184796D01*
G03X1116464Y184625I188J-68D01*
G01X1116465Y184624D01*
G02X1116690Y183834I-1277J-791D01*
G02X1113686I-1502J0D01*
G02X1114689Y185251I1502J0D01*
G01X1114690D01*
G03X1114812Y185373I-67J189D01*
G01X1114915Y185667D01*
G03X1114898Y185838I-188J68D01*
G01X1114897Y185839D01*
G02X1114672Y186629I1277J791D01*
G37*
G36*
G01X1217034D02*
G02X1220038I1502J0D01*
G02X1219035Y185212I-1502J0D01*
G01X1219034D01*
G03X1218912Y185090I67J-189D01*
G01X1218809Y184796D01*
G03X1218826Y184625I188J-68D01*
G01X1218827Y184624D01*
G02X1219052Y183834I-1277J-791D01*
G02X1216048I-1502J0D01*
G02X1217051Y185251I1502J0D01*
G01X1217052D01*
G03X1217174Y185373I-67J189D01*
G01X1217277Y185667D01*
G03X1217260Y185838I-188J68D01*
G01X1217259Y185839D01*
G02X1217034Y186629I1277J791D01*
G37*
G36*
G01X1319396D02*
G02X1322400I1502J0D01*
G02X1321397Y185212I-1502J0D01*
G01X1321396D01*
G03X1321274Y185090I67J-189D01*
G01X1321171Y184796D01*
G03X1321188Y184625I188J-68D01*
G01X1321189Y184624D01*
G02X1321414Y183834I-1277J-791D01*
G02X1318410I-1502J0D01*
G02X1319413Y185251I1502J0D01*
G01X1319414D01*
G03X1319536Y185373I-67J189D01*
G01X1319639Y185667D01*
G03X1319622Y185838I-188J68D01*
G01X1319621Y185839D01*
G02X1319396Y186629I1277J791D01*
G37*
G36*
G01X1469397D02*
G02X1472401I1502J0D01*
G02X1471398Y185212I-1502J0D01*
G01X1471397D01*
G03X1471275Y185090I67J-189D01*
G01X1471172Y184796D01*
G03X1471189Y184625I188J-68D01*
G01X1471190Y184624D01*
G02X1471415Y183834I-1277J-791D01*
G02X1468411I-1502J0D01*
G02X1469414Y185251I1502J0D01*
G01X1469415D01*
G03X1469537Y185373I-67J189D01*
G01X1469640Y185667D01*
G03X1469623Y185838I-188J68D01*
G01X1469622Y185839D01*
G02X1469397Y186629I1277J791D01*
G37*
G36*
G01X1571759D02*
G02X1574763I1502J0D01*
G02X1573760Y185212I-1502J0D01*
G01X1573759D01*
G03X1573637Y185090I67J-189D01*
G01X1573534Y184796D01*
G03X1573551Y184625I188J-68D01*
G01X1573552Y184624D01*
G02X1573777Y183834I-1277J-791D01*
G02X1570773I-1502J0D01*
G02X1571776Y185251I1502J0D01*
G01X1571777D01*
G03X1571899Y185373I-67J189D01*
G01X1572002Y185667D01*
G03X1571985Y185838I-188J68D01*
G01X1571984Y185839D01*
G02X1571759Y186629I1277J791D01*
G37*
G36*
G01X1674121D02*
G02X1677125I1502J0D01*
G02X1676122Y185212I-1502J0D01*
G01X1676121D01*
G03X1675999Y185090I67J-189D01*
G01X1675896Y184796D01*
G03X1675913Y184625I188J-68D01*
G01X1675914Y184624D01*
G02X1676139Y183834I-1277J-791D01*
G02X1673135I-1502J0D01*
G02X1674138Y185251I1502J0D01*
G01X1674139D01*
G03X1674261Y185373I-67J189D01*
G01X1674364Y185667D01*
G03X1674347Y185838I-188J68D01*
G01X1674346Y185839D01*
G02X1674121Y186629I1277J791D01*
G37*
G36*
G01X1776483D02*
G02X1779487I1502J0D01*
G02X1778484Y185212I-1502J0D01*
G01X1778483D01*
G03X1778361Y185090I67J-189D01*
G01X1778258Y184796D01*
G03X1778275Y184625I188J-68D01*
G01X1778276Y184624D01*
G02X1778501Y183834I-1277J-791D01*
G02X1775497I-1502J0D01*
G02X1776500Y185251I1502J0D01*
G01X1776501D01*
G03X1776623Y185373I-67J189D01*
G01X1776726Y185667D01*
G03X1776709Y185838I-188J68D01*
G01X1776708Y185839D01*
G02X1776483Y186629I1277J791D01*
G37*
G36*
G01X942260Y190475D02*
G02Y193479I0J1502D01*
G02X943247Y193109I0J-1501D01*
G01X943248D01*
Y193108D01*
G03X943378Y193060I130J152D01*
G01X943642D01*
G03X943772Y193108I0J200D01*
G01X943773Y193109D01*
G02X944760Y193479I987J-1131D01*
G02Y190475I0J-1502D01*
G02X943773Y190845I0J1501D01*
G01X943772D01*
Y190846D01*
G03X943642Y190894I-130J-152D01*
G01X943378D01*
G03X943248Y190846I0J-200D01*
G01X943247Y190845D01*
G02X942260Y190475I-987J1131D01*
G37*
G36*
G01X31554Y196308D02*
X31555Y196307D01*
G03X31685Y196259I130J152D01*
G01X31949D01*
G03X32079Y196307I0J200D01*
G01X32080Y196308D01*
G02X33067Y196678I987J-1131D01*
G02Y193674I0J-1502D01*
G02X32080Y194044I0J1501D01*
G01X32079D01*
Y194045D01*
G03X31949Y194093I-130J-152D01*
G01X31685D01*
G03X31555Y194045I0J-200D01*
G01X31554Y194044D01*
G02X29580I-987J1131D01*
G01X29579D01*
Y194045D01*
G03X29449Y194093I-130J-152D01*
G01X29185D01*
G03X29055Y194045I0J-200D01*
G01X29054Y194044D01*
G02X27080I-987J1131D01*
G01X27079D01*
Y194045D01*
G03X26949Y194093I-130J-152D01*
G01X26685D01*
G03X26555Y194045I0J-200D01*
G01X26554Y194044D01*
G02X25567Y193674I-987J1131D01*
G02Y196678I0J1502D01*
G02X26554Y196308I0J-1501D01*
G01X26555D01*
Y196307D01*
G03X26685Y196259I130J152D01*
G01X26949D01*
G03X27079Y196307I0J200D01*
G01X27080Y196308D01*
G02X29054I987J-1131D01*
G01X29055D01*
Y196307D01*
G03X29185Y196259I130J152D01*
G01X29449D01*
G03X29579Y196307I0J200D01*
G01X29580Y196308D01*
G02X31554I987J-1131D01*
G37*
G36*
G01X133916D02*
X133917Y196307D01*
G03X134047Y196259I130J152D01*
G01X134311D01*
G03X134441Y196307I0J200D01*
G01X134442Y196308D01*
G02X135429Y196678I987J-1131D01*
G02Y193674I0J-1502D01*
G02X134442Y194044I0J1501D01*
G01X134441D01*
Y194045D01*
G03X134311Y194093I-130J-152D01*
G01X134047D01*
G03X133917Y194045I0J-200D01*
G01X133916Y194044D01*
G02X131942I-987J1131D01*
G01X131941D01*
Y194045D01*
G03X131811Y194093I-130J-152D01*
G01X131547D01*
G03X131417Y194045I0J-200D01*
G01X131416Y194044D01*
G02X129442I-987J1131D01*
G01X129441D01*
Y194045D01*
G03X129311Y194093I-130J-152D01*
G01X129047D01*
G03X128917Y194045I0J-200D01*
G01X128916Y194044D01*
G02X127929Y193674I-987J1131D01*
G02Y196678I0J1502D01*
G02X128916Y196308I0J-1501D01*
G01X128917D01*
Y196307D01*
G03X129047Y196259I130J152D01*
G01X129311D01*
G03X129441Y196307I0J200D01*
G01X129442Y196308D01*
G02X131416I987J-1131D01*
G01X131417D01*
Y196307D01*
G03X131547Y196259I130J152D01*
G01X131811D01*
G03X131941Y196307I0J200D01*
G01X131942Y196308D01*
G02X133916I987J-1131D01*
G37*
G36*
G01X236278D02*
X236279Y196307D01*
G03X236409Y196259I130J152D01*
G01X236673D01*
G03X236803Y196307I0J200D01*
G01X236804Y196308D01*
G02X237791Y196678I987J-1131D01*
G02Y193674I0J-1502D01*
G02X236804Y194044I0J1501D01*
G01X236803D01*
Y194045D01*
G03X236673Y194093I-130J-152D01*
G01X236409D01*
G03X236279Y194045I0J-200D01*
G01X236278Y194044D01*
G02X234304I-987J1131D01*
G01X234303D01*
Y194045D01*
G03X234173Y194093I-130J-152D01*
G01X233909D01*
G03X233779Y194045I0J-200D01*
G01X233778Y194044D01*
G02X231804I-987J1131D01*
G01X231803D01*
Y194045D01*
G03X231673Y194093I-130J-152D01*
G01X231409D01*
G03X231279Y194045I0J-200D01*
G01X231278Y194044D01*
G02X230291Y193674I-987J1131D01*
G02Y196678I0J1502D01*
G02X231278Y196308I0J-1501D01*
G01X231279D01*
Y196307D01*
G03X231409Y196259I130J152D01*
G01X231673D01*
G03X231803Y196307I0J200D01*
G01X231804Y196308D01*
G02X233778I987J-1131D01*
G01X233779D01*
Y196307D01*
G03X233909Y196259I130J152D01*
G01X234173D01*
G03X234303Y196307I0J200D01*
G01X234304Y196308D01*
G02X236278I987J-1131D01*
G37*
G36*
G01X338640D02*
X338641Y196307D01*
G03X338771Y196259I130J152D01*
G01X339035D01*
G03X339165Y196307I0J200D01*
G01X339166Y196308D01*
G02X340153Y196678I987J-1131D01*
G02Y193674I0J-1502D01*
G02X339166Y194044I0J1501D01*
G01X339165D01*
Y194045D01*
G03X339035Y194093I-130J-152D01*
G01X338771D01*
G03X338641Y194045I0J-200D01*
G01X338640Y194044D01*
G02X336666I-987J1131D01*
G01X336665D01*
Y194045D01*
G03X336535Y194093I-130J-152D01*
G01X336271D01*
G03X336141Y194045I0J-200D01*
G01X336140Y194044D01*
G02X334166I-987J1131D01*
G01X334165D01*
Y194045D01*
G03X334035Y194093I-130J-152D01*
G01X333771D01*
G03X333641Y194045I0J-200D01*
G01X333640Y194044D01*
G02X332653Y193674I-987J1131D01*
G02Y196678I0J1502D01*
G02X333640Y196308I0J-1501D01*
G01X333641D01*
Y196307D01*
G03X333771Y196259I130J152D01*
G01X334035D01*
G03X334165Y196307I0J200D01*
G01X334166Y196308D01*
G02X336140I987J-1131D01*
G01X336141D01*
Y196307D01*
G03X336271Y196259I130J152D01*
G01X336535D01*
G03X336665Y196307I0J200D01*
G01X336666Y196308D01*
G02X338640I987J-1131D01*
G37*
G36*
G01X488641D02*
X488642Y196307D01*
G03X488772Y196259I130J152D01*
G01X489036D01*
G03X489166Y196307I0J200D01*
G01X489167Y196308D01*
G02X490154Y196678I987J-1131D01*
G02Y193674I0J-1502D01*
G02X489167Y194044I0J1501D01*
G01X489166D01*
Y194045D01*
G03X489036Y194093I-130J-152D01*
G01X488772D01*
G03X488642Y194045I0J-200D01*
G01X488641Y194044D01*
G02X486667I-987J1131D01*
G01X486666D01*
Y194045D01*
G03X486536Y194093I-130J-152D01*
G01X486272D01*
G03X486142Y194045I0J-200D01*
G01X486141Y194044D01*
G02X484167I-987J1131D01*
G01X484166D01*
Y194045D01*
G03X484036Y194093I-130J-152D01*
G01X483772D01*
G03X483642Y194045I0J-200D01*
G01X483641Y194044D01*
G02X482654Y193674I-987J1131D01*
G02Y196678I0J1502D01*
G02X483641Y196308I0J-1501D01*
G01X483642D01*
Y196307D01*
G03X483772Y196259I130J152D01*
G01X484036D01*
G03X484166Y196307I0J200D01*
G01X484167Y196308D01*
G02X486141I987J-1131D01*
G01X486142D01*
Y196307D01*
G03X486272Y196259I130J152D01*
G01X486536D01*
G03X486666Y196307I0J200D01*
G01X486667Y196308D01*
G02X488641I987J-1131D01*
G37*
G36*
G01X591003D02*
X591004Y196307D01*
G03X591134Y196259I130J152D01*
G01X591398D01*
G03X591528Y196307I0J200D01*
G01X591529Y196308D01*
G02X592516Y196678I987J-1131D01*
G02Y193674I0J-1502D01*
G02X591529Y194044I0J1501D01*
G01X591528D01*
Y194045D01*
G03X591398Y194093I-130J-152D01*
G01X591134D01*
G03X591004Y194045I0J-200D01*
G01X591003Y194044D01*
G02X589029I-987J1131D01*
G01X589028D01*
Y194045D01*
G03X588898Y194093I-130J-152D01*
G01X588634D01*
G03X588504Y194045I0J-200D01*
G01X588503Y194044D01*
G02X586529I-987J1131D01*
G01X586528D01*
Y194045D01*
G03X586398Y194093I-130J-152D01*
G01X586134D01*
G03X586004Y194045I0J-200D01*
G01X586003Y194044D01*
G02X585016Y193674I-987J1131D01*
G02Y196678I0J1502D01*
G02X586003Y196308I0J-1501D01*
G01X586004D01*
Y196307D01*
G03X586134Y196259I130J152D01*
G01X586398D01*
G03X586528Y196307I0J200D01*
G01X586529Y196308D01*
G02X588503I987J-1131D01*
G01X588504D01*
Y196307D01*
G03X588634Y196259I130J152D01*
G01X588898D01*
G03X589028Y196307I0J200D01*
G01X589029Y196308D01*
G02X591003I987J-1131D01*
G37*
G36*
G01X693365D02*
X693366Y196307D01*
G03X693496Y196259I130J152D01*
G01X693760D01*
G03X693890Y196307I0J200D01*
G01X693891Y196308D01*
G02X694878Y196678I987J-1131D01*
G02Y193674I0J-1502D01*
G02X693891Y194044I0J1501D01*
G01X693890D01*
Y194045D01*
G03X693760Y194093I-130J-152D01*
G01X693496D01*
G03X693366Y194045I0J-200D01*
G01X693365Y194044D01*
G02X691391I-987J1131D01*
G01X691390D01*
Y194045D01*
G03X691260Y194093I-130J-152D01*
G01X690996D01*
G03X690866Y194045I0J-200D01*
G01X690865Y194044D01*
G02X688891I-987J1131D01*
G01X688890D01*
Y194045D01*
G03X688760Y194093I-130J-152D01*
G01X688496D01*
G03X688366Y194045I0J-200D01*
G01X688365Y194044D01*
G02X687378Y193674I-987J1131D01*
G02Y196678I0J1502D01*
G02X688365Y196308I0J-1501D01*
G01X688366D01*
Y196307D01*
G03X688496Y196259I130J152D01*
G01X688760D01*
G03X688890Y196307I0J200D01*
G01X688891Y196308D01*
G02X690865I987J-1131D01*
G01X690866D01*
Y196307D01*
G03X690996Y196259I130J152D01*
G01X691260D01*
G03X691390Y196307I0J200D01*
G01X691391Y196308D01*
G02X693365I987J-1131D01*
G37*
G36*
G01X795727D02*
X795728Y196307D01*
G03X795858Y196259I130J152D01*
G01X796122D01*
G03X796252Y196307I0J200D01*
G01X796253Y196308D01*
G02X797240Y196678I987J-1131D01*
G02Y193674I0J-1502D01*
G02X796253Y194044I0J1501D01*
G01X796252D01*
Y194045D01*
G03X796122Y194093I-130J-152D01*
G01X795858D01*
G03X795728Y194045I0J-200D01*
G01X795727Y194044D01*
G02X793753I-987J1131D01*
G01X793752D01*
Y194045D01*
G03X793622Y194093I-130J-152D01*
G01X793358D01*
G03X793228Y194045I0J-200D01*
G01X793227Y194044D01*
G02X791253I-987J1131D01*
G01X791252D01*
Y194045D01*
G03X791122Y194093I-130J-152D01*
G01X790858D01*
G03X790728Y194045I0J-200D01*
G01X790727Y194044D01*
G02X789740Y193674I-987J1131D01*
G02Y196678I0J1502D01*
G02X790727Y196308I0J-1501D01*
G01X790728D01*
Y196307D01*
G03X790858Y196259I130J152D01*
G01X791122D01*
G03X791252Y196307I0J200D01*
G01X791253Y196308D01*
G02X793227I987J-1131D01*
G01X793228D01*
Y196307D01*
G03X793358Y196259I130J152D01*
G01X793622D01*
G03X793752Y196307I0J200D01*
G01X793753Y196308D01*
G02X795727I987J-1131D01*
G37*
G36*
G01X1048089D02*
X1048090Y196307D01*
G03X1048220Y196259I130J152D01*
G01X1048484D01*
G03X1048614Y196307I0J200D01*
G01X1048615Y196308D01*
G02X1049602Y196678I987J-1131D01*
G02Y193674I0J-1502D01*
G02X1048615Y194044I0J1501D01*
G01X1048614D01*
Y194045D01*
G03X1048484Y194093I-130J-152D01*
G01X1048220D01*
G03X1048090Y194045I0J-200D01*
G01X1048089Y194044D01*
G02X1046115I-987J1131D01*
G01X1046114D01*
Y194045D01*
G03X1045984Y194093I-130J-152D01*
G01X1045720D01*
G03X1045590Y194045I0J-200D01*
G01X1045589Y194044D01*
G02X1043615I-987J1131D01*
G01X1043614D01*
Y194045D01*
G03X1043484Y194093I-130J-152D01*
G01X1043220D01*
G03X1043090Y194045I0J-200D01*
G01X1043089Y194044D01*
G02X1042102Y193674I-987J1131D01*
G02Y196678I0J1502D01*
G02X1043089Y196308I0J-1501D01*
G01X1043090D01*
Y196307D01*
G03X1043220Y196259I130J152D01*
G01X1043484D01*
G03X1043614Y196307I0J200D01*
G01X1043615Y196308D01*
G02X1045589I987J-1131D01*
G01X1045590D01*
Y196307D01*
G03X1045720Y196259I130J152D01*
G01X1045984D01*
G03X1046114Y196307I0J200D01*
G01X1046115Y196308D01*
G02X1048089I987J-1131D01*
G37*
G36*
G01X1150451D02*
X1150452Y196307D01*
G03X1150582Y196259I130J152D01*
G01X1150846D01*
G03X1150976Y196307I0J200D01*
G01X1150977Y196308D01*
G02X1151964Y196678I987J-1131D01*
G02Y193674I0J-1502D01*
G02X1150977Y194044I0J1501D01*
G01X1150976D01*
Y194045D01*
G03X1150846Y194093I-130J-152D01*
G01X1150582D01*
G03X1150452Y194045I0J-200D01*
G01X1150451Y194044D01*
G02X1148477I-987J1131D01*
G01X1148476D01*
Y194045D01*
G03X1148346Y194093I-130J-152D01*
G01X1148082D01*
G03X1147952Y194045I0J-200D01*
G01X1147951Y194044D01*
G02X1145977I-987J1131D01*
G01X1145976D01*
Y194045D01*
G03X1145846Y194093I-130J-152D01*
G01X1145582D01*
G03X1145452Y194045I0J-200D01*
G01X1145451Y194044D01*
G02X1144464Y193674I-987J1131D01*
G02Y196678I0J1502D01*
G02X1145451Y196308I0J-1501D01*
G01X1145452D01*
Y196307D01*
G03X1145582Y196259I130J152D01*
G01X1145846D01*
G03X1145976Y196307I0J200D01*
G01X1145977Y196308D01*
G02X1147951I987J-1131D01*
G01X1147952D01*
Y196307D01*
G03X1148082Y196259I130J152D01*
G01X1148346D01*
G03X1148476Y196307I0J200D01*
G01X1148477Y196308D01*
G02X1150451I987J-1131D01*
G37*
G36*
G01X1252813D02*
X1252814Y196307D01*
G03X1252944Y196259I130J152D01*
G01X1253208D01*
G03X1253338Y196307I0J200D01*
G01X1253339Y196308D01*
G02X1254326Y196678I987J-1131D01*
G02Y193674I0J-1502D01*
G02X1253339Y194044I0J1501D01*
G01X1253338D01*
Y194045D01*
G03X1253208Y194093I-130J-152D01*
G01X1252944D01*
G03X1252814Y194045I0J-200D01*
G01X1252813Y194044D01*
G02X1250839I-987J1131D01*
G01X1250838D01*
Y194045D01*
G03X1250708Y194093I-130J-152D01*
G01X1250444D01*
G03X1250314Y194045I0J-200D01*
G01X1250313Y194044D01*
G02X1248339I-987J1131D01*
G01X1248338D01*
Y194045D01*
G03X1248208Y194093I-130J-152D01*
G01X1247944D01*
G03X1247814Y194045I0J-200D01*
G01X1247813Y194044D01*
G02X1246826Y193674I-987J1131D01*
G02Y196678I0J1502D01*
G02X1247813Y196308I0J-1501D01*
G01X1247814D01*
Y196307D01*
G03X1247944Y196259I130J152D01*
G01X1248208D01*
G03X1248338Y196307I0J200D01*
G01X1248339Y196308D01*
G02X1250313I987J-1131D01*
G01X1250314D01*
Y196307D01*
G03X1250444Y196259I130J152D01*
G01X1250708D01*
G03X1250838Y196307I0J200D01*
G01X1250839Y196308D01*
G02X1252813I987J-1131D01*
G37*
G36*
G01X1402814D02*
X1402815Y196307D01*
G03X1402945Y196259I130J152D01*
G01X1403209D01*
G03X1403339Y196307I0J200D01*
G01X1403340Y196308D01*
G02X1404327Y196678I987J-1131D01*
G02Y193674I0J-1502D01*
G02X1403340Y194044I0J1501D01*
G01X1403339D01*
Y194045D01*
G03X1403209Y194093I-130J-152D01*
G01X1402945D01*
G03X1402815Y194045I0J-200D01*
G01X1402814Y194044D01*
G02X1400840I-987J1131D01*
G01X1400839D01*
Y194045D01*
G03X1400709Y194093I-130J-152D01*
G01X1400445D01*
G03X1400315Y194045I0J-200D01*
G01X1400314Y194044D01*
G02X1398340I-987J1131D01*
G01X1398339D01*
Y194045D01*
G03X1398209Y194093I-130J-152D01*
G01X1397945D01*
G03X1397815Y194045I0J-200D01*
G01X1397814Y194044D01*
G02X1396827Y193674I-987J1131D01*
G02Y196678I0J1502D01*
G02X1397814Y196308I0J-1501D01*
G01X1397815D01*
Y196307D01*
G03X1397945Y196259I130J152D01*
G01X1398209D01*
G03X1398339Y196307I0J200D01*
G01X1398340Y196308D01*
G02X1400314I987J-1131D01*
G01X1400315D01*
Y196307D01*
G03X1400445Y196259I130J152D01*
G01X1400709D01*
G03X1400839Y196307I0J200D01*
G01X1400840Y196308D01*
G02X1402814I987J-1131D01*
G37*
G36*
G01X1505176D02*
X1505177Y196307D01*
G03X1505307Y196259I130J152D01*
G01X1505571D01*
G03X1505701Y196307I0J200D01*
G01X1505702Y196308D01*
G02X1506689Y196678I987J-1131D01*
G02Y193674I0J-1502D01*
G02X1505702Y194044I0J1501D01*
G01X1505701D01*
Y194045D01*
G03X1505571Y194093I-130J-152D01*
G01X1505307D01*
G03X1505177Y194045I0J-200D01*
G01X1505176Y194044D01*
G02X1503202I-987J1131D01*
G01X1503201D01*
Y194045D01*
G03X1503071Y194093I-130J-152D01*
G01X1502807D01*
G03X1502677Y194045I0J-200D01*
G01X1502676Y194044D01*
G02X1500702I-987J1131D01*
G01X1500701D01*
Y194045D01*
G03X1500571Y194093I-130J-152D01*
G01X1500307D01*
G03X1500177Y194045I0J-200D01*
G01X1500176Y194044D01*
G02X1499189Y193674I-987J1131D01*
G02Y196678I0J1502D01*
G02X1500176Y196308I0J-1501D01*
G01X1500177D01*
Y196307D01*
G03X1500307Y196259I130J152D01*
G01X1500571D01*
G03X1500701Y196307I0J200D01*
G01X1500702Y196308D01*
G02X1502676I987J-1131D01*
G01X1502677D01*
Y196307D01*
G03X1502807Y196259I130J152D01*
G01X1503071D01*
G03X1503201Y196307I0J200D01*
G01X1503202Y196308D01*
G02X1505176I987J-1131D01*
G37*
G36*
G01X1607538D02*
X1607539Y196307D01*
G03X1607669Y196259I130J152D01*
G01X1607933D01*
G03X1608063Y196307I0J200D01*
G01X1608064Y196308D01*
G02X1609051Y196678I987J-1131D01*
G02Y193674I0J-1502D01*
G02X1608064Y194044I0J1501D01*
G01X1608063D01*
Y194045D01*
G03X1607933Y194093I-130J-152D01*
G01X1607669D01*
G03X1607539Y194045I0J-200D01*
G01X1607538Y194044D01*
G02X1605564I-987J1131D01*
G01X1605563D01*
Y194045D01*
G03X1605433Y194093I-130J-152D01*
G01X1605169D01*
G03X1605039Y194045I0J-200D01*
G01X1605038Y194044D01*
G02X1603064I-987J1131D01*
G01X1603063D01*
Y194045D01*
G03X1602933Y194093I-130J-152D01*
G01X1602669D01*
G03X1602539Y194045I0J-200D01*
G01X1602538Y194044D01*
G02X1601551Y193674I-987J1131D01*
G02Y196678I0J1502D01*
G02X1602538Y196308I0J-1501D01*
G01X1602539D01*
Y196307D01*
G03X1602669Y196259I130J152D01*
G01X1602933D01*
G03X1603063Y196307I0J200D01*
G01X1603064Y196308D01*
G02X1605038I987J-1131D01*
G01X1605039D01*
Y196307D01*
G03X1605169Y196259I130J152D01*
G01X1605433D01*
G03X1605563Y196307I0J200D01*
G01X1605564Y196308D01*
G02X1607538I987J-1131D01*
G37*
G36*
G01X1709900D02*
X1709901Y196307D01*
G03X1710031Y196259I130J152D01*
G01X1710295D01*
G03X1710425Y196307I0J200D01*
G01X1710426Y196308D01*
G02X1711413Y196678I987J-1131D01*
G02Y193674I0J-1502D01*
G02X1710426Y194044I0J1501D01*
G01X1710425D01*
Y194045D01*
G03X1710295Y194093I-130J-152D01*
G01X1710031D01*
G03X1709901Y194045I0J-200D01*
G01X1709900Y194044D01*
G02X1707926I-987J1131D01*
G01X1707925D01*
Y194045D01*
G03X1707795Y194093I-130J-152D01*
G01X1707531D01*
G03X1707401Y194045I0J-200D01*
G01X1707400Y194044D01*
G02X1705426I-987J1131D01*
G01X1705425D01*
Y194045D01*
G03X1705295Y194093I-130J-152D01*
G01X1705031D01*
G03X1704901Y194045I0J-200D01*
G01X1704900Y194044D01*
G02X1703913Y193674I-987J1131D01*
G02Y196678I0J1502D01*
G02X1704900Y196308I0J-1501D01*
G01X1704901D01*
Y196307D01*
G03X1705031Y196259I130J152D01*
G01X1705295D01*
G03X1705425Y196307I0J200D01*
G01X1705426Y196308D01*
G02X1707400I987J-1131D01*
G01X1707401D01*
Y196307D01*
G03X1707531Y196259I130J152D01*
G01X1707795D01*
G03X1707925Y196307I0J200D01*
G01X1707926Y196308D01*
G02X1709900I987J-1131D01*
G37*
G36*
G01X940487Y194178D02*
G02Y197182I0J1502D01*
G02X941474Y196812I0J-1501D01*
G01X941475D01*
Y196811D01*
G03X941605Y196763I130J152D01*
G01X941869D01*
G03X941999Y196811I0J200D01*
G01X942000Y196812D01*
G02X942987Y197182I987J-1131D01*
G02Y194178I0J-1502D01*
G02X942000Y194548I0J1501D01*
G01X941999D01*
Y194549D01*
G03X941869Y194597I-130J-152D01*
G01X941605D01*
G03X941475Y194549I0J-200D01*
G01X941474Y194548D01*
G02X940487Y194178I-987J1131D01*
G37*
G36*
G01X926645Y202304D02*
X926351D01*
G03X926204Y202239I1J-200D01*
G02X925098Y201754I-1106J1019D01*
G02Y204758I0J1502D01*
G02X926204Y204273I0J-1504D01*
G03X926351Y204208I148J135D01*
G01X926645D01*
G03X926792Y204273I-1J200D01*
G02X927898Y204758I1106J-1019D01*
G02Y201754I0J-1502D01*
G02X926792Y202239I0J1504D01*
G03X926645Y202304I-148J-135D01*
G37*
G36*
G01X90340Y207899D02*
X90341Y207898D01*
G03X90471Y207850I130J152D01*
G01X90735D01*
G03X90865Y207898I0J200D01*
G01X90866Y207899D01*
G02X91853Y208269I987J-1131D01*
G02Y205265I0J-1502D01*
G02X90866Y205635I0J1501D01*
G01X90865D01*
Y205636D01*
G03X90735Y205684I-130J-152D01*
G01X90471D01*
G03X90341Y205636I0J-200D01*
G01X90340Y205635D01*
G02X88366I-987J1131D01*
G01X88365D01*
Y205636D01*
G03X88235Y205684I-130J-152D01*
G01X87971D01*
G03X87841Y205636I0J-200D01*
G01X87840Y205635D01*
G02X86853Y205265I-987J1131D01*
G02Y208269I0J1502D01*
G02X87840Y207899I0J-1501D01*
G01X87841D01*
Y207898D01*
G03X87971Y207850I130J152D01*
G01X88235D01*
G03X88365Y207898I0J200D01*
G01X88366Y207899D01*
G02X90340I987J-1131D01*
G37*
G36*
G01X192702D02*
X192703Y207898D01*
G03X192833Y207850I130J152D01*
G01X193097D01*
G03X193227Y207898I0J200D01*
G01X193228Y207899D01*
G02X194215Y208269I987J-1131D01*
G02Y205265I0J-1502D01*
G02X193228Y205635I0J1501D01*
G01X193227D01*
Y205636D01*
G03X193097Y205684I-130J-152D01*
G01X192833D01*
G03X192703Y205636I0J-200D01*
G01X192702Y205635D01*
G02X190728I-987J1131D01*
G01X190727D01*
Y205636D01*
G03X190597Y205684I-130J-152D01*
G01X190333D01*
G03X190203Y205636I0J-200D01*
G01X190202Y205635D01*
G02X189215Y205265I-987J1131D01*
G02Y208269I0J1502D01*
G02X190202Y207899I0J-1501D01*
G01X190203D01*
Y207898D01*
G03X190333Y207850I130J152D01*
G01X190597D01*
G03X190727Y207898I0J200D01*
G01X190728Y207899D01*
G02X192702I987J-1131D01*
G37*
G36*
G01X295064D02*
X295065Y207898D01*
G03X295195Y207850I130J152D01*
G01X295459D01*
G03X295589Y207898I0J200D01*
G01X295590Y207899D01*
G02X296577Y208269I987J-1131D01*
G02Y205265I0J-1502D01*
G02X295590Y205635I0J1501D01*
G01X295589D01*
Y205636D01*
G03X295459Y205684I-130J-152D01*
G01X295195D01*
G03X295065Y205636I0J-200D01*
G01X295064Y205635D01*
G02X293090I-987J1131D01*
G01X293089D01*
Y205636D01*
G03X292959Y205684I-130J-152D01*
G01X292695D01*
G03X292565Y205636I0J-200D01*
G01X292564Y205635D01*
G02X291577Y205265I-987J1131D01*
G02Y208269I0J1502D01*
G02X292564Y207899I0J-1501D01*
G01X292565D01*
Y207898D01*
G03X292695Y207850I130J152D01*
G01X292959D01*
G03X293089Y207898I0J200D01*
G01X293090Y207899D01*
G02X295064I987J-1131D01*
G37*
G36*
G01X397426D02*
X397427Y207898D01*
G03X397557Y207850I130J152D01*
G01X397821D01*
G03X397951Y207898I0J200D01*
G01X397952Y207899D01*
G02X398939Y208269I987J-1131D01*
G02Y205265I0J-1502D01*
G02X397952Y205635I0J1501D01*
G01X397951D01*
Y205636D01*
G03X397821Y205684I-130J-152D01*
G01X397557D01*
G03X397427Y205636I0J-200D01*
G01X397426Y205635D01*
G02X395452I-987J1131D01*
G01X395451D01*
Y205636D01*
G03X395321Y205684I-130J-152D01*
G01X395057D01*
G03X394927Y205636I0J-200D01*
G01X394926Y205635D01*
G02X393939Y205265I-987J1131D01*
G02Y208269I0J1502D01*
G02X394926Y207899I0J-1501D01*
G01X394927D01*
Y207898D01*
G03X395057Y207850I130J152D01*
G01X395321D01*
G03X395451Y207898I0J200D01*
G01X395452Y207899D01*
G02X397426I987J-1131D01*
G37*
G36*
G01X547427D02*
X547428Y207898D01*
G03X547558Y207850I130J152D01*
G01X547822D01*
G03X547952Y207898I0J200D01*
G01X547953Y207899D01*
G02X548940Y208269I987J-1131D01*
G02Y205265I0J-1502D01*
G02X547953Y205635I0J1501D01*
G01X547952D01*
Y205636D01*
G03X547822Y205684I-130J-152D01*
G01X547558D01*
G03X547428Y205636I0J-200D01*
G01X547427Y205635D01*
G02X545453I-987J1131D01*
G01X545452D01*
Y205636D01*
G03X545322Y205684I-130J-152D01*
G01X545058D01*
G03X544928Y205636I0J-200D01*
G01X544927Y205635D01*
G02X543940Y205265I-987J1131D01*
G02Y208269I0J1502D01*
G02X544927Y207899I0J-1501D01*
G01X544928D01*
Y207898D01*
G03X545058Y207850I130J152D01*
G01X545322D01*
G03X545452Y207898I0J200D01*
G01X545453Y207899D01*
G02X547427I987J-1131D01*
G37*
G36*
G01X649789D02*
X649790Y207898D01*
G03X649920Y207850I130J152D01*
G01X650184D01*
G03X650314Y207898I0J200D01*
G01X650315Y207899D01*
G02X651302Y208269I987J-1131D01*
G02Y205265I0J-1502D01*
G02X650315Y205635I0J1501D01*
G01X650314D01*
Y205636D01*
G03X650184Y205684I-130J-152D01*
G01X649920D01*
G03X649790Y205636I0J-200D01*
G01X649789Y205635D01*
G02X647815I-987J1131D01*
G01X647814D01*
Y205636D01*
G03X647684Y205684I-130J-152D01*
G01X647420D01*
G03X647290Y205636I0J-200D01*
G01X647289Y205635D01*
G02X646302Y205265I-987J1131D01*
G02Y208269I0J1502D01*
G02X647289Y207899I0J-1501D01*
G01X647290D01*
Y207898D01*
G03X647420Y207850I130J152D01*
G01X647684D01*
G03X647814Y207898I0J200D01*
G01X647815Y207899D01*
G02X649789I987J-1131D01*
G37*
G36*
G01X752151D02*
X752152Y207898D01*
G03X752282Y207850I130J152D01*
G01X752546D01*
G03X752676Y207898I0J200D01*
G01X752677Y207899D01*
G02X753664Y208269I987J-1131D01*
G02Y205265I0J-1502D01*
G02X752677Y205635I0J1501D01*
G01X752676D01*
Y205636D01*
G03X752546Y205684I-130J-152D01*
G01X752282D01*
G03X752152Y205636I0J-200D01*
G01X752151Y205635D01*
G02X750177I-987J1131D01*
G01X750176D01*
Y205636D01*
G03X750046Y205684I-130J-152D01*
G01X749782D01*
G03X749652Y205636I0J-200D01*
G01X749651Y205635D01*
G02X748664Y205265I-987J1131D01*
G02Y208269I0J1502D01*
G02X749651Y207899I0J-1501D01*
G01X749652D01*
Y207898D01*
G03X749782Y207850I130J152D01*
G01X750046D01*
G03X750176Y207898I0J200D01*
G01X750177Y207899D01*
G02X752151I987J-1131D01*
G37*
G36*
G01X854513D02*
X854514Y207898D01*
G03X854644Y207850I130J152D01*
G01X854908D01*
G03X855038Y207898I0J200D01*
G01X855039Y207899D01*
G02X856026Y208269I987J-1131D01*
G02Y205265I0J-1502D01*
G02X855039Y205635I0J1501D01*
G01X855038D01*
Y205636D01*
G03X854908Y205684I-130J-152D01*
G01X854644D01*
G03X854514Y205636I0J-200D01*
G01X854513Y205635D01*
G02X852539I-987J1131D01*
G01X852538D01*
Y205636D01*
G03X852408Y205684I-130J-152D01*
G01X852144D01*
G03X852014Y205636I0J-200D01*
G01X852013Y205635D01*
G02X851026Y205265I-987J1131D01*
G02Y208269I0J1502D01*
G02X852013Y207899I0J-1501D01*
G01X852014D01*
Y207898D01*
G03X852144Y207850I130J152D01*
G01X852408D01*
G03X852538Y207898I0J200D01*
G01X852539Y207899D01*
G02X854513I987J-1131D01*
G37*
G36*
G01X1004513D02*
X1004514Y207898D01*
G03X1004644Y207850I130J152D01*
G01X1004908D01*
G03X1005038Y207898I0J200D01*
G01X1005039Y207899D01*
G02X1006026Y208269I987J-1131D01*
G02Y205265I0J-1502D01*
G02X1005039Y205635I0J1501D01*
G01X1005038D01*
Y205636D01*
G03X1004908Y205684I-130J-152D01*
G01X1004644D01*
G03X1004514Y205636I0J-200D01*
G01X1004513Y205635D01*
G02X1002539I-987J1131D01*
G01X1002538D01*
Y205636D01*
G03X1002408Y205684I-130J-152D01*
G01X1002144D01*
G03X1002014Y205636I0J-200D01*
G01X1002013Y205635D01*
G02X1001026Y205265I-987J1131D01*
G02Y208269I0J1502D01*
G02X1002013Y207899I0J-1501D01*
G01X1002014D01*
Y207898D01*
G03X1002144Y207850I130J152D01*
G01X1002408D01*
G03X1002538Y207898I0J200D01*
G01X1002539Y207899D01*
G02X1004513I987J-1131D01*
G37*
G36*
G01X1106875D02*
X1106876Y207898D01*
G03X1107006Y207850I130J152D01*
G01X1107270D01*
G03X1107400Y207898I0J200D01*
G01X1107401Y207899D01*
G02X1108388Y208269I987J-1131D01*
G02Y205265I0J-1502D01*
G02X1107401Y205635I0J1501D01*
G01X1107400D01*
Y205636D01*
G03X1107270Y205684I-130J-152D01*
G01X1107006D01*
G03X1106876Y205636I0J-200D01*
G01X1106875Y205635D01*
G02X1104901I-987J1131D01*
G01X1104900D01*
Y205636D01*
G03X1104770Y205684I-130J-152D01*
G01X1104506D01*
G03X1104376Y205636I0J-200D01*
G01X1104375Y205635D01*
G02X1103388Y205265I-987J1131D01*
G02Y208269I0J1502D01*
G02X1104375Y207899I0J-1501D01*
G01X1104376D01*
Y207898D01*
G03X1104506Y207850I130J152D01*
G01X1104770D01*
G03X1104900Y207898I0J200D01*
G01X1104901Y207899D01*
G02X1106875I987J-1131D01*
G37*
G36*
G01X1209237D02*
X1209238Y207898D01*
G03X1209368Y207850I130J152D01*
G01X1209632D01*
G03X1209762Y207898I0J200D01*
G01X1209763Y207899D01*
G02X1210750Y208269I987J-1131D01*
G02Y205265I0J-1502D01*
G02X1209763Y205635I0J1501D01*
G01X1209762D01*
Y205636D01*
G03X1209632Y205684I-130J-152D01*
G01X1209368D01*
G03X1209238Y205636I0J-200D01*
G01X1209237Y205635D01*
G02X1207263I-987J1131D01*
G01X1207262D01*
Y205636D01*
G03X1207132Y205684I-130J-152D01*
G01X1206868D01*
G03X1206738Y205636I0J-200D01*
G01X1206737Y205635D01*
G02X1205750Y205265I-987J1131D01*
G02Y208269I0J1502D01*
G02X1206737Y207899I0J-1501D01*
G01X1206738D01*
Y207898D01*
G03X1206868Y207850I130J152D01*
G01X1207132D01*
G03X1207262Y207898I0J200D01*
G01X1207263Y207899D01*
G02X1209237I987J-1131D01*
G37*
G36*
G01X1311599D02*
X1311600Y207898D01*
G03X1311730Y207850I130J152D01*
G01X1311994D01*
G03X1312124Y207898I0J200D01*
G01X1312125Y207899D01*
G02X1313112Y208269I987J-1131D01*
G02Y205265I0J-1502D01*
G02X1312125Y205635I0J1501D01*
G01X1312124D01*
Y205636D01*
G03X1311994Y205684I-130J-152D01*
G01X1311730D01*
G03X1311600Y205636I0J-200D01*
G01X1311599Y205635D01*
G02X1309625I-987J1131D01*
G01X1309624D01*
Y205636D01*
G03X1309494Y205684I-130J-152D01*
G01X1309230D01*
G03X1309100Y205636I0J-200D01*
G01X1309099Y205635D01*
G02X1308112Y205265I-987J1131D01*
G02Y208269I0J1502D01*
G02X1309099Y207899I0J-1501D01*
G01X1309100D01*
Y207898D01*
G03X1309230Y207850I130J152D01*
G01X1309494D01*
G03X1309624Y207898I0J200D01*
G01X1309625Y207899D01*
G02X1311599I987J-1131D01*
G37*
G36*
G01X1461600D02*
X1461601Y207898D01*
G03X1461731Y207850I130J152D01*
G01X1461995D01*
G03X1462125Y207898I0J200D01*
G01X1462126Y207899D01*
G02X1463113Y208269I987J-1131D01*
G02Y205265I0J-1502D01*
G02X1462126Y205635I0J1501D01*
G01X1462125D01*
Y205636D01*
G03X1461995Y205684I-130J-152D01*
G01X1461731D01*
G03X1461601Y205636I0J-200D01*
G01X1461600Y205635D01*
G02X1459626I-987J1131D01*
G01X1459625D01*
Y205636D01*
G03X1459495Y205684I-130J-152D01*
G01X1459231D01*
G03X1459101Y205636I0J-200D01*
G01X1459100Y205635D01*
G02X1458113Y205265I-987J1131D01*
G02Y208269I0J1502D01*
G02X1459100Y207899I0J-1501D01*
G01X1459101D01*
Y207898D01*
G03X1459231Y207850I130J152D01*
G01X1459495D01*
G03X1459625Y207898I0J200D01*
G01X1459626Y207899D01*
G02X1461600I987J-1131D01*
G37*
G36*
G01X1563962D02*
X1563963Y207898D01*
G03X1564093Y207850I130J152D01*
G01X1564357D01*
G03X1564487Y207898I0J200D01*
G01X1564488Y207899D01*
G02X1565475Y208269I987J-1131D01*
G02Y205265I0J-1502D01*
G02X1564488Y205635I0J1501D01*
G01X1564487D01*
Y205636D01*
G03X1564357Y205684I-130J-152D01*
G01X1564093D01*
G03X1563963Y205636I0J-200D01*
G01X1563962Y205635D01*
G02X1561988I-987J1131D01*
G01X1561987D01*
Y205636D01*
G03X1561857Y205684I-130J-152D01*
G01X1561593D01*
G03X1561463Y205636I0J-200D01*
G01X1561462Y205635D01*
G02X1560475Y205265I-987J1131D01*
G02Y208269I0J1502D01*
G02X1561462Y207899I0J-1501D01*
G01X1561463D01*
Y207898D01*
G03X1561593Y207850I130J152D01*
G01X1561857D01*
G03X1561987Y207898I0J200D01*
G01X1561988Y207899D01*
G02X1563962I987J-1131D01*
G37*
G36*
G01X1666324D02*
X1666325Y207898D01*
G03X1666455Y207850I130J152D01*
G01X1666719D01*
G03X1666849Y207898I0J200D01*
G01X1666850Y207899D01*
G02X1667837Y208269I987J-1131D01*
G02Y205265I0J-1502D01*
G02X1666850Y205635I0J1501D01*
G01X1666849D01*
Y205636D01*
G03X1666719Y205684I-130J-152D01*
G01X1666455D01*
G03X1666325Y205636I0J-200D01*
G01X1666324Y205635D01*
G02X1664350I-987J1131D01*
G01X1664349D01*
Y205636D01*
G03X1664219Y205684I-130J-152D01*
G01X1663955D01*
G03X1663825Y205636I0J-200D01*
G01X1663824Y205635D01*
G02X1662837Y205265I-987J1131D01*
G02Y208269I0J1502D01*
G02X1663824Y207899I0J-1501D01*
G01X1663825D01*
Y207898D01*
G03X1663955Y207850I130J152D01*
G01X1664219D01*
G03X1664349Y207898I0J200D01*
G01X1664350Y207899D01*
G02X1666324I987J-1131D01*
G37*
G36*
G01X1768686D02*
X1768687Y207898D01*
G03X1768817Y207850I130J152D01*
G01X1769081D01*
G03X1769211Y207898I0J200D01*
G01X1769212Y207899D01*
G02X1770199Y208269I987J-1131D01*
G02Y205265I0J-1502D01*
G02X1769212Y205635I0J1501D01*
G01X1769211D01*
Y205636D01*
G03X1769081Y205684I-130J-152D01*
G01X1768817D01*
G03X1768687Y205636I0J-200D01*
G01X1768686Y205635D01*
G02X1766712I-987J1131D01*
G01X1766711D01*
Y205636D01*
G03X1766581Y205684I-130J-152D01*
G01X1766317D01*
G03X1766187Y205636I0J-200D01*
G01X1766186Y205635D01*
G02X1765199Y205265I-987J1131D01*
G02Y208269I0J1502D01*
G02X1766186Y207899I0J-1501D01*
G01X1766187D01*
Y207898D01*
G03X1766317Y207850I130J152D01*
G01X1766581D01*
G03X1766711Y207898I0J200D01*
G01X1766712Y207899D01*
G02X1768686I987J-1131D01*
G37*
G36*
G01X27421Y205304D02*
G02Y208308I0J1502D01*
G02X28408Y207938I0J-1501D01*
G01X28409D01*
Y207937D01*
G03X28539Y207889I130J152D01*
G01X28803D01*
G03X28933Y207937I0J200D01*
G01X28934Y207938D01*
G02X29921Y208308I987J-1131D01*
G02Y205304I0J-1502D01*
G02X28934Y205674I0J1501D01*
G01X28933D01*
Y205675D01*
G03X28803Y205723I-130J-152D01*
G01X28539D01*
G03X28409Y205675I0J-200D01*
G01X28408Y205674D01*
G02X27421Y205304I-987J1131D01*
G37*
G36*
G01X129783D02*
G02Y208308I0J1502D01*
G02X130770Y207938I0J-1501D01*
G01X130771D01*
Y207937D01*
G03X130901Y207889I130J152D01*
G01X131165D01*
G03X131295Y207937I0J200D01*
G01X131296Y207938D01*
G02X132283Y208308I987J-1131D01*
G02Y205304I0J-1502D01*
G02X131296Y205674I0J1501D01*
G01X131295D01*
Y205675D01*
G03X131165Y205723I-130J-152D01*
G01X130901D01*
G03X130771Y205675I0J-200D01*
G01X130770Y205674D01*
G02X129783Y205304I-987J1131D01*
G37*
G36*
G01X232145D02*
G02Y208308I0J1502D01*
G02X233132Y207938I0J-1501D01*
G01X233133D01*
Y207937D01*
G03X233263Y207889I130J152D01*
G01X233527D01*
G03X233657Y207937I0J200D01*
G01X233658Y207938D01*
G02X234645Y208308I987J-1131D01*
G02Y205304I0J-1502D01*
G02X233658Y205674I0J1501D01*
G01X233657D01*
Y205675D01*
G03X233527Y205723I-130J-152D01*
G01X233263D01*
G03X233133Y205675I0J-200D01*
G01X233132Y205674D01*
G02X232145Y205304I-987J1131D01*
G37*
G36*
G01X334507D02*
G02Y208308I0J1502D01*
G02X335494Y207938I0J-1501D01*
G01X335495D01*
Y207937D01*
G03X335625Y207889I130J152D01*
G01X335889D01*
G03X336019Y207937I0J200D01*
G01X336020Y207938D01*
G02X337007Y208308I987J-1131D01*
G02Y205304I0J-1502D01*
G02X336020Y205674I0J1501D01*
G01X336019D01*
Y205675D01*
G03X335889Y205723I-130J-152D01*
G01X335625D01*
G03X335495Y205675I0J-200D01*
G01X335494Y205674D01*
G02X334507Y205304I-987J1131D01*
G37*
G36*
G01X484508D02*
G02Y208308I0J1502D01*
G02X485495Y207938I0J-1501D01*
G01X485496D01*
Y207937D01*
G03X485626Y207889I130J152D01*
G01X485890D01*
G03X486020Y207937I0J200D01*
G01X486021Y207938D01*
G02X487008Y208308I987J-1131D01*
G02Y205304I0J-1502D01*
G02X486021Y205674I0J1501D01*
G01X486020D01*
Y205675D01*
G03X485890Y205723I-130J-152D01*
G01X485626D01*
G03X485496Y205675I0J-200D01*
G01X485495Y205674D01*
G02X484508Y205304I-987J1131D01*
G37*
G36*
G01X586870D02*
G02Y208308I0J1502D01*
G02X587857Y207938I0J-1501D01*
G01X587858D01*
Y207937D01*
G03X587988Y207889I130J152D01*
G01X588252D01*
G03X588382Y207937I0J200D01*
G01X588383Y207938D01*
G02X589370Y208308I987J-1131D01*
G02Y205304I0J-1502D01*
G02X588383Y205674I0J1501D01*
G01X588382D01*
Y205675D01*
G03X588252Y205723I-130J-152D01*
G01X587988D01*
G03X587858Y205675I0J-200D01*
G01X587857Y205674D01*
G02X586870Y205304I-987J1131D01*
G37*
G36*
G01X689232D02*
G02Y208308I0J1502D01*
G02X690219Y207938I0J-1501D01*
G01X690220D01*
Y207937D01*
G03X690350Y207889I130J152D01*
G01X690614D01*
G03X690744Y207937I0J200D01*
G01X690745Y207938D01*
G02X691732Y208308I987J-1131D01*
G02Y205304I0J-1502D01*
G02X690745Y205674I0J1501D01*
G01X690744D01*
Y205675D01*
G03X690614Y205723I-130J-152D01*
G01X690350D01*
G03X690220Y205675I0J-200D01*
G01X690219Y205674D01*
G02X689232Y205304I-987J1131D01*
G37*
G36*
G01X791594D02*
G02Y208308I0J1502D01*
G02X792581Y207938I0J-1501D01*
G01X792582D01*
Y207937D01*
G03X792712Y207889I130J152D01*
G01X792976D01*
G03X793106Y207937I0J200D01*
G01X793107Y207938D01*
G02X794094Y208308I987J-1131D01*
G02Y205304I0J-1502D01*
G02X793107Y205674I0J1501D01*
G01X793106D01*
Y205675D01*
G03X792976Y205723I-130J-152D01*
G01X792712D01*
G03X792582Y205675I0J-200D01*
G01X792581Y205674D01*
G02X791594Y205304I-987J1131D01*
G37*
G36*
G01X1043956D02*
G02Y208308I0J1502D01*
G02X1044943Y207938I0J-1501D01*
G01X1044944D01*
Y207937D01*
G03X1045074Y207889I130J152D01*
G01X1045338D01*
G03X1045468Y207937I0J200D01*
G01X1045469Y207938D01*
G02X1046456Y208308I987J-1131D01*
G02Y205304I0J-1502D01*
G02X1045469Y205674I0J1501D01*
G01X1045468D01*
Y205675D01*
G03X1045338Y205723I-130J-152D01*
G01X1045074D01*
G03X1044944Y205675I0J-200D01*
G01X1044943Y205674D01*
G02X1043956Y205304I-987J1131D01*
G37*
G36*
G01X1146318D02*
G02Y208308I0J1502D01*
G02X1147305Y207938I0J-1501D01*
G01X1147306D01*
Y207937D01*
G03X1147436Y207889I130J152D01*
G01X1147700D01*
G03X1147830Y207937I0J200D01*
G01X1147831Y207938D01*
G02X1148818Y208308I987J-1131D01*
G02Y205304I0J-1502D01*
G02X1147831Y205674I0J1501D01*
G01X1147830D01*
Y205675D01*
G03X1147700Y205723I-130J-152D01*
G01X1147436D01*
G03X1147306Y205675I0J-200D01*
G01X1147305Y205674D01*
G02X1146318Y205304I-987J1131D01*
G37*
G36*
G01X1248680D02*
G02Y208308I0J1502D01*
G02X1249667Y207938I0J-1501D01*
G01X1249668D01*
Y207937D01*
G03X1249798Y207889I130J152D01*
G01X1250062D01*
G03X1250192Y207937I0J200D01*
G01X1250193Y207938D01*
G02X1251180Y208308I987J-1131D01*
G02Y205304I0J-1502D01*
G02X1250193Y205674I0J1501D01*
G01X1250192D01*
Y205675D01*
G03X1250062Y205723I-130J-152D01*
G01X1249798D01*
G03X1249668Y205675I0J-200D01*
G01X1249667Y205674D01*
G02X1248680Y205304I-987J1131D01*
G37*
G36*
G01X1398681D02*
G02Y208308I0J1502D01*
G02X1399668Y207938I0J-1501D01*
G01X1399669D01*
Y207937D01*
G03X1399799Y207889I130J152D01*
G01X1400063D01*
G03X1400193Y207937I0J200D01*
G01X1400194Y207938D01*
G02X1401181Y208308I987J-1131D01*
G02Y205304I0J-1502D01*
G02X1400194Y205674I0J1501D01*
G01X1400193D01*
Y205675D01*
G03X1400063Y205723I-130J-152D01*
G01X1399799D01*
G03X1399669Y205675I0J-200D01*
G01X1399668Y205674D01*
G02X1398681Y205304I-987J1131D01*
G37*
G36*
G01X1501043D02*
G02Y208308I0J1502D01*
G02X1502030Y207938I0J-1501D01*
G01X1502031D01*
Y207937D01*
G03X1502161Y207889I130J152D01*
G01X1502425D01*
G03X1502555Y207937I0J200D01*
G01X1502556Y207938D01*
G02X1503543Y208308I987J-1131D01*
G02Y205304I0J-1502D01*
G02X1502556Y205674I0J1501D01*
G01X1502555D01*
Y205675D01*
G03X1502425Y205723I-130J-152D01*
G01X1502161D01*
G03X1502031Y205675I0J-200D01*
G01X1502030Y205674D01*
G02X1501043Y205304I-987J1131D01*
G37*
G36*
G01X1603405D02*
G02Y208308I0J1502D01*
G02X1604392Y207938I0J-1501D01*
G01X1604393D01*
Y207937D01*
G03X1604523Y207889I130J152D01*
G01X1604787D01*
G03X1604917Y207937I0J200D01*
G01X1604918Y207938D01*
G02X1605905Y208308I987J-1131D01*
G02Y205304I0J-1502D01*
G02X1604918Y205674I0J1501D01*
G01X1604917D01*
Y205675D01*
G03X1604787Y205723I-130J-152D01*
G01X1604523D01*
G03X1604393Y205675I0J-200D01*
G01X1604392Y205674D01*
G02X1603405Y205304I-987J1131D01*
G37*
G36*
G01X1705767D02*
G02Y208308I0J1502D01*
G02X1706754Y207938I0J-1501D01*
G01X1706755D01*
Y207937D01*
G03X1706885Y207889I130J152D01*
G01X1707149D01*
G03X1707279Y207937I0J200D01*
G01X1707280Y207938D01*
G02X1708267Y208308I987J-1131D01*
G02Y205304I0J-1502D01*
G02X1707280Y205674I0J1501D01*
G01X1707279D01*
Y205675D01*
G03X1707149Y205723I-130J-152D01*
G01X1706885D01*
G03X1706755Y205675I0J-200D01*
G01X1706754Y205674D01*
G02X1705767Y205304I-987J1131D01*
G37*
G36*
G01X932909Y207141D02*
G02X935913I1502J0D01*
G02X935543Y206154I-1501J0D01*
G01Y206153D01*
X935542D01*
G03X935494Y206023I152J-130D01*
G01Y205759D01*
G03X935542Y205629I200J0D01*
G01X935543Y205628D01*
G02Y203654I-1131J-987D01*
G01Y203653D01*
X935542D01*
G03X935494Y203523I152J-130D01*
G01Y203259D01*
G03X935542Y203129I200J0D01*
G01X935543Y203128D01*
G02X935913Y202141I-1131J-987D01*
G02X934411Y200639I-1502J0D01*
G02X933556Y200906I0J1502D01*
G01X933522Y200929D01*
X933441Y200946D01*
X933074Y200866D01*
X933007Y200818D01*
X932986Y200783D01*
G02X931698Y200054I-1288J773D01*
G02Y203058I0J1502D01*
G02X932553Y202791I0J-1502D01*
G01X932587Y202768D01*
X932668Y202751D01*
X933035Y202831D01*
X933102Y202879D01*
X933123Y202914D01*
G02X933279Y203127I1285J-777D01*
G03X933280Y203129I-173J88D01*
G03X933328Y203259I-152J130D01*
G01Y203523D01*
G03X933280Y203653I-200J0D01*
G01X933279Y203654D01*
G02Y205628I1131J987D01*
G01Y205629D01*
X933280D01*
G03X933328Y205759I-152J130D01*
G01Y206023D01*
G03X933280Y206153I-200J0D01*
G01X933279Y206154D01*
G02X932909Y207141I1131J987D01*
G37*
G36*
G01X25648Y209007D02*
G02Y212011I0J1502D01*
G02X26635Y211641I0J-1501D01*
G01X26636D01*
Y211640D01*
G03X26766Y211592I130J152D01*
G01X27030D01*
G03X27160Y211640I0J200D01*
G01X27161Y211641D01*
G02X28148Y212011I987J-1131D01*
G02Y209007I0J-1502D01*
G02X27161Y209377I0J1501D01*
G01X27160D01*
Y209378D01*
G03X27030Y209426I-130J-152D01*
G01X26766D01*
G03X26636Y209378I0J-200D01*
G01X26635Y209377D01*
G02X25648Y209007I-987J1131D01*
G37*
G36*
G01X128010D02*
G02Y212011I0J1502D01*
G02X128997Y211641I0J-1501D01*
G01X128998D01*
Y211640D01*
G03X129128Y211592I130J152D01*
G01X129392D01*
G03X129522Y211640I0J200D01*
G01X129523Y211641D01*
G02X130510Y212011I987J-1131D01*
G02Y209007I0J-1502D01*
G02X129523Y209377I0J1501D01*
G01X129522D01*
Y209378D01*
G03X129392Y209426I-130J-152D01*
G01X129128D01*
G03X128998Y209378I0J-200D01*
G01X128997Y209377D01*
G02X128010Y209007I-987J1131D01*
G37*
G36*
G01X230372D02*
G02Y212011I0J1502D01*
G02X231359Y211641I0J-1501D01*
G01X231360D01*
Y211640D01*
G03X231490Y211592I130J152D01*
G01X231754D01*
G03X231884Y211640I0J200D01*
G01X231885Y211641D01*
G02X232872Y212011I987J-1131D01*
G02Y209007I0J-1502D01*
G02X231885Y209377I0J1501D01*
G01X231884D01*
Y209378D01*
G03X231754Y209426I-130J-152D01*
G01X231490D01*
G03X231360Y209378I0J-200D01*
G01X231359Y209377D01*
G02X230372Y209007I-987J1131D01*
G37*
G36*
G01X332734D02*
G02Y212011I0J1502D01*
G02X333721Y211641I0J-1501D01*
G01X333722D01*
Y211640D01*
G03X333852Y211592I130J152D01*
G01X334116D01*
G03X334246Y211640I0J200D01*
G01X334247Y211641D01*
G02X335234Y212011I987J-1131D01*
G02Y209007I0J-1502D01*
G02X334247Y209377I0J1501D01*
G01X334246D01*
Y209378D01*
G03X334116Y209426I-130J-152D01*
G01X333852D01*
G03X333722Y209378I0J-200D01*
G01X333721Y209377D01*
G02X332734Y209007I-987J1131D01*
G37*
G36*
G01X482735D02*
G02Y212011I0J1502D01*
G02X483722Y211641I0J-1501D01*
G01X483723D01*
Y211640D01*
G03X483853Y211592I130J152D01*
G01X484117D01*
G03X484247Y211640I0J200D01*
G01X484248Y211641D01*
G02X485235Y212011I987J-1131D01*
G02Y209007I0J-1502D01*
G02X484248Y209377I0J1501D01*
G01X484247D01*
Y209378D01*
G03X484117Y209426I-130J-152D01*
G01X483853D01*
G03X483723Y209378I0J-200D01*
G01X483722Y209377D01*
G02X482735Y209007I-987J1131D01*
G37*
G36*
G01X585097D02*
G02Y212011I0J1502D01*
G02X586084Y211641I0J-1501D01*
G01X586085D01*
Y211640D01*
G03X586215Y211592I130J152D01*
G01X586479D01*
G03X586609Y211640I0J200D01*
G01X586610Y211641D01*
G02X587597Y212011I987J-1131D01*
G02Y209007I0J-1502D01*
G02X586610Y209377I0J1501D01*
G01X586609D01*
Y209378D01*
G03X586479Y209426I-130J-152D01*
G01X586215D01*
G03X586085Y209378I0J-200D01*
G01X586084Y209377D01*
G02X585097Y209007I-987J1131D01*
G37*
G36*
G01X687459D02*
G02Y212011I0J1502D01*
G02X688446Y211641I0J-1501D01*
G01X688447D01*
Y211640D01*
G03X688577Y211592I130J152D01*
G01X688841D01*
G03X688971Y211640I0J200D01*
G01X688972Y211641D01*
G02X689959Y212011I987J-1131D01*
G02Y209007I0J-1502D01*
G02X688972Y209377I0J1501D01*
G01X688971D01*
Y209378D01*
G03X688841Y209426I-130J-152D01*
G01X688577D01*
G03X688447Y209378I0J-200D01*
G01X688446Y209377D01*
G02X687459Y209007I-987J1131D01*
G37*
G36*
G01X789821D02*
G02Y212011I0J1502D01*
G02X790808Y211641I0J-1501D01*
G01X790809D01*
Y211640D01*
G03X790939Y211592I130J152D01*
G01X791203D01*
G03X791333Y211640I0J200D01*
G01X791334Y211641D01*
G02X792321Y212011I987J-1131D01*
G02Y209007I0J-1502D01*
G02X791334Y209377I0J1501D01*
G01X791333D01*
Y209378D01*
G03X791203Y209426I-130J-152D01*
G01X790939D01*
G03X790809Y209378I0J-200D01*
G01X790808Y209377D01*
G02X789821Y209007I-987J1131D01*
G37*
G36*
G01X1042183D02*
G02Y212011I0J1502D01*
G02X1043170Y211641I0J-1501D01*
G01X1043171D01*
Y211640D01*
G03X1043301Y211592I130J152D01*
G01X1043565D01*
G03X1043695Y211640I0J200D01*
G01X1043696Y211641D01*
G02X1044683Y212011I987J-1131D01*
G02Y209007I0J-1502D01*
G02X1043696Y209377I0J1501D01*
G01X1043695D01*
Y209378D01*
G03X1043565Y209426I-130J-152D01*
G01X1043301D01*
G03X1043171Y209378I0J-200D01*
G01X1043170Y209377D01*
G02X1042183Y209007I-987J1131D01*
G37*
G36*
G01X1144545D02*
G02Y212011I0J1502D01*
G02X1145532Y211641I0J-1501D01*
G01X1145533D01*
Y211640D01*
G03X1145663Y211592I130J152D01*
G01X1145927D01*
G03X1146057Y211640I0J200D01*
G01X1146058Y211641D01*
G02X1147045Y212011I987J-1131D01*
G02Y209007I0J-1502D01*
G02X1146058Y209377I0J1501D01*
G01X1146057D01*
Y209378D01*
G03X1145927Y209426I-130J-152D01*
G01X1145663D01*
G03X1145533Y209378I0J-200D01*
G01X1145532Y209377D01*
G02X1144545Y209007I-987J1131D01*
G37*
G36*
G01X1246907D02*
G02Y212011I0J1502D01*
G02X1247894Y211641I0J-1501D01*
G01X1247895D01*
Y211640D01*
G03X1248025Y211592I130J152D01*
G01X1248289D01*
G03X1248419Y211640I0J200D01*
G01X1248420Y211641D01*
G02X1249407Y212011I987J-1131D01*
G02Y209007I0J-1502D01*
G02X1248420Y209377I0J1501D01*
G01X1248419D01*
Y209378D01*
G03X1248289Y209426I-130J-152D01*
G01X1248025D01*
G03X1247895Y209378I0J-200D01*
G01X1247894Y209377D01*
G02X1246907Y209007I-987J1131D01*
G37*
G36*
G01X1396908D02*
G02Y212011I0J1502D01*
G02X1397895Y211641I0J-1501D01*
G01X1397896D01*
Y211640D01*
G03X1398026Y211592I130J152D01*
G01X1398290D01*
G03X1398420Y211640I0J200D01*
G01X1398421Y211641D01*
G02X1399408Y212011I987J-1131D01*
G02Y209007I0J-1502D01*
G02X1398421Y209377I0J1501D01*
G01X1398420D01*
Y209378D01*
G03X1398290Y209426I-130J-152D01*
G01X1398026D01*
G03X1397896Y209378I0J-200D01*
G01X1397895Y209377D01*
G02X1396908Y209007I-987J1131D01*
G37*
G36*
G01X1499270D02*
G02Y212011I0J1502D01*
G02X1500257Y211641I0J-1501D01*
G01X1500258D01*
Y211640D01*
G03X1500388Y211592I130J152D01*
G01X1500652D01*
G03X1500782Y211640I0J200D01*
G01X1500783Y211641D01*
G02X1501770Y212011I987J-1131D01*
G02Y209007I0J-1502D01*
G02X1500783Y209377I0J1501D01*
G01X1500782D01*
Y209378D01*
G03X1500652Y209426I-130J-152D01*
G01X1500388D01*
G03X1500258Y209378I0J-200D01*
G01X1500257Y209377D01*
G02X1499270Y209007I-987J1131D01*
G37*
G36*
G01X1601632D02*
G02Y212011I0J1502D01*
G02X1602619Y211641I0J-1501D01*
G01X1602620D01*
Y211640D01*
G03X1602750Y211592I130J152D01*
G01X1603014D01*
G03X1603144Y211640I0J200D01*
G01X1603145Y211641D01*
G02X1604132Y212011I987J-1131D01*
G02Y209007I0J-1502D01*
G02X1603145Y209377I0J1501D01*
G01X1603144D01*
Y209378D01*
G03X1603014Y209426I-130J-152D01*
G01X1602750D01*
G03X1602620Y209378I0J-200D01*
G01X1602619Y209377D01*
G02X1601632Y209007I-987J1131D01*
G37*
G36*
G01X1703994D02*
G02Y212011I0J1502D01*
G02X1704981Y211641I0J-1501D01*
G01X1704982D01*
Y211640D01*
G03X1705112Y211592I130J152D01*
G01X1705376D01*
G03X1705506Y211640I0J200D01*
G01X1705507Y211641D01*
G02X1706494Y212011I987J-1131D01*
G02Y209007I0J-1502D01*
G02X1705507Y209377I0J1501D01*
G01X1705506D01*
Y209378D01*
G03X1705376Y209426I-130J-152D01*
G01X1705112D01*
G03X1704982Y209378I0J-200D01*
G01X1704981Y209377D01*
G02X1703994Y209007I-987J1131D01*
G37*
G36*
G01X75317Y213859D02*
G02X78321I1502J0D01*
G02X77951Y212872I-1501J0D01*
G01Y212871D01*
X77950D01*
G03X77902Y212741I152J-130D01*
G01Y212477D01*
G03X77950Y212347I200J0D01*
G01X77951Y212346D01*
G02X78321Y211359I-1131J-987D01*
G02X75317I-1502J0D01*
G02X75687Y212346I1501J0D01*
G01Y212347D01*
X75688D01*
G03X75736Y212477I-152J130D01*
G01Y212741D01*
G03X75688Y212871I-200J0D01*
G01X75687Y212872D01*
G02X75317Y213859I1131J987D01*
G37*
G36*
G01X177679D02*
G02X180683I1502J0D01*
G02X180313Y212872I-1501J0D01*
G01Y212871D01*
X180312D01*
G03X180264Y212741I152J-130D01*
G01Y212477D01*
G03X180312Y212347I200J0D01*
G01X180313Y212346D01*
G02X180683Y211359I-1131J-987D01*
G02X177679I-1502J0D01*
G02X178049Y212346I1501J0D01*
G01Y212347D01*
X178050D01*
G03X178098Y212477I-152J130D01*
G01Y212741D01*
G03X178050Y212871I-200J0D01*
G01X178049Y212872D01*
G02X177679Y213859I1131J987D01*
G37*
G36*
G01X280041D02*
G02X283045I1502J0D01*
G02X282675Y212872I-1501J0D01*
G01Y212871D01*
X282674D01*
G03X282626Y212741I152J-130D01*
G01Y212477D01*
G03X282674Y212347I200J0D01*
G01X282675Y212346D01*
G02X283045Y211359I-1131J-987D01*
G02X280041I-1502J0D01*
G02X280411Y212346I1501J0D01*
G01Y212347D01*
X280412D01*
G03X280460Y212477I-152J130D01*
G01Y212741D01*
G03X280412Y212871I-200J0D01*
G01X280411Y212872D01*
G02X280041Y213859I1131J987D01*
G37*
G36*
G01X382403D02*
G02X385407I1502J0D01*
G02X385037Y212872I-1501J0D01*
G01Y212871D01*
X385036D01*
G03X384988Y212741I152J-130D01*
G01Y212477D01*
G03X385036Y212347I200J0D01*
G01X385037Y212346D01*
G02X385407Y211359I-1131J-987D01*
G02X382403I-1502J0D01*
G02X382773Y212346I1501J0D01*
G01Y212347D01*
X382774D01*
G03X382822Y212477I-152J130D01*
G01Y212741D01*
G03X382774Y212871I-200J0D01*
G01X382773Y212872D01*
G02X382403Y213859I1131J987D01*
G37*
G36*
G01X532404D02*
G02X535408I1502J0D01*
G02X535038Y212872I-1501J0D01*
G01Y212871D01*
X535037D01*
G03X534989Y212741I152J-130D01*
G01Y212477D01*
G03X535037Y212347I200J0D01*
G01X535038Y212346D01*
G02X535408Y211359I-1131J-987D01*
G02X532404I-1502J0D01*
G02X532774Y212346I1501J0D01*
G01Y212347D01*
X532775D01*
G03X532823Y212477I-152J130D01*
G01Y212741D01*
G03X532775Y212871I-200J0D01*
G01X532774Y212872D01*
G02X532404Y213859I1131J987D01*
G37*
G36*
G01X634766D02*
G02X637770I1502J0D01*
G02X637400Y212872I-1501J0D01*
G01Y212871D01*
X637399D01*
G03X637351Y212741I152J-130D01*
G01Y212477D01*
G03X637399Y212347I200J0D01*
G01X637400Y212346D01*
G02X637770Y211359I-1131J-987D01*
G02X634766I-1502J0D01*
G02X635136Y212346I1501J0D01*
G01Y212347D01*
X635137D01*
G03X635185Y212477I-152J130D01*
G01Y212741D01*
G03X635137Y212871I-200J0D01*
G01X635136Y212872D01*
G02X634766Y213859I1131J987D01*
G37*
G36*
G01X737128D02*
G02X740132I1502J0D01*
G02X739762Y212872I-1501J0D01*
G01Y212871D01*
X739761D01*
G03X739713Y212741I152J-130D01*
G01Y212477D01*
G03X739761Y212347I200J0D01*
G01X739762Y212346D01*
G02X740132Y211359I-1131J-987D01*
G02X737128I-1502J0D01*
G02X737498Y212346I1501J0D01*
G01Y212347D01*
X737499D01*
G03X737547Y212477I-152J130D01*
G01Y212741D01*
G03X737499Y212871I-200J0D01*
G01X737498Y212872D01*
G02X737128Y213859I1131J987D01*
G37*
G36*
G01X839490D02*
G02X842494I1502J0D01*
G02X842124Y212872I-1501J0D01*
G01Y212871D01*
X842123D01*
G03X842075Y212741I152J-130D01*
G01Y212477D01*
G03X842123Y212347I200J0D01*
G01X842124Y212346D01*
G02X842494Y211359I-1131J-987D01*
G02X839490I-1502J0D01*
G02X839860Y212346I1501J0D01*
G01Y212347D01*
X839861D01*
G03X839909Y212477I-152J130D01*
G01Y212741D01*
G03X839861Y212871I-200J0D01*
G01X839860Y212872D01*
G02X839490Y213859I1131J987D01*
G37*
G36*
G01X989490D02*
G02X992494I1502J0D01*
G02X992124Y212872I-1501J0D01*
G01Y212871D01*
X992123D01*
G03X992075Y212741I152J-130D01*
G01Y212477D01*
G03X992123Y212347I200J0D01*
G01X992124Y212346D01*
G02X992494Y211359I-1131J-987D01*
G02X989490I-1502J0D01*
G02X989860Y212346I1501J0D01*
G01Y212347D01*
X989861D01*
G03X989909Y212477I-152J130D01*
G01Y212741D01*
G03X989861Y212871I-200J0D01*
G01X989860Y212872D01*
G02X989490Y213859I1131J987D01*
G37*
G36*
G01X1091852D02*
G02X1094856I1502J0D01*
G02X1094486Y212872I-1501J0D01*
G01Y212871D01*
X1094485D01*
G03X1094437Y212741I152J-130D01*
G01Y212477D01*
G03X1094485Y212347I200J0D01*
G01X1094486Y212346D01*
G02X1094856Y211359I-1131J-987D01*
G02X1091852I-1502J0D01*
G02X1092222Y212346I1501J0D01*
G01Y212347D01*
X1092223D01*
G03X1092271Y212477I-152J130D01*
G01Y212741D01*
G03X1092223Y212871I-200J0D01*
G01X1092222Y212872D01*
G02X1091852Y213859I1131J987D01*
G37*
G36*
G01X1194214D02*
G02X1197218I1502J0D01*
G02X1196848Y212872I-1501J0D01*
G01Y212871D01*
X1196847D01*
G03X1196799Y212741I152J-130D01*
G01Y212477D01*
G03X1196847Y212347I200J0D01*
G01X1196848Y212346D01*
G02X1197218Y211359I-1131J-987D01*
G02X1194214I-1502J0D01*
G02X1194584Y212346I1501J0D01*
G01Y212347D01*
X1194585D01*
G03X1194633Y212477I-152J130D01*
G01Y212741D01*
G03X1194585Y212871I-200J0D01*
G01X1194584Y212872D01*
G02X1194214Y213859I1131J987D01*
G37*
G36*
G01X1296576D02*
G02X1299580I1502J0D01*
G02X1299210Y212872I-1501J0D01*
G01Y212871D01*
X1299209D01*
G03X1299161Y212741I152J-130D01*
G01Y212477D01*
G03X1299209Y212347I200J0D01*
G01X1299210Y212346D01*
G02X1299580Y211359I-1131J-987D01*
G02X1296576I-1502J0D01*
G02X1296946Y212346I1501J0D01*
G01Y212347D01*
X1296947D01*
G03X1296995Y212477I-152J130D01*
G01Y212741D01*
G03X1296947Y212871I-200J0D01*
G01X1296946Y212872D01*
G02X1296576Y213859I1131J987D01*
G37*
G36*
G01X1446577D02*
G02X1449581I1502J0D01*
G02X1449211Y212872I-1501J0D01*
G01Y212871D01*
X1449210D01*
G03X1449162Y212741I152J-130D01*
G01Y212477D01*
G03X1449210Y212347I200J0D01*
G01X1449211Y212346D01*
G02X1449581Y211359I-1131J-987D01*
G02X1446577I-1502J0D01*
G02X1446947Y212346I1501J0D01*
G01Y212347D01*
X1446948D01*
G03X1446996Y212477I-152J130D01*
G01Y212741D01*
G03X1446948Y212871I-200J0D01*
G01X1446947Y212872D01*
G02X1446577Y213859I1131J987D01*
G37*
G36*
G01X1548939D02*
G02X1551943I1502J0D01*
G02X1551573Y212872I-1501J0D01*
G01Y212871D01*
X1551572D01*
G03X1551524Y212741I152J-130D01*
G01Y212477D01*
G03X1551572Y212347I200J0D01*
G01X1551573Y212346D01*
G02X1551943Y211359I-1131J-987D01*
G02X1548939I-1502J0D01*
G02X1549309Y212346I1501J0D01*
G01Y212347D01*
X1549310D01*
G03X1549358Y212477I-152J130D01*
G01Y212741D01*
G03X1549310Y212871I-200J0D01*
G01X1549309Y212872D01*
G02X1548939Y213859I1131J987D01*
G37*
G36*
G01X1651301D02*
G02X1654305I1502J0D01*
G02X1653935Y212872I-1501J0D01*
G01Y212871D01*
X1653934D01*
G03X1653886Y212741I152J-130D01*
G01Y212477D01*
G03X1653934Y212347I200J0D01*
G01X1653935Y212346D01*
G02X1654305Y211359I-1131J-987D01*
G02X1651301I-1502J0D01*
G02X1651671Y212346I1501J0D01*
G01Y212347D01*
X1651672D01*
G03X1651720Y212477I-152J130D01*
G01Y212741D01*
G03X1651672Y212871I-200J0D01*
G01X1651671Y212872D01*
G02X1651301Y213859I1131J987D01*
G37*
G36*
G01X1753663D02*
G02X1756667I1502J0D01*
G02X1756297Y212872I-1501J0D01*
G01Y212871D01*
X1756296D01*
G03X1756248Y212741I152J-130D01*
G01Y212477D01*
G03X1756296Y212347I200J0D01*
G01X1756297Y212346D01*
G02X1756667Y211359I-1131J-987D01*
G02X1753663I-1502J0D01*
G02X1754033Y212346I1501J0D01*
G01Y212347D01*
X1754034D01*
G03X1754082Y212477I-152J130D01*
G01Y212741D01*
G03X1754034Y212871I-200J0D01*
G01X1754033Y212872D01*
G02X1753663Y213859I1131J987D01*
G37*
G36*
G01X53231Y215478D02*
G02X56235I1502J0D01*
G02X55865Y214491I-1501J0D01*
G01Y214490D01*
X55864D01*
G03X55816Y214360I152J-130D01*
G01Y214096D01*
G03X55864Y213966I200J0D01*
G01X55865Y213965D01*
G02Y211991I-1131J-987D01*
G01Y211990D01*
X55864D01*
G03X55816Y211860I152J-130D01*
G01Y211596D01*
G03X55864Y211466I200J0D01*
G01X55865Y211465D01*
G02Y209491I-1131J-987D01*
G01Y209490D01*
X55864D01*
G03X55816Y209360I152J-130D01*
G01Y209096D01*
G03X55864Y208966I200J0D01*
G01X55865Y208965D01*
G02X56235Y207978I-1131J-987D01*
G02X53231I-1502J0D01*
G02X53601Y208965I1501J0D01*
G01Y208966D01*
X53602D01*
G03X53650Y209096I-152J130D01*
G01Y209360D01*
G03X53602Y209490I-200J0D01*
G01X53601Y209491D01*
G02Y211465I1131J987D01*
G01Y211466D01*
X53602D01*
G03X53650Y211596I-152J130D01*
G01Y211860D01*
G03X53602Y211990I-200J0D01*
G01X53601Y211991D01*
G02Y213965I1131J987D01*
G01Y213966D01*
X53602D01*
G03X53650Y214096I-152J130D01*
G01Y214360D01*
G03X53602Y214490I-200J0D01*
G01X53601Y214491D01*
G02X53231Y215478I1131J987D01*
G37*
G36*
G01X155593D02*
G02X158597I1502J0D01*
G02X158227Y214491I-1501J0D01*
G01Y214490D01*
X158226D01*
G03X158178Y214360I152J-130D01*
G01Y214096D01*
G03X158226Y213966I200J0D01*
G01X158227Y213965D01*
G02Y211991I-1131J-987D01*
G01Y211990D01*
X158226D01*
G03X158178Y211860I152J-130D01*
G01Y211596D01*
G03X158226Y211466I200J0D01*
G01X158227Y211465D01*
G02Y209491I-1131J-987D01*
G01Y209490D01*
X158226D01*
G03X158178Y209360I152J-130D01*
G01Y209096D01*
G03X158226Y208966I200J0D01*
G01X158227Y208965D01*
G02X158597Y207978I-1131J-987D01*
G02X155593I-1502J0D01*
G02X155963Y208965I1501J0D01*
G01Y208966D01*
X155964D01*
G03X156012Y209096I-152J130D01*
G01Y209360D01*
G03X155964Y209490I-200J0D01*
G01X155963Y209491D01*
G02Y211465I1131J987D01*
G01Y211466D01*
X155964D01*
G03X156012Y211596I-152J130D01*
G01Y211860D01*
G03X155964Y211990I-200J0D01*
G01X155963Y211991D01*
G02Y213965I1131J987D01*
G01Y213966D01*
X155964D01*
G03X156012Y214096I-152J130D01*
G01Y214360D01*
G03X155964Y214490I-200J0D01*
G01X155963Y214491D01*
G02X155593Y215478I1131J987D01*
G37*
G36*
G01X257955D02*
G02X260959I1502J0D01*
G02X260589Y214491I-1501J0D01*
G01Y214490D01*
X260588D01*
G03X260540Y214360I152J-130D01*
G01Y214096D01*
G03X260588Y213966I200J0D01*
G01X260589Y213965D01*
G02Y211991I-1131J-987D01*
G01Y211990D01*
X260588D01*
G03X260540Y211860I152J-130D01*
G01Y211596D01*
G03X260588Y211466I200J0D01*
G01X260589Y211465D01*
G02Y209491I-1131J-987D01*
G01Y209490D01*
X260588D01*
G03X260540Y209360I152J-130D01*
G01Y209096D01*
G03X260588Y208966I200J0D01*
G01X260589Y208965D01*
G02X260959Y207978I-1131J-987D01*
G02X257955I-1502J0D01*
G02X258325Y208965I1501J0D01*
G01Y208966D01*
X258326D01*
G03X258374Y209096I-152J130D01*
G01Y209360D01*
G03X258326Y209490I-200J0D01*
G01X258325Y209491D01*
G02Y211465I1131J987D01*
G01Y211466D01*
X258326D01*
G03X258374Y211596I-152J130D01*
G01Y211860D01*
G03X258326Y211990I-200J0D01*
G01X258325Y211991D01*
G02Y213965I1131J987D01*
G01Y213966D01*
X258326D01*
G03X258374Y214096I-152J130D01*
G01Y214360D01*
G03X258326Y214490I-200J0D01*
G01X258325Y214491D01*
G02X257955Y215478I1131J987D01*
G37*
G36*
G01X360317D02*
G02X363321I1502J0D01*
G02X362951Y214491I-1501J0D01*
G01Y214490D01*
X362950D01*
G03X362902Y214360I152J-130D01*
G01Y214096D01*
G03X362950Y213966I200J0D01*
G01X362951Y213965D01*
G02Y211991I-1131J-987D01*
G01Y211990D01*
X362950D01*
G03X362902Y211860I152J-130D01*
G01Y211596D01*
G03X362950Y211466I200J0D01*
G01X362951Y211465D01*
G02Y209491I-1131J-987D01*
G01Y209490D01*
X362950D01*
G03X362902Y209360I152J-130D01*
G01Y209096D01*
G03X362950Y208966I200J0D01*
G01X362951Y208965D01*
G02X363321Y207978I-1131J-987D01*
G02X360317I-1502J0D01*
G02X360687Y208965I1501J0D01*
G01Y208966D01*
X360688D01*
G03X360736Y209096I-152J130D01*
G01Y209360D01*
G03X360688Y209490I-200J0D01*
G01X360687Y209491D01*
G02Y211465I1131J987D01*
G01Y211466D01*
X360688D01*
G03X360736Y211596I-152J130D01*
G01Y211860D01*
G03X360688Y211990I-200J0D01*
G01X360687Y211991D01*
G02Y213965I1131J987D01*
G01Y213966D01*
X360688D01*
G03X360736Y214096I-152J130D01*
G01Y214360D01*
G03X360688Y214490I-200J0D01*
G01X360687Y214491D01*
G02X360317Y215478I1131J987D01*
G37*
G36*
G01X510318D02*
G02X513322I1502J0D01*
G02X512952Y214491I-1501J0D01*
G01Y214490D01*
X512951D01*
G03X512903Y214360I152J-130D01*
G01Y214096D01*
G03X512951Y213966I200J0D01*
G01X512952Y213965D01*
G02Y211991I-1131J-987D01*
G01Y211990D01*
X512951D01*
G03X512903Y211860I152J-130D01*
G01Y211596D01*
G03X512951Y211466I200J0D01*
G01X512952Y211465D01*
G02Y209491I-1131J-987D01*
G01Y209490D01*
X512951D01*
G03X512903Y209360I152J-130D01*
G01Y209096D01*
G03X512951Y208966I200J0D01*
G01X512952Y208965D01*
G02X513322Y207978I-1131J-987D01*
G02X510318I-1502J0D01*
G02X510688Y208965I1501J0D01*
G01Y208966D01*
X510689D01*
G03X510737Y209096I-152J130D01*
G01Y209360D01*
G03X510689Y209490I-200J0D01*
G01X510688Y209491D01*
G02Y211465I1131J987D01*
G01Y211466D01*
X510689D01*
G03X510737Y211596I-152J130D01*
G01Y211860D01*
G03X510689Y211990I-200J0D01*
G01X510688Y211991D01*
G02Y213965I1131J987D01*
G01Y213966D01*
X510689D01*
G03X510737Y214096I-152J130D01*
G01Y214360D01*
G03X510689Y214490I-200J0D01*
G01X510688Y214491D01*
G02X510318Y215478I1131J987D01*
G37*
G36*
G01X612680D02*
G02X615684I1502J0D01*
G02X615314Y214491I-1501J0D01*
G01Y214490D01*
X615313D01*
G03X615265Y214360I152J-130D01*
G01Y214096D01*
G03X615313Y213966I200J0D01*
G01X615314Y213965D01*
G02Y211991I-1131J-987D01*
G01Y211990D01*
X615313D01*
G03X615265Y211860I152J-130D01*
G01Y211596D01*
G03X615313Y211466I200J0D01*
G01X615314Y211465D01*
G02Y209491I-1131J-987D01*
G01Y209490D01*
X615313D01*
G03X615265Y209360I152J-130D01*
G01Y209096D01*
G03X615313Y208966I200J0D01*
G01X615314Y208965D01*
G02X615684Y207978I-1131J-987D01*
G02X612680I-1502J0D01*
G02X613050Y208965I1501J0D01*
G01Y208966D01*
X613051D01*
G03X613099Y209096I-152J130D01*
G01Y209360D01*
G03X613051Y209490I-200J0D01*
G01X613050Y209491D01*
G02Y211465I1131J987D01*
G01Y211466D01*
X613051D01*
G03X613099Y211596I-152J130D01*
G01Y211860D01*
G03X613051Y211990I-200J0D01*
G01X613050Y211991D01*
G02Y213965I1131J987D01*
G01Y213966D01*
X613051D01*
G03X613099Y214096I-152J130D01*
G01Y214360D01*
G03X613051Y214490I-200J0D01*
G01X613050Y214491D01*
G02X612680Y215478I1131J987D01*
G37*
G36*
G01X715042D02*
G02X718046I1502J0D01*
G02X717676Y214491I-1501J0D01*
G01Y214490D01*
X717675D01*
G03X717627Y214360I152J-130D01*
G01Y214096D01*
G03X717675Y213966I200J0D01*
G01X717676Y213965D01*
G02Y211991I-1131J-987D01*
G01Y211990D01*
X717675D01*
G03X717627Y211860I152J-130D01*
G01Y211596D01*
G03X717675Y211466I200J0D01*
G01X717676Y211465D01*
G02Y209491I-1131J-987D01*
G01Y209490D01*
X717675D01*
G03X717627Y209360I152J-130D01*
G01Y209096D01*
G03X717675Y208966I200J0D01*
G01X717676Y208965D01*
G02X718046Y207978I-1131J-987D01*
G02X715042I-1502J0D01*
G02X715412Y208965I1501J0D01*
G01Y208966D01*
X715413D01*
G03X715461Y209096I-152J130D01*
G01Y209360D01*
G03X715413Y209490I-200J0D01*
G01X715412Y209491D01*
G02Y211465I1131J987D01*
G01Y211466D01*
X715413D01*
G03X715461Y211596I-152J130D01*
G01Y211860D01*
G03X715413Y211990I-200J0D01*
G01X715412Y211991D01*
G02Y213965I1131J987D01*
G01Y213966D01*
X715413D01*
G03X715461Y214096I-152J130D01*
G01Y214360D01*
G03X715413Y214490I-200J0D01*
G01X715412Y214491D01*
G02X715042Y215478I1131J987D01*
G37*
G36*
G01X817404D02*
G02X820408I1502J0D01*
G02X820038Y214491I-1501J0D01*
G01Y214490D01*
X820037D01*
G03X819989Y214360I152J-130D01*
G01Y214096D01*
G03X820037Y213966I200J0D01*
G01X820038Y213965D01*
G02Y211991I-1131J-987D01*
G01Y211990D01*
X820037D01*
G03X819989Y211860I152J-130D01*
G01Y211596D01*
G03X820037Y211466I200J0D01*
G01X820038Y211465D01*
G02Y209491I-1131J-987D01*
G01Y209490D01*
X820037D01*
G03X819989Y209360I152J-130D01*
G01Y209096D01*
G03X820037Y208966I200J0D01*
G01X820038Y208965D01*
G02X820408Y207978I-1131J-987D01*
G02X817404I-1502J0D01*
G02X817774Y208965I1501J0D01*
G01Y208966D01*
X817775D01*
G03X817823Y209096I-152J130D01*
G01Y209360D01*
G03X817775Y209490I-200J0D01*
G01X817774Y209491D01*
G02Y211465I1131J987D01*
G01Y211466D01*
X817775D01*
G03X817823Y211596I-152J130D01*
G01Y211860D01*
G03X817775Y211990I-200J0D01*
G01X817774Y211991D01*
G02Y213965I1131J987D01*
G01Y213966D01*
X817775D01*
G03X817823Y214096I-152J130D01*
G01Y214360D01*
G03X817775Y214490I-200J0D01*
G01X817774Y214491D01*
G02X817404Y215478I1131J987D01*
G37*
G36*
G01X967404D02*
G02X970408I1502J0D01*
G02X970038Y214491I-1501J0D01*
G01Y214490D01*
X970037D01*
G03X969989Y214360I152J-130D01*
G01Y214096D01*
G03X970037Y213966I200J0D01*
G01X970038Y213965D01*
G02Y211991I-1131J-987D01*
G01Y211990D01*
X970037D01*
G03X969989Y211860I152J-130D01*
G01Y211596D01*
G03X970037Y211466I200J0D01*
G01X970038Y211465D01*
G02Y209491I-1131J-987D01*
G01Y209490D01*
X970037D01*
G03X969989Y209360I152J-130D01*
G01Y209096D01*
G03X970037Y208966I200J0D01*
G01X970038Y208965D01*
G02X970408Y207978I-1131J-987D01*
G02X967404I-1502J0D01*
G02X967774Y208965I1501J0D01*
G01Y208966D01*
X967775D01*
G03X967823Y209096I-152J130D01*
G01Y209360D01*
G03X967775Y209490I-200J0D01*
G01X967774Y209491D01*
G02Y211465I1131J987D01*
G01Y211466D01*
X967775D01*
G03X967823Y211596I-152J130D01*
G01Y211860D01*
G03X967775Y211990I-200J0D01*
G01X967774Y211991D01*
G02Y213965I1131J987D01*
G01Y213966D01*
X967775D01*
G03X967823Y214096I-152J130D01*
G01Y214360D01*
G03X967775Y214490I-200J0D01*
G01X967774Y214491D01*
G02X967404Y215478I1131J987D01*
G37*
G36*
G01X1069766D02*
G02X1072770I1502J0D01*
G02X1072400Y214491I-1501J0D01*
G01Y214490D01*
X1072399D01*
G03X1072351Y214360I152J-130D01*
G01Y214096D01*
G03X1072399Y213966I200J0D01*
G01X1072400Y213965D01*
G02Y211991I-1131J-987D01*
G01Y211990D01*
X1072399D01*
G03X1072351Y211860I152J-130D01*
G01Y211596D01*
G03X1072399Y211466I200J0D01*
G01X1072400Y211465D01*
G02Y209491I-1131J-987D01*
G01Y209490D01*
X1072399D01*
G03X1072351Y209360I152J-130D01*
G01Y209096D01*
G03X1072399Y208966I200J0D01*
G01X1072400Y208965D01*
G02X1072770Y207978I-1131J-987D01*
G02X1069766I-1502J0D01*
G02X1070136Y208965I1501J0D01*
G01Y208966D01*
X1070137D01*
G03X1070185Y209096I-152J130D01*
G01Y209360D01*
G03X1070137Y209490I-200J0D01*
G01X1070136Y209491D01*
G02Y211465I1131J987D01*
G01Y211466D01*
X1070137D01*
G03X1070185Y211596I-152J130D01*
G01Y211860D01*
G03X1070137Y211990I-200J0D01*
G01X1070136Y211991D01*
G02Y213965I1131J987D01*
G01Y213966D01*
X1070137D01*
G03X1070185Y214096I-152J130D01*
G01Y214360D01*
G03X1070137Y214490I-200J0D01*
G01X1070136Y214491D01*
G02X1069766Y215478I1131J987D01*
G37*
G36*
G01X1172128D02*
G02X1175132I1502J0D01*
G02X1174762Y214491I-1501J0D01*
G01Y214490D01*
X1174761D01*
G03X1174713Y214360I152J-130D01*
G01Y214096D01*
G03X1174761Y213966I200J0D01*
G01X1174762Y213965D01*
G02Y211991I-1131J-987D01*
G01Y211990D01*
X1174761D01*
G03X1174713Y211860I152J-130D01*
G01Y211596D01*
G03X1174761Y211466I200J0D01*
G01X1174762Y211465D01*
G02Y209491I-1131J-987D01*
G01Y209490D01*
X1174761D01*
G03X1174713Y209360I152J-130D01*
G01Y209096D01*
G03X1174761Y208966I200J0D01*
G01X1174762Y208965D01*
G02X1175132Y207978I-1131J-987D01*
G02X1172128I-1502J0D01*
G02X1172498Y208965I1501J0D01*
G01Y208966D01*
X1172499D01*
G03X1172547Y209096I-152J130D01*
G01Y209360D01*
G03X1172499Y209490I-200J0D01*
G01X1172498Y209491D01*
G02Y211465I1131J987D01*
G01Y211466D01*
X1172499D01*
G03X1172547Y211596I-152J130D01*
G01Y211860D01*
G03X1172499Y211990I-200J0D01*
G01X1172498Y211991D01*
G02Y213965I1131J987D01*
G01Y213966D01*
X1172499D01*
G03X1172547Y214096I-152J130D01*
G01Y214360D01*
G03X1172499Y214490I-200J0D01*
G01X1172498Y214491D01*
G02X1172128Y215478I1131J987D01*
G37*
G36*
G01X1274490D02*
G02X1277494I1502J0D01*
G02X1277124Y214491I-1501J0D01*
G01Y214490D01*
X1277123D01*
G03X1277075Y214360I152J-130D01*
G01Y214096D01*
G03X1277123Y213966I200J0D01*
G01X1277124Y213965D01*
G02Y211991I-1131J-987D01*
G01Y211990D01*
X1277123D01*
G03X1277075Y211860I152J-130D01*
G01Y211596D01*
G03X1277123Y211466I200J0D01*
G01X1277124Y211465D01*
G02Y209491I-1131J-987D01*
G01Y209490D01*
X1277123D01*
G03X1277075Y209360I152J-130D01*
G01Y209096D01*
G03X1277123Y208966I200J0D01*
G01X1277124Y208965D01*
G02X1277494Y207978I-1131J-987D01*
G02X1274490I-1502J0D01*
G02X1274860Y208965I1501J0D01*
G01Y208966D01*
X1274861D01*
G03X1274909Y209096I-152J130D01*
G01Y209360D01*
G03X1274861Y209490I-200J0D01*
G01X1274860Y209491D01*
G02Y211465I1131J987D01*
G01Y211466D01*
X1274861D01*
G03X1274909Y211596I-152J130D01*
G01Y211860D01*
G03X1274861Y211990I-200J0D01*
G01X1274860Y211991D01*
G02Y213965I1131J987D01*
G01Y213966D01*
X1274861D01*
G03X1274909Y214096I-152J130D01*
G01Y214360D01*
G03X1274861Y214490I-200J0D01*
G01X1274860Y214491D01*
G02X1274490Y215478I1131J987D01*
G37*
G36*
G01X1424491D02*
G02X1427495I1502J0D01*
G02X1427125Y214491I-1501J0D01*
G01Y214490D01*
X1427124D01*
G03X1427076Y214360I152J-130D01*
G01Y214096D01*
G03X1427124Y213966I200J0D01*
G01X1427125Y213965D01*
G02Y211991I-1131J-987D01*
G01Y211990D01*
X1427124D01*
G03X1427076Y211860I152J-130D01*
G01Y211596D01*
G03X1427124Y211466I200J0D01*
G01X1427125Y211465D01*
G02Y209491I-1131J-987D01*
G01Y209490D01*
X1427124D01*
G03X1427076Y209360I152J-130D01*
G01Y209096D01*
G03X1427124Y208966I200J0D01*
G01X1427125Y208965D01*
G02X1427495Y207978I-1131J-987D01*
G02X1424491I-1502J0D01*
G02X1424861Y208965I1501J0D01*
G01Y208966D01*
X1424862D01*
G03X1424910Y209096I-152J130D01*
G01Y209360D01*
G03X1424862Y209490I-200J0D01*
G01X1424861Y209491D01*
G02Y211465I1131J987D01*
G01Y211466D01*
X1424862D01*
G03X1424910Y211596I-152J130D01*
G01Y211860D01*
G03X1424862Y211990I-200J0D01*
G01X1424861Y211991D01*
G02Y213965I1131J987D01*
G01Y213966D01*
X1424862D01*
G03X1424910Y214096I-152J130D01*
G01Y214360D01*
G03X1424862Y214490I-200J0D01*
G01X1424861Y214491D01*
G02X1424491Y215478I1131J987D01*
G37*
G36*
G01X1526853D02*
G02X1529857I1502J0D01*
G02X1529487Y214491I-1501J0D01*
G01Y214490D01*
X1529486D01*
G03X1529438Y214360I152J-130D01*
G01Y214096D01*
G03X1529486Y213966I200J0D01*
G01X1529487Y213965D01*
G02Y211991I-1131J-987D01*
G01Y211990D01*
X1529486D01*
G03X1529438Y211860I152J-130D01*
G01Y211596D01*
G03X1529486Y211466I200J0D01*
G01X1529487Y211465D01*
G02Y209491I-1131J-987D01*
G01Y209490D01*
X1529486D01*
G03X1529438Y209360I152J-130D01*
G01Y209096D01*
G03X1529486Y208966I200J0D01*
G01X1529487Y208965D01*
G02X1529857Y207978I-1131J-987D01*
G02X1526853I-1502J0D01*
G02X1527223Y208965I1501J0D01*
G01Y208966D01*
X1527224D01*
G03X1527272Y209096I-152J130D01*
G01Y209360D01*
G03X1527224Y209490I-200J0D01*
G01X1527223Y209491D01*
G02Y211465I1131J987D01*
G01Y211466D01*
X1527224D01*
G03X1527272Y211596I-152J130D01*
G01Y211860D01*
G03X1527224Y211990I-200J0D01*
G01X1527223Y211991D01*
G02Y213965I1131J987D01*
G01Y213966D01*
X1527224D01*
G03X1527272Y214096I-152J130D01*
G01Y214360D01*
G03X1527224Y214490I-200J0D01*
G01X1527223Y214491D01*
G02X1526853Y215478I1131J987D01*
G37*
G36*
G01X1629215D02*
G02X1632219I1502J0D01*
G02X1631849Y214491I-1501J0D01*
G01Y214490D01*
X1631848D01*
G03X1631800Y214360I152J-130D01*
G01Y214096D01*
G03X1631848Y213966I200J0D01*
G01X1631849Y213965D01*
G02Y211991I-1131J-987D01*
G01Y211990D01*
X1631848D01*
G03X1631800Y211860I152J-130D01*
G01Y211596D01*
G03X1631848Y211466I200J0D01*
G01X1631849Y211465D01*
G02Y209491I-1131J-987D01*
G01Y209490D01*
X1631848D01*
G03X1631800Y209360I152J-130D01*
G01Y209096D01*
G03X1631848Y208966I200J0D01*
G01X1631849Y208965D01*
G02X1632219Y207978I-1131J-987D01*
G02X1629215I-1502J0D01*
G02X1629585Y208965I1501J0D01*
G01Y208966D01*
X1629586D01*
G03X1629634Y209096I-152J130D01*
G01Y209360D01*
G03X1629586Y209490I-200J0D01*
G01X1629585Y209491D01*
G02Y211465I1131J987D01*
G01Y211466D01*
X1629586D01*
G03X1629634Y211596I-152J130D01*
G01Y211860D01*
G03X1629586Y211990I-200J0D01*
G01X1629585Y211991D01*
G02Y213965I1131J987D01*
G01Y213966D01*
X1629586D01*
G03X1629634Y214096I-152J130D01*
G01Y214360D01*
G03X1629586Y214490I-200J0D01*
G01X1629585Y214491D01*
G02X1629215Y215478I1131J987D01*
G37*
G36*
G01X1731577D02*
G02X1734581I1502J0D01*
G02X1734211Y214491I-1501J0D01*
G01Y214490D01*
X1734210D01*
G03X1734162Y214360I152J-130D01*
G01Y214096D01*
G03X1734210Y213966I200J0D01*
G01X1734211Y213965D01*
G02Y211991I-1131J-987D01*
G01Y211990D01*
X1734210D01*
G03X1734162Y211860I152J-130D01*
G01Y211596D01*
G03X1734210Y211466I200J0D01*
G01X1734211Y211465D01*
G02Y209491I-1131J-987D01*
G01Y209490D01*
X1734210D01*
G03X1734162Y209360I152J-130D01*
G01Y209096D01*
G03X1734210Y208966I200J0D01*
G01X1734211Y208965D01*
G02X1734581Y207978I-1131J-987D01*
G02X1731577I-1502J0D01*
G02X1731947Y208965I1501J0D01*
G01Y208966D01*
X1731948D01*
G03X1731996Y209096I-152J130D01*
G01Y209360D01*
G03X1731948Y209490I-200J0D01*
G01X1731947Y209491D01*
G02Y211465I1131J987D01*
G01Y211466D01*
X1731948D01*
G03X1731996Y211596I-152J130D01*
G01Y211860D01*
G03X1731948Y211990I-200J0D01*
G01X1731947Y211991D01*
G02Y213965I1131J987D01*
G01Y213966D01*
X1731948D01*
G03X1731996Y214096I-152J130D01*
G01Y214360D01*
G03X1731948Y214490I-200J0D01*
G01X1731947Y214491D01*
G02X1731577Y215478I1131J987D01*
G37*
G36*
G01X79020Y215632D02*
G02X82024I1502J0D01*
G02X81654Y214645I-1501J0D01*
G01Y214644D01*
X81653D01*
G03X81605Y214514I152J-130D01*
G01Y214250D01*
G03X81653Y214120I200J0D01*
G01X81654Y214119D01*
G02X82024Y213132I-1131J-987D01*
G02X79020I-1502J0D01*
G02X79390Y214119I1501J0D01*
G01Y214120D01*
X79391D01*
G03X79439Y214250I-152J130D01*
G01Y214514D01*
G03X79391Y214644I-200J0D01*
G01X79390Y214645D01*
G02X79020Y215632I1131J987D01*
G37*
G36*
G01X181382D02*
G02X184386I1502J0D01*
G02X184016Y214645I-1501J0D01*
G01Y214644D01*
X184015D01*
G03X183967Y214514I152J-130D01*
G01Y214250D01*
G03X184015Y214120I200J0D01*
G01X184016Y214119D01*
G02X184386Y213132I-1131J-987D01*
G02X181382I-1502J0D01*
G02X181752Y214119I1501J0D01*
G01Y214120D01*
X181753D01*
G03X181801Y214250I-152J130D01*
G01Y214514D01*
G03X181753Y214644I-200J0D01*
G01X181752Y214645D01*
G02X181382Y215632I1131J987D01*
G37*
G36*
G01X283744D02*
G02X286748I1502J0D01*
G02X286378Y214645I-1501J0D01*
G01Y214644D01*
X286377D01*
G03X286329Y214514I152J-130D01*
G01Y214250D01*
G03X286377Y214120I200J0D01*
G01X286378Y214119D01*
G02X286748Y213132I-1131J-987D01*
G02X283744I-1502J0D01*
G02X284114Y214119I1501J0D01*
G01Y214120D01*
X284115D01*
G03X284163Y214250I-152J130D01*
G01Y214514D01*
G03X284115Y214644I-200J0D01*
G01X284114Y214645D01*
G02X283744Y215632I1131J987D01*
G37*
G36*
G01X386106D02*
G02X389110I1502J0D01*
G02X388740Y214645I-1501J0D01*
G01Y214644D01*
X388739D01*
G03X388691Y214514I152J-130D01*
G01Y214250D01*
G03X388739Y214120I200J0D01*
G01X388740Y214119D01*
G02X389110Y213132I-1131J-987D01*
G02X386106I-1502J0D01*
G02X386476Y214119I1501J0D01*
G01Y214120D01*
X386477D01*
G03X386525Y214250I-152J130D01*
G01Y214514D01*
G03X386477Y214644I-200J0D01*
G01X386476Y214645D01*
G02X386106Y215632I1131J987D01*
G37*
G36*
G01X536107D02*
G02X539111I1502J0D01*
G02X538741Y214645I-1501J0D01*
G01Y214644D01*
X538740D01*
G03X538692Y214514I152J-130D01*
G01Y214250D01*
G03X538740Y214120I200J0D01*
G01X538741Y214119D01*
G02X539111Y213132I-1131J-987D01*
G02X536107I-1502J0D01*
G02X536477Y214119I1501J0D01*
G01Y214120D01*
X536478D01*
G03X536526Y214250I-152J130D01*
G01Y214514D01*
G03X536478Y214644I-200J0D01*
G01X536477Y214645D01*
G02X536107Y215632I1131J987D01*
G37*
G36*
G01X638469D02*
G02X641473I1502J0D01*
G02X641103Y214645I-1501J0D01*
G01Y214644D01*
X641102D01*
G03X641054Y214514I152J-130D01*
G01Y214250D01*
G03X641102Y214120I200J0D01*
G01X641103Y214119D01*
G02X641473Y213132I-1131J-987D01*
G02X638469I-1502J0D01*
G02X638839Y214119I1501J0D01*
G01Y214120D01*
X638840D01*
G03X638888Y214250I-152J130D01*
G01Y214514D01*
G03X638840Y214644I-200J0D01*
G01X638839Y214645D01*
G02X638469Y215632I1131J987D01*
G37*
G36*
G01X740831D02*
G02X743835I1502J0D01*
G02X743465Y214645I-1501J0D01*
G01Y214644D01*
X743464D01*
G03X743416Y214514I152J-130D01*
G01Y214250D01*
G03X743464Y214120I200J0D01*
G01X743465Y214119D01*
G02X743835Y213132I-1131J-987D01*
G02X740831I-1502J0D01*
G02X741201Y214119I1501J0D01*
G01Y214120D01*
X741202D01*
G03X741250Y214250I-152J130D01*
G01Y214514D01*
G03X741202Y214644I-200J0D01*
G01X741201Y214645D01*
G02X740831Y215632I1131J987D01*
G37*
G36*
G01X843193D02*
G02X846197I1502J0D01*
G02X845827Y214645I-1501J0D01*
G01Y214644D01*
X845826D01*
G03X845778Y214514I152J-130D01*
G01Y214250D01*
G03X845826Y214120I200J0D01*
G01X845827Y214119D01*
G02X846197Y213132I-1131J-987D01*
G02X843193I-1502J0D01*
G02X843563Y214119I1501J0D01*
G01Y214120D01*
X843564D01*
G03X843612Y214250I-152J130D01*
G01Y214514D01*
G03X843564Y214644I-200J0D01*
G01X843563Y214645D01*
G02X843193Y215632I1131J987D01*
G37*
G36*
G01X993193D02*
G02X996197I1502J0D01*
G02X995827Y214645I-1501J0D01*
G01Y214644D01*
X995826D01*
G03X995778Y214514I152J-130D01*
G01Y214250D01*
G03X995826Y214120I200J0D01*
G01X995827Y214119D01*
G02X996197Y213132I-1131J-987D01*
G02X993193I-1502J0D01*
G02X993563Y214119I1501J0D01*
G01Y214120D01*
X993564D01*
G03X993612Y214250I-152J130D01*
G01Y214514D01*
G03X993564Y214644I-200J0D01*
G01X993563Y214645D01*
G02X993193Y215632I1131J987D01*
G37*
G36*
G01X1095555D02*
G02X1098559I1502J0D01*
G02X1098189Y214645I-1501J0D01*
G01Y214644D01*
X1098188D01*
G03X1098140Y214514I152J-130D01*
G01Y214250D01*
G03X1098188Y214120I200J0D01*
G01X1098189Y214119D01*
G02X1098559Y213132I-1131J-987D01*
G02X1095555I-1502J0D01*
G02X1095925Y214119I1501J0D01*
G01Y214120D01*
X1095926D01*
G03X1095974Y214250I-152J130D01*
G01Y214514D01*
G03X1095926Y214644I-200J0D01*
G01X1095925Y214645D01*
G02X1095555Y215632I1131J987D01*
G37*
G36*
G01X1197917D02*
G02X1200921I1502J0D01*
G02X1200551Y214645I-1501J0D01*
G01Y214644D01*
X1200550D01*
G03X1200502Y214514I152J-130D01*
G01Y214250D01*
G03X1200550Y214120I200J0D01*
G01X1200551Y214119D01*
G02X1200921Y213132I-1131J-987D01*
G02X1197917I-1502J0D01*
G02X1198287Y214119I1501J0D01*
G01Y214120D01*
X1198288D01*
G03X1198336Y214250I-152J130D01*
G01Y214514D01*
G03X1198288Y214644I-200J0D01*
G01X1198287Y214645D01*
G02X1197917Y215632I1131J987D01*
G37*
G36*
G01X1300279D02*
G02X1303283I1502J0D01*
G02X1302913Y214645I-1501J0D01*
G01Y214644D01*
X1302912D01*
G03X1302864Y214514I152J-130D01*
G01Y214250D01*
G03X1302912Y214120I200J0D01*
G01X1302913Y214119D01*
G02X1303283Y213132I-1131J-987D01*
G02X1300279I-1502J0D01*
G02X1300649Y214119I1501J0D01*
G01Y214120D01*
X1300650D01*
G03X1300698Y214250I-152J130D01*
G01Y214514D01*
G03X1300650Y214644I-200J0D01*
G01X1300649Y214645D01*
G02X1300279Y215632I1131J987D01*
G37*
G36*
G01X1450280D02*
G02X1453284I1502J0D01*
G02X1452914Y214645I-1501J0D01*
G01Y214644D01*
X1452913D01*
G03X1452865Y214514I152J-130D01*
G01Y214250D01*
G03X1452913Y214120I200J0D01*
G01X1452914Y214119D01*
G02X1453284Y213132I-1131J-987D01*
G02X1450280I-1502J0D01*
G02X1450650Y214119I1501J0D01*
G01Y214120D01*
X1450651D01*
G03X1450699Y214250I-152J130D01*
G01Y214514D01*
G03X1450651Y214644I-200J0D01*
G01X1450650Y214645D01*
G02X1450280Y215632I1131J987D01*
G37*
G36*
G01X1552642D02*
G02X1555646I1502J0D01*
G02X1555276Y214645I-1501J0D01*
G01Y214644D01*
X1555275D01*
G03X1555227Y214514I152J-130D01*
G01Y214250D01*
G03X1555275Y214120I200J0D01*
G01X1555276Y214119D01*
G02X1555646Y213132I-1131J-987D01*
G02X1552642I-1502J0D01*
G02X1553012Y214119I1501J0D01*
G01Y214120D01*
X1553013D01*
G03X1553061Y214250I-152J130D01*
G01Y214514D01*
G03X1553013Y214644I-200J0D01*
G01X1553012Y214645D01*
G02X1552642Y215632I1131J987D01*
G37*
G36*
G01X1655004D02*
G02X1658008I1502J0D01*
G02X1657638Y214645I-1501J0D01*
G01Y214644D01*
X1657637D01*
G03X1657589Y214514I152J-130D01*
G01Y214250D01*
G03X1657637Y214120I200J0D01*
G01X1657638Y214119D01*
G02X1658008Y213132I-1131J-987D01*
G02X1655004I-1502J0D01*
G02X1655374Y214119I1501J0D01*
G01Y214120D01*
X1655375D01*
G03X1655423Y214250I-152J130D01*
G01Y214514D01*
G03X1655375Y214644I-200J0D01*
G01X1655374Y214645D01*
G02X1655004Y215632I1131J987D01*
G37*
G36*
G01X1757366D02*
G02X1760370I1502J0D01*
G02X1760000Y214645I-1501J0D01*
G01Y214644D01*
X1759999D01*
G03X1759951Y214514I152J-130D01*
G01Y214250D01*
G03X1759999Y214120I200J0D01*
G01X1760000Y214119D01*
G02X1760370Y213132I-1131J-987D01*
G02X1757366I-1502J0D01*
G02X1757736Y214119I1501J0D01*
G01Y214120D01*
X1757737D01*
G03X1757785Y214250I-152J130D01*
G01Y214514D01*
G03X1757737Y214644I-200J0D01*
G01X1757736Y214645D01*
G02X1757366Y215632I1131J987D01*
G37*
G36*
G01X63687Y215713D02*
G02X66691I1502J0D01*
G02X66321Y214726I-1501J0D01*
G01Y214725D01*
X66320D01*
G03X66272Y214595I152J-130D01*
G01Y214331D01*
G03X66320Y214201I200J0D01*
G01X66321Y214200D01*
G02Y212226I-1131J-987D01*
G01Y212225D01*
X66320D01*
G03X66272Y212095I152J-130D01*
G01Y211831D01*
G03X66320Y211701I200J0D01*
G01X66321Y211700D01*
G02Y209726I-1131J-987D01*
G01Y209725D01*
X66320D01*
G03X66272Y209595I152J-130D01*
G01Y209331D01*
G03X66320Y209201I200J0D01*
G01X66321Y209200D01*
G02X66691Y208213I-1131J-987D01*
G02X63687I-1502J0D01*
G02X64057Y209200I1501J0D01*
G01Y209201D01*
X64058D01*
G03X64106Y209331I-152J130D01*
G01Y209595D01*
G03X64058Y209725I-200J0D01*
G01X64057Y209726D01*
G02Y211700I1131J987D01*
G01Y211701D01*
X64058D01*
G03X64106Y211831I-152J130D01*
G01Y212095D01*
G03X64058Y212225I-200J0D01*
G01X64057Y212226D01*
G02Y214200I1131J987D01*
G01Y214201D01*
X64058D01*
G03X64106Y214331I-152J130D01*
G01Y214595D01*
G03X64058Y214725I-200J0D01*
G01X64057Y214726D01*
G02X63687Y215713I1131J987D01*
G37*
G36*
G01X166049D02*
G02X169053I1502J0D01*
G02X168683Y214726I-1501J0D01*
G01Y214725D01*
X168682D01*
G03X168634Y214595I152J-130D01*
G01Y214331D01*
G03X168682Y214201I200J0D01*
G01X168683Y214200D01*
G02Y212226I-1131J-987D01*
G01Y212225D01*
X168682D01*
G03X168634Y212095I152J-130D01*
G01Y211831D01*
G03X168682Y211701I200J0D01*
G01X168683Y211700D01*
G02Y209726I-1131J-987D01*
G01Y209725D01*
X168682D01*
G03X168634Y209595I152J-130D01*
G01Y209331D01*
G03X168682Y209201I200J0D01*
G01X168683Y209200D01*
G02X169053Y208213I-1131J-987D01*
G02X166049I-1502J0D01*
G02X166419Y209200I1501J0D01*
G01Y209201D01*
X166420D01*
G03X166468Y209331I-152J130D01*
G01Y209595D01*
G03X166420Y209725I-200J0D01*
G01X166419Y209726D01*
G02Y211700I1131J987D01*
G01Y211701D01*
X166420D01*
G03X166468Y211831I-152J130D01*
G01Y212095D01*
G03X166420Y212225I-200J0D01*
G01X166419Y212226D01*
G02Y214200I1131J987D01*
G01Y214201D01*
X166420D01*
G03X166468Y214331I-152J130D01*
G01Y214595D01*
G03X166420Y214725I-200J0D01*
G01X166419Y214726D01*
G02X166049Y215713I1131J987D01*
G37*
G36*
G01X268411D02*
G02X271415I1502J0D01*
G02X271045Y214726I-1501J0D01*
G01Y214725D01*
X271044D01*
G03X270996Y214595I152J-130D01*
G01Y214331D01*
G03X271044Y214201I200J0D01*
G01X271045Y214200D01*
G02Y212226I-1131J-987D01*
G01Y212225D01*
X271044D01*
G03X270996Y212095I152J-130D01*
G01Y211831D01*
G03X271044Y211701I200J0D01*
G01X271045Y211700D01*
G02Y209726I-1131J-987D01*
G01Y209725D01*
X271044D01*
G03X270996Y209595I152J-130D01*
G01Y209331D01*
G03X271044Y209201I200J0D01*
G01X271045Y209200D01*
G02X271415Y208213I-1131J-987D01*
G02X268411I-1502J0D01*
G02X268781Y209200I1501J0D01*
G01Y209201D01*
X268782D01*
G03X268830Y209331I-152J130D01*
G01Y209595D01*
G03X268782Y209725I-200J0D01*
G01X268781Y209726D01*
G02Y211700I1131J987D01*
G01Y211701D01*
X268782D01*
G03X268830Y211831I-152J130D01*
G01Y212095D01*
G03X268782Y212225I-200J0D01*
G01X268781Y212226D01*
G02Y214200I1131J987D01*
G01Y214201D01*
X268782D01*
G03X268830Y214331I-152J130D01*
G01Y214595D01*
G03X268782Y214725I-200J0D01*
G01X268781Y214726D01*
G02X268411Y215713I1131J987D01*
G37*
G36*
G01X370773D02*
G02X373777I1502J0D01*
G02X373407Y214726I-1501J0D01*
G01Y214725D01*
X373406D01*
G03X373358Y214595I152J-130D01*
G01Y214331D01*
G03X373406Y214201I200J0D01*
G01X373407Y214200D01*
G02Y212226I-1131J-987D01*
G01Y212225D01*
X373406D01*
G03X373358Y212095I152J-130D01*
G01Y211831D01*
G03X373406Y211701I200J0D01*
G01X373407Y211700D01*
G02Y209726I-1131J-987D01*
G01Y209725D01*
X373406D01*
G03X373358Y209595I152J-130D01*
G01Y209331D01*
G03X373406Y209201I200J0D01*
G01X373407Y209200D01*
G02X373777Y208213I-1131J-987D01*
G02X370773I-1502J0D01*
G02X371143Y209200I1501J0D01*
G01Y209201D01*
X371144D01*
G03X371192Y209331I-152J130D01*
G01Y209595D01*
G03X371144Y209725I-200J0D01*
G01X371143Y209726D01*
G02Y211700I1131J987D01*
G01Y211701D01*
X371144D01*
G03X371192Y211831I-152J130D01*
G01Y212095D01*
G03X371144Y212225I-200J0D01*
G01X371143Y212226D01*
G02Y214200I1131J987D01*
G01Y214201D01*
X371144D01*
G03X371192Y214331I-152J130D01*
G01Y214595D01*
G03X371144Y214725I-200J0D01*
G01X371143Y214726D01*
G02X370773Y215713I1131J987D01*
G37*
G36*
G01X520774D02*
G02X523778I1502J0D01*
G02X523408Y214726I-1501J0D01*
G01Y214725D01*
X523407D01*
G03X523359Y214595I152J-130D01*
G01Y214331D01*
G03X523407Y214201I200J0D01*
G01X523408Y214200D01*
G02Y212226I-1131J-987D01*
G01Y212225D01*
X523407D01*
G03X523359Y212095I152J-130D01*
G01Y211831D01*
G03X523407Y211701I200J0D01*
G01X523408Y211700D01*
G02Y209726I-1131J-987D01*
G01Y209725D01*
X523407D01*
G03X523359Y209595I152J-130D01*
G01Y209331D01*
G03X523407Y209201I200J0D01*
G01X523408Y209200D01*
G02X523778Y208213I-1131J-987D01*
G02X520774I-1502J0D01*
G02X521144Y209200I1501J0D01*
G01Y209201D01*
X521145D01*
G03X521193Y209331I-152J130D01*
G01Y209595D01*
G03X521145Y209725I-200J0D01*
G01X521144Y209726D01*
G02Y211700I1131J987D01*
G01Y211701D01*
X521145D01*
G03X521193Y211831I-152J130D01*
G01Y212095D01*
G03X521145Y212225I-200J0D01*
G01X521144Y212226D01*
G02Y214200I1131J987D01*
G01Y214201D01*
X521145D01*
G03X521193Y214331I-152J130D01*
G01Y214595D01*
G03X521145Y214725I-200J0D01*
G01X521144Y214726D01*
G02X520774Y215713I1131J987D01*
G37*
G36*
G01X623136D02*
G02X626140I1502J0D01*
G02X625770Y214726I-1501J0D01*
G01Y214725D01*
X625769D01*
G03X625721Y214595I152J-130D01*
G01Y214331D01*
G03X625769Y214201I200J0D01*
G01X625770Y214200D01*
G02Y212226I-1131J-987D01*
G01Y212225D01*
X625769D01*
G03X625721Y212095I152J-130D01*
G01Y211831D01*
G03X625769Y211701I200J0D01*
G01X625770Y211700D01*
G02Y209726I-1131J-987D01*
G01Y209725D01*
X625769D01*
G03X625721Y209595I152J-130D01*
G01Y209331D01*
G03X625769Y209201I200J0D01*
G01X625770Y209200D01*
G02X626140Y208213I-1131J-987D01*
G02X623136I-1502J0D01*
G02X623506Y209200I1501J0D01*
G01Y209201D01*
X623507D01*
G03X623555Y209331I-152J130D01*
G01Y209595D01*
G03X623507Y209725I-200J0D01*
G01X623506Y209726D01*
G02Y211700I1131J987D01*
G01Y211701D01*
X623507D01*
G03X623555Y211831I-152J130D01*
G01Y212095D01*
G03X623507Y212225I-200J0D01*
G01X623506Y212226D01*
G02Y214200I1131J987D01*
G01Y214201D01*
X623507D01*
G03X623555Y214331I-152J130D01*
G01Y214595D01*
G03X623507Y214725I-200J0D01*
G01X623506Y214726D01*
G02X623136Y215713I1131J987D01*
G37*
G36*
G01X725498D02*
G02X728502I1502J0D01*
G02X728132Y214726I-1501J0D01*
G01Y214725D01*
X728131D01*
G03X728083Y214595I152J-130D01*
G01Y214331D01*
G03X728131Y214201I200J0D01*
G01X728132Y214200D01*
G02Y212226I-1131J-987D01*
G01Y212225D01*
X728131D01*
G03X728083Y212095I152J-130D01*
G01Y211831D01*
G03X728131Y211701I200J0D01*
G01X728132Y211700D01*
G02Y209726I-1131J-987D01*
G01Y209725D01*
X728131D01*
G03X728083Y209595I152J-130D01*
G01Y209331D01*
G03X728131Y209201I200J0D01*
G01X728132Y209200D01*
G02X728502Y208213I-1131J-987D01*
G02X725498I-1502J0D01*
G02X725868Y209200I1501J0D01*
G01Y209201D01*
X725869D01*
G03X725917Y209331I-152J130D01*
G01Y209595D01*
G03X725869Y209725I-200J0D01*
G01X725868Y209726D01*
G02Y211700I1131J987D01*
G01Y211701D01*
X725869D01*
G03X725917Y211831I-152J130D01*
G01Y212095D01*
G03X725869Y212225I-200J0D01*
G01X725868Y212226D01*
G02Y214200I1131J987D01*
G01Y214201D01*
X725869D01*
G03X725917Y214331I-152J130D01*
G01Y214595D01*
G03X725869Y214725I-200J0D01*
G01X725868Y214726D01*
G02X725498Y215713I1131J987D01*
G37*
G36*
G01X827860D02*
G02X830864I1502J0D01*
G02X830494Y214726I-1501J0D01*
G01Y214725D01*
X830493D01*
G03X830445Y214595I152J-130D01*
G01Y214331D01*
G03X830493Y214201I200J0D01*
G01X830494Y214200D01*
G02Y212226I-1131J-987D01*
G01Y212225D01*
X830493D01*
G03X830445Y212095I152J-130D01*
G01Y211831D01*
G03X830493Y211701I200J0D01*
G01X830494Y211700D01*
G02Y209726I-1131J-987D01*
G01Y209725D01*
X830493D01*
G03X830445Y209595I152J-130D01*
G01Y209331D01*
G03X830493Y209201I200J0D01*
G01X830494Y209200D01*
G02X830864Y208213I-1131J-987D01*
G02X827860I-1502J0D01*
G02X828230Y209200I1501J0D01*
G01Y209201D01*
X828231D01*
G03X828279Y209331I-152J130D01*
G01Y209595D01*
G03X828231Y209725I-200J0D01*
G01X828230Y209726D01*
G02Y211700I1131J987D01*
G01Y211701D01*
X828231D01*
G03X828279Y211831I-152J130D01*
G01Y212095D01*
G03X828231Y212225I-200J0D01*
G01X828230Y212226D01*
G02Y214200I1131J987D01*
G01Y214201D01*
X828231D01*
G03X828279Y214331I-152J130D01*
G01Y214595D01*
G03X828231Y214725I-200J0D01*
G01X828230Y214726D01*
G02X827860Y215713I1131J987D01*
G37*
G36*
G01X977860D02*
G02X980864I1502J0D01*
G02X980494Y214726I-1501J0D01*
G01Y214725D01*
X980493D01*
G03X980445Y214595I152J-130D01*
G01Y214331D01*
G03X980493Y214201I200J0D01*
G01X980494Y214200D01*
G02Y212226I-1131J-987D01*
G01Y212225D01*
X980493D01*
G03X980445Y212095I152J-130D01*
G01Y211831D01*
G03X980493Y211701I200J0D01*
G01X980494Y211700D01*
G02Y209726I-1131J-987D01*
G01Y209725D01*
X980493D01*
G03X980445Y209595I152J-130D01*
G01Y209331D01*
G03X980493Y209201I200J0D01*
G01X980494Y209200D01*
G02X980864Y208213I-1131J-987D01*
G02X977860I-1502J0D01*
G02X978230Y209200I1501J0D01*
G01Y209201D01*
X978231D01*
G03X978279Y209331I-152J130D01*
G01Y209595D01*
G03X978231Y209725I-200J0D01*
G01X978230Y209726D01*
G02Y211700I1131J987D01*
G01Y211701D01*
X978231D01*
G03X978279Y211831I-152J130D01*
G01Y212095D01*
G03X978231Y212225I-200J0D01*
G01X978230Y212226D01*
G02Y214200I1131J987D01*
G01Y214201D01*
X978231D01*
G03X978279Y214331I-152J130D01*
G01Y214595D01*
G03X978231Y214725I-200J0D01*
G01X978230Y214726D01*
G02X977860Y215713I1131J987D01*
G37*
G36*
G01X1080222D02*
G02X1083226I1502J0D01*
G02X1082856Y214726I-1501J0D01*
G01Y214725D01*
X1082855D01*
G03X1082807Y214595I152J-130D01*
G01Y214331D01*
G03X1082855Y214201I200J0D01*
G01X1082856Y214200D01*
G02Y212226I-1131J-987D01*
G01Y212225D01*
X1082855D01*
G03X1082807Y212095I152J-130D01*
G01Y211831D01*
G03X1082855Y211701I200J0D01*
G01X1082856Y211700D01*
G02Y209726I-1131J-987D01*
G01Y209725D01*
X1082855D01*
G03X1082807Y209595I152J-130D01*
G01Y209331D01*
G03X1082855Y209201I200J0D01*
G01X1082856Y209200D01*
G02X1083226Y208213I-1131J-987D01*
G02X1080222I-1502J0D01*
G02X1080592Y209200I1501J0D01*
G01Y209201D01*
X1080593D01*
G03X1080641Y209331I-152J130D01*
G01Y209595D01*
G03X1080593Y209725I-200J0D01*
G01X1080592Y209726D01*
G02Y211700I1131J987D01*
G01Y211701D01*
X1080593D01*
G03X1080641Y211831I-152J130D01*
G01Y212095D01*
G03X1080593Y212225I-200J0D01*
G01X1080592Y212226D01*
G02Y214200I1131J987D01*
G01Y214201D01*
X1080593D01*
G03X1080641Y214331I-152J130D01*
G01Y214595D01*
G03X1080593Y214725I-200J0D01*
G01X1080592Y214726D01*
G02X1080222Y215713I1131J987D01*
G37*
G36*
G01X1182584D02*
G02X1185588I1502J0D01*
G02X1185218Y214726I-1501J0D01*
G01Y214725D01*
X1185217D01*
G03X1185169Y214595I152J-130D01*
G01Y214331D01*
G03X1185217Y214201I200J0D01*
G01X1185218Y214200D01*
G02Y212226I-1131J-987D01*
G01Y212225D01*
X1185217D01*
G03X1185169Y212095I152J-130D01*
G01Y211831D01*
G03X1185217Y211701I200J0D01*
G01X1185218Y211700D01*
G02Y209726I-1131J-987D01*
G01Y209725D01*
X1185217D01*
G03X1185169Y209595I152J-130D01*
G01Y209331D01*
G03X1185217Y209201I200J0D01*
G01X1185218Y209200D01*
G02X1185588Y208213I-1131J-987D01*
G02X1182584I-1502J0D01*
G02X1182954Y209200I1501J0D01*
G01Y209201D01*
X1182955D01*
G03X1183003Y209331I-152J130D01*
G01Y209595D01*
G03X1182955Y209725I-200J0D01*
G01X1182954Y209726D01*
G02Y211700I1131J987D01*
G01Y211701D01*
X1182955D01*
G03X1183003Y211831I-152J130D01*
G01Y212095D01*
G03X1182955Y212225I-200J0D01*
G01X1182954Y212226D01*
G02Y214200I1131J987D01*
G01Y214201D01*
X1182955D01*
G03X1183003Y214331I-152J130D01*
G01Y214595D01*
G03X1182955Y214725I-200J0D01*
G01X1182954Y214726D01*
G02X1182584Y215713I1131J987D01*
G37*
G36*
G01X1284946D02*
G02X1287950I1502J0D01*
G02X1287580Y214726I-1501J0D01*
G01Y214725D01*
X1287579D01*
G03X1287531Y214595I152J-130D01*
G01Y214331D01*
G03X1287579Y214201I200J0D01*
G01X1287580Y214200D01*
G02Y212226I-1131J-987D01*
G01Y212225D01*
X1287579D01*
G03X1287531Y212095I152J-130D01*
G01Y211831D01*
G03X1287579Y211701I200J0D01*
G01X1287580Y211700D01*
G02Y209726I-1131J-987D01*
G01Y209725D01*
X1287579D01*
G03X1287531Y209595I152J-130D01*
G01Y209331D01*
G03X1287579Y209201I200J0D01*
G01X1287580Y209200D01*
G02X1287950Y208213I-1131J-987D01*
G02X1284946I-1502J0D01*
G02X1285316Y209200I1501J0D01*
G01Y209201D01*
X1285317D01*
G03X1285365Y209331I-152J130D01*
G01Y209595D01*
G03X1285317Y209725I-200J0D01*
G01X1285316Y209726D01*
G02Y211700I1131J987D01*
G01Y211701D01*
X1285317D01*
G03X1285365Y211831I-152J130D01*
G01Y212095D01*
G03X1285317Y212225I-200J0D01*
G01X1285316Y212226D01*
G02Y214200I1131J987D01*
G01Y214201D01*
X1285317D01*
G03X1285365Y214331I-152J130D01*
G01Y214595D01*
G03X1285317Y214725I-200J0D01*
G01X1285316Y214726D01*
G02X1284946Y215713I1131J987D01*
G37*
G36*
G01X1434947D02*
G02X1437951I1502J0D01*
G02X1437581Y214726I-1501J0D01*
G01Y214725D01*
X1437580D01*
G03X1437532Y214595I152J-130D01*
G01Y214331D01*
G03X1437580Y214201I200J0D01*
G01X1437581Y214200D01*
G02Y212226I-1131J-987D01*
G01Y212225D01*
X1437580D01*
G03X1437532Y212095I152J-130D01*
G01Y211831D01*
G03X1437580Y211701I200J0D01*
G01X1437581Y211700D01*
G02Y209726I-1131J-987D01*
G01Y209725D01*
X1437580D01*
G03X1437532Y209595I152J-130D01*
G01Y209331D01*
G03X1437580Y209201I200J0D01*
G01X1437581Y209200D01*
G02X1437951Y208213I-1131J-987D01*
G02X1434947I-1502J0D01*
G02X1435317Y209200I1501J0D01*
G01Y209201D01*
X1435318D01*
G03X1435366Y209331I-152J130D01*
G01Y209595D01*
G03X1435318Y209725I-200J0D01*
G01X1435317Y209726D01*
G02Y211700I1131J987D01*
G01Y211701D01*
X1435318D01*
G03X1435366Y211831I-152J130D01*
G01Y212095D01*
G03X1435318Y212225I-200J0D01*
G01X1435317Y212226D01*
G02Y214200I1131J987D01*
G01Y214201D01*
X1435318D01*
G03X1435366Y214331I-152J130D01*
G01Y214595D01*
G03X1435318Y214725I-200J0D01*
G01X1435317Y214726D01*
G02X1434947Y215713I1131J987D01*
G37*
G36*
G01X1537309D02*
G02X1540313I1502J0D01*
G02X1539943Y214726I-1501J0D01*
G01Y214725D01*
X1539942D01*
G03X1539894Y214595I152J-130D01*
G01Y214331D01*
G03X1539942Y214201I200J0D01*
G01X1539943Y214200D01*
G02Y212226I-1131J-987D01*
G01Y212225D01*
X1539942D01*
G03X1539894Y212095I152J-130D01*
G01Y211831D01*
G03X1539942Y211701I200J0D01*
G01X1539943Y211700D01*
G02Y209726I-1131J-987D01*
G01Y209725D01*
X1539942D01*
G03X1539894Y209595I152J-130D01*
G01Y209331D01*
G03X1539942Y209201I200J0D01*
G01X1539943Y209200D01*
G02X1540313Y208213I-1131J-987D01*
G02X1537309I-1502J0D01*
G02X1537679Y209200I1501J0D01*
G01Y209201D01*
X1537680D01*
G03X1537728Y209331I-152J130D01*
G01Y209595D01*
G03X1537680Y209725I-200J0D01*
G01X1537679Y209726D01*
G02Y211700I1131J987D01*
G01Y211701D01*
X1537680D01*
G03X1537728Y211831I-152J130D01*
G01Y212095D01*
G03X1537680Y212225I-200J0D01*
G01X1537679Y212226D01*
G02Y214200I1131J987D01*
G01Y214201D01*
X1537680D01*
G03X1537728Y214331I-152J130D01*
G01Y214595D01*
G03X1537680Y214725I-200J0D01*
G01X1537679Y214726D01*
G02X1537309Y215713I1131J987D01*
G37*
G36*
G01X1639671D02*
G02X1642675I1502J0D01*
G02X1642305Y214726I-1501J0D01*
G01Y214725D01*
X1642304D01*
G03X1642256Y214595I152J-130D01*
G01Y214331D01*
G03X1642304Y214201I200J0D01*
G01X1642305Y214200D01*
G02Y212226I-1131J-987D01*
G01Y212225D01*
X1642304D01*
G03X1642256Y212095I152J-130D01*
G01Y211831D01*
G03X1642304Y211701I200J0D01*
G01X1642305Y211700D01*
G02Y209726I-1131J-987D01*
G01Y209725D01*
X1642304D01*
G03X1642256Y209595I152J-130D01*
G01Y209331D01*
G03X1642304Y209201I200J0D01*
G01X1642305Y209200D01*
G02X1642675Y208213I-1131J-987D01*
G02X1639671I-1502J0D01*
G02X1640041Y209200I1501J0D01*
G01Y209201D01*
X1640042D01*
G03X1640090Y209331I-152J130D01*
G01Y209595D01*
G03X1640042Y209725I-200J0D01*
G01X1640041Y209726D01*
G02Y211700I1131J987D01*
G01Y211701D01*
X1640042D01*
G03X1640090Y211831I-152J130D01*
G01Y212095D01*
G03X1640042Y212225I-200J0D01*
G01X1640041Y212226D01*
G02Y214200I1131J987D01*
G01Y214201D01*
X1640042D01*
G03X1640090Y214331I-152J130D01*
G01Y214595D01*
G03X1640042Y214725I-200J0D01*
G01X1640041Y214726D01*
G02X1639671Y215713I1131J987D01*
G37*
G36*
G01X1742033D02*
G02X1745037I1502J0D01*
G02X1744667Y214726I-1501J0D01*
G01Y214725D01*
X1744666D01*
G03X1744618Y214595I152J-130D01*
G01Y214331D01*
G03X1744666Y214201I200J0D01*
G01X1744667Y214200D01*
G02Y212226I-1131J-987D01*
G01Y212225D01*
X1744666D01*
G03X1744618Y212095I152J-130D01*
G01Y211831D01*
G03X1744666Y211701I200J0D01*
G01X1744667Y211700D01*
G02Y209726I-1131J-987D01*
G01Y209725D01*
X1744666D01*
G03X1744618Y209595I152J-130D01*
G01Y209331D01*
G03X1744666Y209201I200J0D01*
G01X1744667Y209200D01*
G02X1745037Y208213I-1131J-987D01*
G02X1742033I-1502J0D01*
G02X1742403Y209200I1501J0D01*
G01Y209201D01*
X1742404D01*
G03X1742452Y209331I-152J130D01*
G01Y209595D01*
G03X1742404Y209725I-200J0D01*
G01X1742403Y209726D01*
G02Y211700I1131J987D01*
G01Y211701D01*
X1742404D01*
G03X1742452Y211831I-152J130D01*
G01Y212095D01*
G03X1742404Y212225I-200J0D01*
G01X1742403Y212226D01*
G02Y214200I1131J987D01*
G01Y214201D01*
X1742404D01*
G03X1742452Y214331I-152J130D01*
G01Y214595D01*
G03X1742404Y214725I-200J0D01*
G01X1742403Y214726D01*
G02X1742033Y215713I1131J987D01*
G37*
G36*
G01X11806Y217133D02*
X11512D01*
G03X11365Y217068I1J-200D01*
G02X10259Y216583I-1106J1019D01*
G02Y219587I0J1502D01*
G02X11365Y219102I0J-1504D01*
G03X11512Y219037I148J135D01*
G01X11806D01*
G03X11953Y219102I-1J200D01*
G02X13059Y219587I1106J-1019D01*
G02Y216583I0J-1502D01*
G02X11953Y217068I0J1504D01*
G03X11806Y217133I-148J-135D01*
G37*
G36*
G01X114168D02*
X113874D01*
G03X113727Y217068I1J-200D01*
G02X112621Y216583I-1106J1019D01*
G02Y219587I0J1502D01*
G02X113727Y219102I0J-1504D01*
G03X113874Y219037I148J135D01*
G01X114168D01*
G03X114315Y219102I-1J200D01*
G02X115421Y219587I1106J-1019D01*
G02Y216583I0J-1502D01*
G02X114315Y217068I0J1504D01*
G03X114168Y217133I-148J-135D01*
G37*
G36*
G01X216530D02*
X216236D01*
G03X216089Y217068I1J-200D01*
G02X214983Y216583I-1106J1019D01*
G02Y219587I0J1502D01*
G02X216089Y219102I0J-1504D01*
G03X216236Y219037I148J135D01*
G01X216530D01*
G03X216677Y219102I-1J200D01*
G02X217783Y219587I1106J-1019D01*
G02Y216583I0J-1502D01*
G02X216677Y217068I0J1504D01*
G03X216530Y217133I-148J-135D01*
G37*
G36*
G01X318892D02*
X318598D01*
G03X318451Y217068I1J-200D01*
G02X317345Y216583I-1106J1019D01*
G02Y219587I0J1502D01*
G02X318451Y219102I0J-1504D01*
G03X318598Y219037I148J135D01*
G01X318892D01*
G03X319039Y219102I-1J200D01*
G02X320145Y219587I1106J-1019D01*
G02Y216583I0J-1502D01*
G02X319039Y217068I0J1504D01*
G03X318892Y217133I-148J-135D01*
G37*
G36*
G01X468893D02*
X468599D01*
G03X468452Y217068I1J-200D01*
G02X467346Y216583I-1106J1019D01*
G02Y219587I0J1502D01*
G02X468452Y219102I0J-1504D01*
G03X468599Y219037I148J135D01*
G01X468893D01*
G03X469040Y219102I-1J200D01*
G02X470146Y219587I1106J-1019D01*
G02Y216583I0J-1502D01*
G02X469040Y217068I0J1504D01*
G03X468893Y217133I-148J-135D01*
G37*
G36*
G01X571255D02*
X570961D01*
G03X570814Y217068I1J-200D01*
G02X569708Y216583I-1106J1019D01*
G02Y219587I0J1502D01*
G02X570814Y219102I0J-1504D01*
G03X570961Y219037I148J135D01*
G01X571255D01*
G03X571402Y219102I-1J200D01*
G02X572508Y219587I1106J-1019D01*
G02Y216583I0J-1502D01*
G02X571402Y217068I0J1504D01*
G03X571255Y217133I-148J-135D01*
G37*
G36*
G01X673617D02*
X673323D01*
G03X673176Y217068I1J-200D01*
G02X672070Y216583I-1106J1019D01*
G02Y219587I0J1502D01*
G02X673176Y219102I0J-1504D01*
G03X673323Y219037I148J135D01*
G01X673617D01*
G03X673764Y219102I-1J200D01*
G02X674870Y219587I1106J-1019D01*
G02Y216583I0J-1502D01*
G02X673764Y217068I0J1504D01*
G03X673617Y217133I-148J-135D01*
G37*
G36*
G01X775979D02*
X775685D01*
G03X775538Y217068I1J-200D01*
G02X774432Y216583I-1106J1019D01*
G02Y219587I0J1502D01*
G02X775538Y219102I0J-1504D01*
G03X775685Y219037I148J135D01*
G01X775979D01*
G03X776126Y219102I-1J200D01*
G02X777232Y219587I1106J-1019D01*
G02Y216583I0J-1502D01*
G02X776126Y217068I0J1504D01*
G03X775979Y217133I-148J-135D01*
G37*
G36*
G01X1028341D02*
X1028047D01*
G03X1027900Y217068I1J-200D01*
G02X1026794Y216583I-1106J1019D01*
G02Y219587I0J1502D01*
G02X1027900Y219102I0J-1504D01*
G03X1028047Y219037I148J135D01*
G01X1028341D01*
G03X1028488Y219102I-1J200D01*
G02X1029594Y219587I1106J-1019D01*
G02Y216583I0J-1502D01*
G02X1028488Y217068I0J1504D01*
G03X1028341Y217133I-148J-135D01*
G37*
G36*
G01X1130703D02*
X1130409D01*
G03X1130262Y217068I1J-200D01*
G02X1129156Y216583I-1106J1019D01*
G02Y219587I0J1502D01*
G02X1130262Y219102I0J-1504D01*
G03X1130409Y219037I148J135D01*
G01X1130703D01*
G03X1130850Y219102I-1J200D01*
G02X1131956Y219587I1106J-1019D01*
G02Y216583I0J-1502D01*
G02X1130850Y217068I0J1504D01*
G03X1130703Y217133I-148J-135D01*
G37*
G36*
G01X1233065D02*
X1232771D01*
G03X1232624Y217068I1J-200D01*
G02X1231518Y216583I-1106J1019D01*
G02Y219587I0J1502D01*
G02X1232624Y219102I0J-1504D01*
G03X1232771Y219037I148J135D01*
G01X1233065D01*
G03X1233212Y219102I-1J200D01*
G02X1234318Y219587I1106J-1019D01*
G02Y216583I0J-1502D01*
G02X1233212Y217068I0J1504D01*
G03X1233065Y217133I-148J-135D01*
G37*
G36*
G01X1383066D02*
X1382772D01*
G03X1382625Y217068I1J-200D01*
G02X1381519Y216583I-1106J1019D01*
G02Y219587I0J1502D01*
G02X1382625Y219102I0J-1504D01*
G03X1382772Y219037I148J135D01*
G01X1383066D01*
G03X1383213Y219102I-1J200D01*
G02X1384319Y219587I1106J-1019D01*
G02Y216583I0J-1502D01*
G02X1383213Y217068I0J1504D01*
G03X1383066Y217133I-148J-135D01*
G37*
G36*
G01X1485428D02*
X1485134D01*
G03X1484987Y217068I1J-200D01*
G02X1483881Y216583I-1106J1019D01*
G02Y219587I0J1502D01*
G02X1484987Y219102I0J-1504D01*
G03X1485134Y219037I148J135D01*
G01X1485428D01*
G03X1485575Y219102I-1J200D01*
G02X1486681Y219587I1106J-1019D01*
G02Y216583I0J-1502D01*
G02X1485575Y217068I0J1504D01*
G03X1485428Y217133I-148J-135D01*
G37*
G36*
G01X1587790D02*
X1587496D01*
G03X1587349Y217068I1J-200D01*
G02X1586243Y216583I-1106J1019D01*
G02Y219587I0J1502D01*
G02X1587349Y219102I0J-1504D01*
G03X1587496Y219037I148J135D01*
G01X1587790D01*
G03X1587937Y219102I-1J200D01*
G02X1589043Y219587I1106J-1019D01*
G02Y216583I0J-1502D01*
G02X1587937Y217068I0J1504D01*
G03X1587790Y217133I-148J-135D01*
G37*
G36*
G01X1690152D02*
X1689858D01*
G03X1689711Y217068I1J-200D01*
G02X1688605Y216583I-1106J1019D01*
G02Y219587I0J1502D01*
G02X1689711Y219102I0J-1504D01*
G03X1689858Y219037I148J135D01*
G01X1690152D01*
G03X1690299Y219102I-1J200D01*
G02X1691405Y219587I1106J-1019D01*
G02Y216583I0J-1502D01*
G02X1690299Y217068I0J1504D01*
G03X1690152Y217133I-148J-135D01*
G37*
G36*
G01X18070Y221970D02*
G02X21074I1502J0D01*
G02X20704Y220983I-1501J0D01*
G01Y220982D01*
X20703D01*
G03X20655Y220852I152J-130D01*
G01Y220588D01*
G03X20703Y220458I200J0D01*
G01X20704Y220457D01*
G02Y218483I-1131J-987D01*
G01Y218482D01*
X20703D01*
G03X20655Y218352I152J-130D01*
G01Y218088D01*
G03X20703Y217958I200J0D01*
G01X20704Y217957D01*
G02X21074Y216970I-1131J-987D01*
G02X19572Y215468I-1502J0D01*
G02X18717Y215735I0J1502D01*
G01X18683Y215758D01*
X18602Y215775D01*
X18235Y215695D01*
X18168Y215647D01*
X18147Y215612D01*
G02X16859Y214883I-1288J773D01*
G02Y217887I0J1502D01*
G02X17714Y217620I0J-1502D01*
G01X17748Y217597D01*
X17829Y217580D01*
X18196Y217660D01*
X18263Y217708D01*
X18284Y217743D01*
G02X18440Y217956I1285J-777D01*
G03X18441Y217958I-173J88D01*
G03X18489Y218088I-152J130D01*
G01Y218352D01*
G03X18441Y218482I-200J0D01*
G01X18440Y218483D01*
G02Y220457I1131J987D01*
G01Y220458D01*
X18441D01*
G03X18489Y220588I-152J130D01*
G01Y220852D01*
G03X18441Y220982I-200J0D01*
G01X18440Y220983D01*
G02X18070Y221970I1131J987D01*
G37*
G36*
G01X120432D02*
G02X123436I1502J0D01*
G02X123066Y220983I-1501J0D01*
G01Y220982D01*
X123065D01*
G03X123017Y220852I152J-130D01*
G01Y220588D01*
G03X123065Y220458I200J0D01*
G01X123066Y220457D01*
G02Y218483I-1131J-987D01*
G01Y218482D01*
X123065D01*
G03X123017Y218352I152J-130D01*
G01Y218088D01*
G03X123065Y217958I200J0D01*
G01X123066Y217957D01*
G02X123436Y216970I-1131J-987D01*
G02X121934Y215468I-1502J0D01*
G02X121079Y215735I0J1502D01*
G01X121045Y215758D01*
X120964Y215775D01*
X120597Y215695D01*
X120530Y215647D01*
X120509Y215612D01*
G02X119221Y214883I-1288J773D01*
G02Y217887I0J1502D01*
G02X120076Y217620I0J-1502D01*
G01X120110Y217597D01*
X120191Y217580D01*
X120558Y217660D01*
X120625Y217708D01*
X120646Y217743D01*
G02X120802Y217956I1285J-777D01*
G03X120803Y217958I-173J88D01*
G03X120851Y218088I-152J130D01*
G01Y218352D01*
G03X120803Y218482I-200J0D01*
G01X120802Y218483D01*
G02Y220457I1131J987D01*
G01Y220458D01*
X120803D01*
G03X120851Y220588I-152J130D01*
G01Y220852D01*
G03X120803Y220982I-200J0D01*
G01X120802Y220983D01*
G02X120432Y221970I1131J987D01*
G37*
G36*
G01X222794D02*
G02X225798I1502J0D01*
G02X225428Y220983I-1501J0D01*
G01Y220982D01*
X225427D01*
G03X225379Y220852I152J-130D01*
G01Y220588D01*
G03X225427Y220458I200J0D01*
G01X225428Y220457D01*
G02Y218483I-1131J-987D01*
G01Y218482D01*
X225427D01*
G03X225379Y218352I152J-130D01*
G01Y218088D01*
G03X225427Y217958I200J0D01*
G01X225428Y217957D01*
G02X225798Y216970I-1131J-987D01*
G02X224296Y215468I-1502J0D01*
G02X223441Y215735I0J1502D01*
G01X223407Y215758D01*
X223326Y215775D01*
X222959Y215695D01*
X222892Y215647D01*
X222871Y215612D01*
G02X221583Y214883I-1288J773D01*
G02Y217887I0J1502D01*
G02X222438Y217620I0J-1502D01*
G01X222472Y217597D01*
X222553Y217580D01*
X222920Y217660D01*
X222987Y217708D01*
X223008Y217743D01*
G02X223164Y217956I1285J-777D01*
G03X223165Y217958I-173J88D01*
G03X223213Y218088I-152J130D01*
G01Y218352D01*
G03X223165Y218482I-200J0D01*
G01X223164Y218483D01*
G02Y220457I1131J987D01*
G01Y220458D01*
X223165D01*
G03X223213Y220588I-152J130D01*
G01Y220852D01*
G03X223165Y220982I-200J0D01*
G01X223164Y220983D01*
G02X222794Y221970I1131J987D01*
G37*
G36*
G01X325156D02*
G02X328160I1502J0D01*
G02X327790Y220983I-1501J0D01*
G01Y220982D01*
X327789D01*
G03X327741Y220852I152J-130D01*
G01Y220588D01*
G03X327789Y220458I200J0D01*
G01X327790Y220457D01*
G02Y218483I-1131J-987D01*
G01Y218482D01*
X327789D01*
G03X327741Y218352I152J-130D01*
G01Y218088D01*
G03X327789Y217958I200J0D01*
G01X327790Y217957D01*
G02X328160Y216970I-1131J-987D01*
G02X326658Y215468I-1502J0D01*
G02X325803Y215735I0J1502D01*
G01X325769Y215758D01*
X325688Y215775D01*
X325321Y215695D01*
X325254Y215647D01*
X325233Y215612D01*
G02X323945Y214883I-1288J773D01*
G02Y217887I0J1502D01*
G02X324800Y217620I0J-1502D01*
G01X324834Y217597D01*
X324915Y217580D01*
X325282Y217660D01*
X325349Y217708D01*
X325370Y217743D01*
G02X325526Y217956I1285J-777D01*
G03X325527Y217958I-173J88D01*
G03X325575Y218088I-152J130D01*
G01Y218352D01*
G03X325527Y218482I-200J0D01*
G01X325526Y218483D01*
G02Y220457I1131J987D01*
G01Y220458D01*
X325527D01*
G03X325575Y220588I-152J130D01*
G01Y220852D01*
G03X325527Y220982I-200J0D01*
G01X325526Y220983D01*
G02X325156Y221970I1131J987D01*
G37*
G36*
G01X475157D02*
G02X478161I1502J0D01*
G02X477791Y220983I-1501J0D01*
G01Y220982D01*
X477790D01*
G03X477742Y220852I152J-130D01*
G01Y220588D01*
G03X477790Y220458I200J0D01*
G01X477791Y220457D01*
G02Y218483I-1131J-987D01*
G01Y218482D01*
X477790D01*
G03X477742Y218352I152J-130D01*
G01Y218088D01*
G03X477790Y217958I200J0D01*
G01X477791Y217957D01*
G02X478161Y216970I-1131J-987D01*
G02X476659Y215468I-1502J0D01*
G02X475804Y215735I0J1502D01*
G01X475770Y215758D01*
X475689Y215775D01*
X475322Y215695D01*
X475255Y215647D01*
X475234Y215612D01*
G02X473946Y214883I-1288J773D01*
G02Y217887I0J1502D01*
G02X474801Y217620I0J-1502D01*
G01X474835Y217597D01*
X474916Y217580D01*
X475283Y217660D01*
X475350Y217708D01*
X475371Y217743D01*
G02X475527Y217956I1285J-777D01*
G03X475528Y217958I-173J88D01*
G03X475576Y218088I-152J130D01*
G01Y218352D01*
G03X475528Y218482I-200J0D01*
G01X475527Y218483D01*
G02Y220457I1131J987D01*
G01Y220458D01*
X475528D01*
G03X475576Y220588I-152J130D01*
G01Y220852D01*
G03X475528Y220982I-200J0D01*
G01X475527Y220983D01*
G02X475157Y221970I1131J987D01*
G37*
G36*
G01X577519D02*
G02X580523I1502J0D01*
G02X580153Y220983I-1501J0D01*
G01Y220982D01*
X580152D01*
G03X580104Y220852I152J-130D01*
G01Y220588D01*
G03X580152Y220458I200J0D01*
G01X580153Y220457D01*
G02Y218483I-1131J-987D01*
G01Y218482D01*
X580152D01*
G03X580104Y218352I152J-130D01*
G01Y218088D01*
G03X580152Y217958I200J0D01*
G01X580153Y217957D01*
G02X580523Y216970I-1131J-987D01*
G02X579021Y215468I-1502J0D01*
G02X578166Y215735I0J1502D01*
G01X578132Y215758D01*
X578051Y215775D01*
X577684Y215695D01*
X577617Y215647D01*
X577596Y215612D01*
G02X576308Y214883I-1288J773D01*
G02Y217887I0J1502D01*
G02X577163Y217620I0J-1502D01*
G01X577197Y217597D01*
X577278Y217580D01*
X577645Y217660D01*
X577712Y217708D01*
X577733Y217743D01*
G02X577889Y217956I1285J-777D01*
G03X577890Y217958I-173J88D01*
G03X577938Y218088I-152J130D01*
G01Y218352D01*
G03X577890Y218482I-200J0D01*
G01X577889Y218483D01*
G02Y220457I1131J987D01*
G01Y220458D01*
X577890D01*
G03X577938Y220588I-152J130D01*
G01Y220852D01*
G03X577890Y220982I-200J0D01*
G01X577889Y220983D01*
G02X577519Y221970I1131J987D01*
G37*
G36*
G01X679881D02*
G02X682885I1502J0D01*
G02X682515Y220983I-1501J0D01*
G01Y220982D01*
X682514D01*
G03X682466Y220852I152J-130D01*
G01Y220588D01*
G03X682514Y220458I200J0D01*
G01X682515Y220457D01*
G02Y218483I-1131J-987D01*
G01Y218482D01*
X682514D01*
G03X682466Y218352I152J-130D01*
G01Y218088D01*
G03X682514Y217958I200J0D01*
G01X682515Y217957D01*
G02X682885Y216970I-1131J-987D01*
G02X681383Y215468I-1502J0D01*
G02X680528Y215735I0J1502D01*
G01X680494Y215758D01*
X680413Y215775D01*
X680046Y215695D01*
X679979Y215647D01*
X679958Y215612D01*
G02X678670Y214883I-1288J773D01*
G02Y217887I0J1502D01*
G02X679525Y217620I0J-1502D01*
G01X679559Y217597D01*
X679640Y217580D01*
X680007Y217660D01*
X680074Y217708D01*
X680095Y217743D01*
G02X680251Y217956I1285J-777D01*
G03X680252Y217958I-173J88D01*
G03X680300Y218088I-152J130D01*
G01Y218352D01*
G03X680252Y218482I-200J0D01*
G01X680251Y218483D01*
G02Y220457I1131J987D01*
G01Y220458D01*
X680252D01*
G03X680300Y220588I-152J130D01*
G01Y220852D01*
G03X680252Y220982I-200J0D01*
G01X680251Y220983D01*
G02X679881Y221970I1131J987D01*
G37*
G36*
G01X782243D02*
G02X785247I1502J0D01*
G02X784877Y220983I-1501J0D01*
G01Y220982D01*
X784876D01*
G03X784828Y220852I152J-130D01*
G01Y220588D01*
G03X784876Y220458I200J0D01*
G01X784877Y220457D01*
G02Y218483I-1131J-987D01*
G01Y218482D01*
X784876D01*
G03X784828Y218352I152J-130D01*
G01Y218088D01*
G03X784876Y217958I200J0D01*
G01X784877Y217957D01*
G02X785247Y216970I-1131J-987D01*
G02X783745Y215468I-1502J0D01*
G02X782890Y215735I0J1502D01*
G01X782856Y215758D01*
X782775Y215775D01*
X782408Y215695D01*
X782341Y215647D01*
X782320Y215612D01*
G02X781032Y214883I-1288J773D01*
G02Y217887I0J1502D01*
G02X781887Y217620I0J-1502D01*
G01X781921Y217597D01*
X782002Y217580D01*
X782369Y217660D01*
X782436Y217708D01*
X782457Y217743D01*
G02X782613Y217956I1285J-777D01*
G03X782614Y217958I-173J88D01*
G03X782662Y218088I-152J130D01*
G01Y218352D01*
G03X782614Y218482I-200J0D01*
G01X782613Y218483D01*
G02Y220457I1131J987D01*
G01Y220458D01*
X782614D01*
G03X782662Y220588I-152J130D01*
G01Y220852D01*
G03X782614Y220982I-200J0D01*
G01X782613Y220983D01*
G02X782243Y221970I1131J987D01*
G37*
G36*
G01X1034605D02*
G02X1037609I1502J0D01*
G02X1037239Y220983I-1501J0D01*
G01Y220982D01*
X1037238D01*
G03X1037190Y220852I152J-130D01*
G01Y220588D01*
G03X1037238Y220458I200J0D01*
G01X1037239Y220457D01*
G02Y218483I-1131J-987D01*
G01Y218482D01*
X1037238D01*
G03X1037190Y218352I152J-130D01*
G01Y218088D01*
G03X1037238Y217958I200J0D01*
G01X1037239Y217957D01*
G02X1037609Y216970I-1131J-987D01*
G02X1036107Y215468I-1502J0D01*
G02X1035252Y215735I0J1502D01*
G01X1035218Y215758D01*
X1035137Y215775D01*
X1034770Y215695D01*
X1034703Y215647D01*
X1034682Y215612D01*
G02X1033394Y214883I-1288J773D01*
G02Y217887I0J1502D01*
G02X1034249Y217620I0J-1502D01*
G01X1034283Y217597D01*
X1034364Y217580D01*
X1034731Y217660D01*
X1034798Y217708D01*
X1034819Y217743D01*
G02X1034975Y217956I1285J-777D01*
G03X1034976Y217958I-173J88D01*
G03X1035024Y218088I-152J130D01*
G01Y218352D01*
G03X1034976Y218482I-200J0D01*
G01X1034975Y218483D01*
G02Y220457I1131J987D01*
G01Y220458D01*
X1034976D01*
G03X1035024Y220588I-152J130D01*
G01Y220852D01*
G03X1034976Y220982I-200J0D01*
G01X1034975Y220983D01*
G02X1034605Y221970I1131J987D01*
G37*
G36*
G01X1136967D02*
G02X1139971I1502J0D01*
G02X1139601Y220983I-1501J0D01*
G01Y220982D01*
X1139600D01*
G03X1139552Y220852I152J-130D01*
G01Y220588D01*
G03X1139600Y220458I200J0D01*
G01X1139601Y220457D01*
G02Y218483I-1131J-987D01*
G01Y218482D01*
X1139600D01*
G03X1139552Y218352I152J-130D01*
G01Y218088D01*
G03X1139600Y217958I200J0D01*
G01X1139601Y217957D01*
G02X1139971Y216970I-1131J-987D01*
G02X1138469Y215468I-1502J0D01*
G02X1137614Y215735I0J1502D01*
G01X1137580Y215758D01*
X1137499Y215775D01*
X1137132Y215695D01*
X1137065Y215647D01*
X1137044Y215612D01*
G02X1135756Y214883I-1288J773D01*
G02Y217887I0J1502D01*
G02X1136611Y217620I0J-1502D01*
G01X1136645Y217597D01*
X1136726Y217580D01*
X1137093Y217660D01*
X1137160Y217708D01*
X1137181Y217743D01*
G02X1137337Y217956I1285J-777D01*
G03X1137338Y217958I-173J88D01*
G03X1137386Y218088I-152J130D01*
G01Y218352D01*
G03X1137338Y218482I-200J0D01*
G01X1137337Y218483D01*
G02Y220457I1131J987D01*
G01Y220458D01*
X1137338D01*
G03X1137386Y220588I-152J130D01*
G01Y220852D01*
G03X1137338Y220982I-200J0D01*
G01X1137337Y220983D01*
G02X1136967Y221970I1131J987D01*
G37*
G36*
G01X1239329D02*
G02X1242333I1502J0D01*
G02X1241963Y220983I-1501J0D01*
G01Y220982D01*
X1241962D01*
G03X1241914Y220852I152J-130D01*
G01Y220588D01*
G03X1241962Y220458I200J0D01*
G01X1241963Y220457D01*
G02Y218483I-1131J-987D01*
G01Y218482D01*
X1241962D01*
G03X1241914Y218352I152J-130D01*
G01Y218088D01*
G03X1241962Y217958I200J0D01*
G01X1241963Y217957D01*
G02X1242333Y216970I-1131J-987D01*
G02X1240831Y215468I-1502J0D01*
G02X1239976Y215735I0J1502D01*
G01X1239942Y215758D01*
X1239861Y215775D01*
X1239494Y215695D01*
X1239427Y215647D01*
X1239406Y215612D01*
G02X1238118Y214883I-1288J773D01*
G02Y217887I0J1502D01*
G02X1238973Y217620I0J-1502D01*
G01X1239007Y217597D01*
X1239088Y217580D01*
X1239455Y217660D01*
X1239522Y217708D01*
X1239543Y217743D01*
G02X1239699Y217956I1285J-777D01*
G03X1239700Y217958I-173J88D01*
G03X1239748Y218088I-152J130D01*
G01Y218352D01*
G03X1239700Y218482I-200J0D01*
G01X1239699Y218483D01*
G02Y220457I1131J987D01*
G01Y220458D01*
X1239700D01*
G03X1239748Y220588I-152J130D01*
G01Y220852D01*
G03X1239700Y220982I-200J0D01*
G01X1239699Y220983D01*
G02X1239329Y221970I1131J987D01*
G37*
G36*
G01X1389330D02*
G02X1392334I1502J0D01*
G02X1391964Y220983I-1501J0D01*
G01Y220982D01*
X1391963D01*
G03X1391915Y220852I152J-130D01*
G01Y220588D01*
G03X1391963Y220458I200J0D01*
G01X1391964Y220457D01*
G02Y218483I-1131J-987D01*
G01Y218482D01*
X1391963D01*
G03X1391915Y218352I152J-130D01*
G01Y218088D01*
G03X1391963Y217958I200J0D01*
G01X1391964Y217957D01*
G02X1392334Y216970I-1131J-987D01*
G02X1390832Y215468I-1502J0D01*
G02X1389977Y215735I0J1502D01*
G01X1389943Y215758D01*
X1389862Y215775D01*
X1389495Y215695D01*
X1389428Y215647D01*
X1389407Y215612D01*
G02X1388119Y214883I-1288J773D01*
G02Y217887I0J1502D01*
G02X1388974Y217620I0J-1502D01*
G01X1389008Y217597D01*
X1389089Y217580D01*
X1389456Y217660D01*
X1389523Y217708D01*
X1389544Y217743D01*
G02X1389700Y217956I1285J-777D01*
G03X1389701Y217958I-173J88D01*
G03X1389749Y218088I-152J130D01*
G01Y218352D01*
G03X1389701Y218482I-200J0D01*
G01X1389700Y218483D01*
G02Y220457I1131J987D01*
G01Y220458D01*
X1389701D01*
G03X1389749Y220588I-152J130D01*
G01Y220852D01*
G03X1389701Y220982I-200J0D01*
G01X1389700Y220983D01*
G02X1389330Y221970I1131J987D01*
G37*
G36*
G01X1491692D02*
G02X1494696I1502J0D01*
G02X1494326Y220983I-1501J0D01*
G01Y220982D01*
X1494325D01*
G03X1494277Y220852I152J-130D01*
G01Y220588D01*
G03X1494325Y220458I200J0D01*
G01X1494326Y220457D01*
G02Y218483I-1131J-987D01*
G01Y218482D01*
X1494325D01*
G03X1494277Y218352I152J-130D01*
G01Y218088D01*
G03X1494325Y217958I200J0D01*
G01X1494326Y217957D01*
G02X1494696Y216970I-1131J-987D01*
G02X1493194Y215468I-1502J0D01*
G02X1492339Y215735I0J1502D01*
G01X1492305Y215758D01*
X1492224Y215775D01*
X1491857Y215695D01*
X1491790Y215647D01*
X1491769Y215612D01*
G02X1490481Y214883I-1288J773D01*
G02Y217887I0J1502D01*
G02X1491336Y217620I0J-1502D01*
G01X1491370Y217597D01*
X1491451Y217580D01*
X1491818Y217660D01*
X1491885Y217708D01*
X1491906Y217743D01*
G02X1492062Y217956I1285J-777D01*
G03X1492063Y217958I-173J88D01*
G03X1492111Y218088I-152J130D01*
G01Y218352D01*
G03X1492063Y218482I-200J0D01*
G01X1492062Y218483D01*
G02Y220457I1131J987D01*
G01Y220458D01*
X1492063D01*
G03X1492111Y220588I-152J130D01*
G01Y220852D01*
G03X1492063Y220982I-200J0D01*
G01X1492062Y220983D01*
G02X1491692Y221970I1131J987D01*
G37*
G36*
G01X1594054D02*
G02X1597058I1502J0D01*
G02X1596688Y220983I-1501J0D01*
G01Y220982D01*
X1596687D01*
G03X1596639Y220852I152J-130D01*
G01Y220588D01*
G03X1596687Y220458I200J0D01*
G01X1596688Y220457D01*
G02Y218483I-1131J-987D01*
G01Y218482D01*
X1596687D01*
G03X1596639Y218352I152J-130D01*
G01Y218088D01*
G03X1596687Y217958I200J0D01*
G01X1596688Y217957D01*
G02X1597058Y216970I-1131J-987D01*
G02X1595556Y215468I-1502J0D01*
G02X1594701Y215735I0J1502D01*
G01X1594667Y215758D01*
X1594586Y215775D01*
X1594219Y215695D01*
X1594152Y215647D01*
X1594131Y215612D01*
G02X1592843Y214883I-1288J773D01*
G02Y217887I0J1502D01*
G02X1593698Y217620I0J-1502D01*
G01X1593732Y217597D01*
X1593813Y217580D01*
X1594180Y217660D01*
X1594247Y217708D01*
X1594268Y217743D01*
G02X1594424Y217956I1285J-777D01*
G03X1594425Y217958I-173J88D01*
G03X1594473Y218088I-152J130D01*
G01Y218352D01*
G03X1594425Y218482I-200J0D01*
G01X1594424Y218483D01*
G02Y220457I1131J987D01*
G01Y220458D01*
X1594425D01*
G03X1594473Y220588I-152J130D01*
G01Y220852D01*
G03X1594425Y220982I-200J0D01*
G01X1594424Y220983D01*
G02X1594054Y221970I1131J987D01*
G37*
G36*
G01X1696416D02*
G02X1699420I1502J0D01*
G02X1699050Y220983I-1501J0D01*
G01Y220982D01*
X1699049D01*
G03X1699001Y220852I152J-130D01*
G01Y220588D01*
G03X1699049Y220458I200J0D01*
G01X1699050Y220457D01*
G02Y218483I-1131J-987D01*
G01Y218482D01*
X1699049D01*
G03X1699001Y218352I152J-130D01*
G01Y218088D01*
G03X1699049Y217958I200J0D01*
G01X1699050Y217957D01*
G02X1699420Y216970I-1131J-987D01*
G02X1697918Y215468I-1502J0D01*
G02X1697063Y215735I0J1502D01*
G01X1697029Y215758D01*
X1696948Y215775D01*
X1696581Y215695D01*
X1696514Y215647D01*
X1696493Y215612D01*
G02X1695205Y214883I-1288J773D01*
G02Y217887I0J1502D01*
G02X1696060Y217620I0J-1502D01*
G01X1696094Y217597D01*
X1696175Y217580D01*
X1696542Y217660D01*
X1696609Y217708D01*
X1696630Y217743D01*
G02X1696786Y217956I1285J-777D01*
G03X1696787Y217958I-173J88D01*
G03X1696835Y218088I-152J130D01*
G01Y218352D01*
G03X1696787Y218482I-200J0D01*
G01X1696786Y218483D01*
G02Y220457I1131J987D01*
G01Y220458D01*
X1696787D01*
G03X1696835Y220588I-152J130D01*
G01Y220852D01*
G03X1696787Y220982I-200J0D01*
G01X1696786Y220983D01*
G02X1696416Y221970I1131J987D01*
G37*
G36*
G01X84896Y224421D02*
G02X87900I1502J0D01*
G02X87633Y223566I-1502J0D01*
G01X87610Y223532D01*
X87593Y223451D01*
X87673Y223084D01*
X87721Y223017D01*
X87756Y222996D01*
G02X87969Y222840I-777J-1285D01*
G03X87971Y222839I88J173D01*
G03X88101Y222791I130J152D01*
G01X88365D01*
G03X88495Y222839I0J200D01*
G01X88496Y222840D01*
G02X90470I987J-1131D01*
G01X90471D01*
Y222839D01*
G03X90601Y222791I130J152D01*
G01X90865D01*
G03X90995Y222839I0J200D01*
G01X90996Y222840D01*
G02X91983Y223210I987J-1131D01*
G02Y220206I0J-1502D01*
G02X90996Y220576I0J1501D01*
G01X90995D01*
Y220577D01*
G03X90865Y220625I-130J-152D01*
G01X90601D01*
G03X90471Y220577I0J-200D01*
G01X90470Y220576D01*
G02X88496I-987J1131D01*
G01X88495D01*
Y220577D01*
G03X88365Y220625I-130J-152D01*
G01X88101D01*
G03X87971Y220577I0J-200D01*
G01X87970Y220576D01*
G02X86983Y220206I-987J1131D01*
G02X85481Y221708I0J1502D01*
G02X85748Y222563I1502J0D01*
G01X85771Y222597D01*
X85788Y222678D01*
X85708Y223045D01*
X85660Y223112D01*
X85625Y223133D01*
G02X84896Y224421I773J1288D01*
G37*
G36*
G01X187258D02*
G02X190262I1502J0D01*
G02X189995Y223566I-1502J0D01*
G01X189972Y223532D01*
X189955Y223451D01*
X190035Y223084D01*
X190083Y223017D01*
X190118Y222996D01*
G02X190331Y222840I-777J-1285D01*
G03X190333Y222839I88J173D01*
G03X190463Y222791I130J152D01*
G01X190727D01*
G03X190857Y222839I0J200D01*
G01X190858Y222840D01*
G02X192832I987J-1131D01*
G01X192833D01*
Y222839D01*
G03X192963Y222791I130J152D01*
G01X193227D01*
G03X193357Y222839I0J200D01*
G01X193358Y222840D01*
G02X194345Y223210I987J-1131D01*
G02Y220206I0J-1502D01*
G02X193358Y220576I0J1501D01*
G01X193357D01*
Y220577D01*
G03X193227Y220625I-130J-152D01*
G01X192963D01*
G03X192833Y220577I0J-200D01*
G01X192832Y220576D01*
G02X190858I-987J1131D01*
G01X190857D01*
Y220577D01*
G03X190727Y220625I-130J-152D01*
G01X190463D01*
G03X190333Y220577I0J-200D01*
G01X190332Y220576D01*
G02X189345Y220206I-987J1131D01*
G02X187843Y221708I0J1502D01*
G02X188110Y222563I1502J0D01*
G01X188133Y222597D01*
X188150Y222678D01*
X188070Y223045D01*
X188022Y223112D01*
X187987Y223133D01*
G02X187258Y224421I773J1288D01*
G37*
G36*
G01X289620D02*
G02X292624I1502J0D01*
G02X292357Y223566I-1502J0D01*
G01X292334Y223532D01*
X292317Y223451D01*
X292397Y223084D01*
X292445Y223017D01*
X292480Y222996D01*
G02X292693Y222840I-777J-1285D01*
G03X292695Y222839I88J173D01*
G03X292825Y222791I130J152D01*
G01X293089D01*
G03X293219Y222839I0J200D01*
G01X293220Y222840D01*
G02X295194I987J-1131D01*
G01X295195D01*
Y222839D01*
G03X295325Y222791I130J152D01*
G01X295589D01*
G03X295719Y222839I0J200D01*
G01X295720Y222840D01*
G02X296707Y223210I987J-1131D01*
G02Y220206I0J-1502D01*
G02X295720Y220576I0J1501D01*
G01X295719D01*
Y220577D01*
G03X295589Y220625I-130J-152D01*
G01X295325D01*
G03X295195Y220577I0J-200D01*
G01X295194Y220576D01*
G02X293220I-987J1131D01*
G01X293219D01*
Y220577D01*
G03X293089Y220625I-130J-152D01*
G01X292825D01*
G03X292695Y220577I0J-200D01*
G01X292694Y220576D01*
G02X291707Y220206I-987J1131D01*
G02X290205Y221708I0J1502D01*
G02X290472Y222563I1502J0D01*
G01X290495Y222597D01*
X290512Y222678D01*
X290432Y223045D01*
X290384Y223112D01*
X290349Y223133D01*
G02X289620Y224421I773J1288D01*
G37*
G36*
G01X391982D02*
G02X394986I1502J0D01*
G02X394719Y223566I-1502J0D01*
G01X394696Y223532D01*
X394679Y223451D01*
X394759Y223084D01*
X394807Y223017D01*
X394842Y222996D01*
G02X395055Y222840I-777J-1285D01*
G03X395057Y222839I88J173D01*
G03X395187Y222791I130J152D01*
G01X395451D01*
G03X395581Y222839I0J200D01*
G01X395582Y222840D01*
G02X397556I987J-1131D01*
G01X397557D01*
Y222839D01*
G03X397687Y222791I130J152D01*
G01X397951D01*
G03X398081Y222839I0J200D01*
G01X398082Y222840D01*
G02X399069Y223210I987J-1131D01*
G02Y220206I0J-1502D01*
G02X398082Y220576I0J1501D01*
G01X398081D01*
Y220577D01*
G03X397951Y220625I-130J-152D01*
G01X397687D01*
G03X397557Y220577I0J-200D01*
G01X397556Y220576D01*
G02X395582I-987J1131D01*
G01X395581D01*
Y220577D01*
G03X395451Y220625I-130J-152D01*
G01X395187D01*
G03X395057Y220577I0J-200D01*
G01X395056Y220576D01*
G02X394069Y220206I-987J1131D01*
G02X392567Y221708I0J1502D01*
G02X392834Y222563I1502J0D01*
G01X392857Y222597D01*
X392874Y222678D01*
X392794Y223045D01*
X392746Y223112D01*
X392711Y223133D01*
G02X391982Y224421I773J1288D01*
G37*
G36*
G01X541983D02*
G02X544987I1502J0D01*
G02X544720Y223566I-1502J0D01*
G01X544697Y223532D01*
X544680Y223451D01*
X544760Y223084D01*
X544808Y223017D01*
X544843Y222996D01*
G02X545056Y222840I-777J-1285D01*
G03X545058Y222839I88J173D01*
G03X545188Y222791I130J152D01*
G01X545452D01*
G03X545582Y222839I0J200D01*
G01X545583Y222840D01*
G02X547557I987J-1131D01*
G01X547558D01*
Y222839D01*
G03X547688Y222791I130J152D01*
G01X547952D01*
G03X548082Y222839I0J200D01*
G01X548083Y222840D01*
G02X549070Y223210I987J-1131D01*
G02Y220206I0J-1502D01*
G02X548083Y220576I0J1501D01*
G01X548082D01*
Y220577D01*
G03X547952Y220625I-130J-152D01*
G01X547688D01*
G03X547558Y220577I0J-200D01*
G01X547557Y220576D01*
G02X545583I-987J1131D01*
G01X545582D01*
Y220577D01*
G03X545452Y220625I-130J-152D01*
G01X545188D01*
G03X545058Y220577I0J-200D01*
G01X545057Y220576D01*
G02X544070Y220206I-987J1131D01*
G02X542568Y221708I0J1502D01*
G02X542835Y222563I1502J0D01*
G01X542858Y222597D01*
X542875Y222678D01*
X542795Y223045D01*
X542747Y223112D01*
X542712Y223133D01*
G02X541983Y224421I773J1288D01*
G37*
G36*
G01X644345D02*
G02X647349I1502J0D01*
G02X647082Y223566I-1502J0D01*
G01X647059Y223532D01*
X647042Y223451D01*
X647122Y223084D01*
X647170Y223017D01*
X647205Y222996D01*
G02X647418Y222840I-777J-1285D01*
G03X647420Y222839I88J173D01*
G03X647550Y222791I130J152D01*
G01X647814D01*
G03X647944Y222839I0J200D01*
G01X647945Y222840D01*
G02X649919I987J-1131D01*
G01X649920D01*
Y222839D01*
G03X650050Y222791I130J152D01*
G01X650314D01*
G03X650444Y222839I0J200D01*
G01X650445Y222840D01*
G02X651432Y223210I987J-1131D01*
G02Y220206I0J-1502D01*
G02X650445Y220576I0J1501D01*
G01X650444D01*
Y220577D01*
G03X650314Y220625I-130J-152D01*
G01X650050D01*
G03X649920Y220577I0J-200D01*
G01X649919Y220576D01*
G02X647945I-987J1131D01*
G01X647944D01*
Y220577D01*
G03X647814Y220625I-130J-152D01*
G01X647550D01*
G03X647420Y220577I0J-200D01*
G01X647419Y220576D01*
G02X646432Y220206I-987J1131D01*
G02X644930Y221708I0J1502D01*
G02X645197Y222563I1502J0D01*
G01X645220Y222597D01*
X645237Y222678D01*
X645157Y223045D01*
X645109Y223112D01*
X645074Y223133D01*
G02X644345Y224421I773J1288D01*
G37*
G36*
G01X746707D02*
G02X749711I1502J0D01*
G02X749444Y223566I-1502J0D01*
G01X749421Y223532D01*
X749404Y223451D01*
X749484Y223084D01*
X749532Y223017D01*
X749567Y222996D01*
G02X749780Y222840I-777J-1285D01*
G03X749782Y222839I88J173D01*
G03X749912Y222791I130J152D01*
G01X750176D01*
G03X750306Y222839I0J200D01*
G01X750307Y222840D01*
G02X752281I987J-1131D01*
G01X752282D01*
Y222839D01*
G03X752412Y222791I130J152D01*
G01X752676D01*
G03X752806Y222839I0J200D01*
G01X752807Y222840D01*
G02X753794Y223210I987J-1131D01*
G02Y220206I0J-1502D01*
G02X752807Y220576I0J1501D01*
G01X752806D01*
Y220577D01*
G03X752676Y220625I-130J-152D01*
G01X752412D01*
G03X752282Y220577I0J-200D01*
G01X752281Y220576D01*
G02X750307I-987J1131D01*
G01X750306D01*
Y220577D01*
G03X750176Y220625I-130J-152D01*
G01X749912D01*
G03X749782Y220577I0J-200D01*
G01X749781Y220576D01*
G02X748794Y220206I-987J1131D01*
G02X747292Y221708I0J1502D01*
G02X747559Y222563I1502J0D01*
G01X747582Y222597D01*
X747599Y222678D01*
X747519Y223045D01*
X747471Y223112D01*
X747436Y223133D01*
G02X746707Y224421I773J1288D01*
G37*
G36*
G01X849069D02*
G02X852073I1502J0D01*
G02X851806Y223566I-1502J0D01*
G01X851783Y223532D01*
X851766Y223451D01*
X851846Y223084D01*
X851894Y223017D01*
X851929Y222996D01*
G02X852142Y222840I-777J-1285D01*
G03X852144Y222839I88J173D01*
G03X852274Y222791I130J152D01*
G01X852538D01*
G03X852668Y222839I0J200D01*
G01X852669Y222840D01*
G02X854643I987J-1131D01*
G01X854644D01*
Y222839D01*
G03X854774Y222791I130J152D01*
G01X855038D01*
G03X855168Y222839I0J200D01*
G01X855169Y222840D01*
G02X856156Y223210I987J-1131D01*
G02Y220206I0J-1502D01*
G02X855169Y220576I0J1501D01*
G01X855168D01*
Y220577D01*
G03X855038Y220625I-130J-152D01*
G01X854774D01*
G03X854644Y220577I0J-200D01*
G01X854643Y220576D01*
G02X852669I-987J1131D01*
G01X852668D01*
Y220577D01*
G03X852538Y220625I-130J-152D01*
G01X852274D01*
G03X852144Y220577I0J-200D01*
G01X852143Y220576D01*
G02X851156Y220206I-987J1131D01*
G02X849654Y221708I0J1502D01*
G02X849921Y222563I1502J0D01*
G01X849944Y222597D01*
X849961Y222678D01*
X849881Y223045D01*
X849833Y223112D01*
X849798Y223133D01*
G02X849069Y224421I773J1288D01*
G37*
G36*
G01X999069D02*
G02X1002073I1502J0D01*
G02X1001806Y223566I-1502J0D01*
G01X1001783Y223532D01*
X1001766Y223451D01*
X1001846Y223084D01*
X1001894Y223017D01*
X1001929Y222996D01*
G02X1002142Y222840I-777J-1285D01*
G03X1002144Y222839I88J173D01*
G03X1002274Y222791I130J152D01*
G01X1002538D01*
G03X1002668Y222839I0J200D01*
G01X1002669Y222840D01*
G02X1004643I987J-1131D01*
G01X1004644D01*
Y222839D01*
G03X1004774Y222791I130J152D01*
G01X1005038D01*
G03X1005168Y222839I0J200D01*
G01X1005169Y222840D01*
G02X1006156Y223210I987J-1131D01*
G02Y220206I0J-1502D01*
G02X1005169Y220576I0J1501D01*
G01X1005168D01*
Y220577D01*
G03X1005038Y220625I-130J-152D01*
G01X1004774D01*
G03X1004644Y220577I0J-200D01*
G01X1004643Y220576D01*
G02X1002669I-987J1131D01*
G01X1002668D01*
Y220577D01*
G03X1002538Y220625I-130J-152D01*
G01X1002274D01*
G03X1002144Y220577I0J-200D01*
G01X1002143Y220576D01*
G02X1001156Y220206I-987J1131D01*
G02X999654Y221708I0J1502D01*
G02X999921Y222563I1502J0D01*
G01X999944Y222597D01*
X999961Y222678D01*
X999881Y223045D01*
X999833Y223112D01*
X999798Y223133D01*
G02X999069Y224421I773J1288D01*
G37*
G36*
G01X1101431D02*
G02X1104435I1502J0D01*
G02X1104168Y223566I-1502J0D01*
G01X1104145Y223532D01*
X1104128Y223451D01*
X1104208Y223084D01*
X1104256Y223017D01*
X1104291Y222996D01*
G02X1104504Y222840I-777J-1285D01*
G03X1104506Y222839I88J173D01*
G03X1104636Y222791I130J152D01*
G01X1104900D01*
G03X1105030Y222839I0J200D01*
G01X1105031Y222840D01*
G02X1107005I987J-1131D01*
G01X1107006D01*
Y222839D01*
G03X1107136Y222791I130J152D01*
G01X1107400D01*
G03X1107530Y222839I0J200D01*
G01X1107531Y222840D01*
G02X1108518Y223210I987J-1131D01*
G02Y220206I0J-1502D01*
G02X1107531Y220576I0J1501D01*
G01X1107530D01*
Y220577D01*
G03X1107400Y220625I-130J-152D01*
G01X1107136D01*
G03X1107006Y220577I0J-200D01*
G01X1107005Y220576D01*
G02X1105031I-987J1131D01*
G01X1105030D01*
Y220577D01*
G03X1104900Y220625I-130J-152D01*
G01X1104636D01*
G03X1104506Y220577I0J-200D01*
G01X1104505Y220576D01*
G02X1103518Y220206I-987J1131D01*
G02X1102016Y221708I0J1502D01*
G02X1102283Y222563I1502J0D01*
G01X1102306Y222597D01*
X1102323Y222678D01*
X1102243Y223045D01*
X1102195Y223112D01*
X1102160Y223133D01*
G02X1101431Y224421I773J1288D01*
G37*
G36*
G01X1203793D02*
G02X1206797I1502J0D01*
G02X1206530Y223566I-1502J0D01*
G01X1206507Y223532D01*
X1206490Y223451D01*
X1206570Y223084D01*
X1206618Y223017D01*
X1206653Y222996D01*
G02X1206866Y222840I-777J-1285D01*
G03X1206868Y222839I88J173D01*
G03X1206998Y222791I130J152D01*
G01X1207262D01*
G03X1207392Y222839I0J200D01*
G01X1207393Y222840D01*
G02X1209367I987J-1131D01*
G01X1209368D01*
Y222839D01*
G03X1209498Y222791I130J152D01*
G01X1209762D01*
G03X1209892Y222839I0J200D01*
G01X1209893Y222840D01*
G02X1210880Y223210I987J-1131D01*
G02Y220206I0J-1502D01*
G02X1209893Y220576I0J1501D01*
G01X1209892D01*
Y220577D01*
G03X1209762Y220625I-130J-152D01*
G01X1209498D01*
G03X1209368Y220577I0J-200D01*
G01X1209367Y220576D01*
G02X1207393I-987J1131D01*
G01X1207392D01*
Y220577D01*
G03X1207262Y220625I-130J-152D01*
G01X1206998D01*
G03X1206868Y220577I0J-200D01*
G01X1206867Y220576D01*
G02X1205880Y220206I-987J1131D01*
G02X1204378Y221708I0J1502D01*
G02X1204645Y222563I1502J0D01*
G01X1204668Y222597D01*
X1204685Y222678D01*
X1204605Y223045D01*
X1204557Y223112D01*
X1204522Y223133D01*
G02X1203793Y224421I773J1288D01*
G37*
G36*
G01X1306155D02*
G02X1309159I1502J0D01*
G02X1308892Y223566I-1502J0D01*
G01X1308869Y223532D01*
X1308852Y223451D01*
X1308932Y223084D01*
X1308980Y223017D01*
X1309015Y222996D01*
G02X1309228Y222840I-777J-1285D01*
G03X1309230Y222839I88J173D01*
G03X1309360Y222791I130J152D01*
G01X1309624D01*
G03X1309754Y222839I0J200D01*
G01X1309755Y222840D01*
G02X1311729I987J-1131D01*
G01X1311730D01*
Y222839D01*
G03X1311860Y222791I130J152D01*
G01X1312124D01*
G03X1312254Y222839I0J200D01*
G01X1312255Y222840D01*
G02X1313242Y223210I987J-1131D01*
G02Y220206I0J-1502D01*
G02X1312255Y220576I0J1501D01*
G01X1312254D01*
Y220577D01*
G03X1312124Y220625I-130J-152D01*
G01X1311860D01*
G03X1311730Y220577I0J-200D01*
G01X1311729Y220576D01*
G02X1309755I-987J1131D01*
G01X1309754D01*
Y220577D01*
G03X1309624Y220625I-130J-152D01*
G01X1309360D01*
G03X1309230Y220577I0J-200D01*
G01X1309229Y220576D01*
G02X1308242Y220206I-987J1131D01*
G02X1306740Y221708I0J1502D01*
G02X1307007Y222563I1502J0D01*
G01X1307030Y222597D01*
X1307047Y222678D01*
X1306967Y223045D01*
X1306919Y223112D01*
X1306884Y223133D01*
G02X1306155Y224421I773J1288D01*
G37*
G36*
G01X1456156D02*
G02X1459160I1502J0D01*
G02X1458893Y223566I-1502J0D01*
G01X1458870Y223532D01*
X1458853Y223451D01*
X1458933Y223084D01*
X1458981Y223017D01*
X1459016Y222996D01*
G02X1459229Y222840I-777J-1285D01*
G03X1459231Y222839I88J173D01*
G03X1459361Y222791I130J152D01*
G01X1459625D01*
G03X1459755Y222839I0J200D01*
G01X1459756Y222840D01*
G02X1461730I987J-1131D01*
G01X1461731D01*
Y222839D01*
G03X1461861Y222791I130J152D01*
G01X1462125D01*
G03X1462255Y222839I0J200D01*
G01X1462256Y222840D01*
G02X1463243Y223210I987J-1131D01*
G02Y220206I0J-1502D01*
G02X1462256Y220576I0J1501D01*
G01X1462255D01*
Y220577D01*
G03X1462125Y220625I-130J-152D01*
G01X1461861D01*
G03X1461731Y220577I0J-200D01*
G01X1461730Y220576D01*
G02X1459756I-987J1131D01*
G01X1459755D01*
Y220577D01*
G03X1459625Y220625I-130J-152D01*
G01X1459361D01*
G03X1459231Y220577I0J-200D01*
G01X1459230Y220576D01*
G02X1458243Y220206I-987J1131D01*
G02X1456741Y221708I0J1502D01*
G02X1457008Y222563I1502J0D01*
G01X1457031Y222597D01*
X1457048Y222678D01*
X1456968Y223045D01*
X1456920Y223112D01*
X1456885Y223133D01*
G02X1456156Y224421I773J1288D01*
G37*
G36*
G01X1558518D02*
G02X1561522I1502J0D01*
G02X1561255Y223566I-1502J0D01*
G01X1561232Y223532D01*
X1561215Y223451D01*
X1561295Y223084D01*
X1561343Y223017D01*
X1561378Y222996D01*
G02X1561591Y222840I-777J-1285D01*
G03X1561593Y222839I88J173D01*
G03X1561723Y222791I130J152D01*
G01X1561987D01*
G03X1562117Y222839I0J200D01*
G01X1562118Y222840D01*
G02X1564092I987J-1131D01*
G01X1564093D01*
Y222839D01*
G03X1564223Y222791I130J152D01*
G01X1564487D01*
G03X1564617Y222839I0J200D01*
G01X1564618Y222840D01*
G02X1565605Y223210I987J-1131D01*
G02Y220206I0J-1502D01*
G02X1564618Y220576I0J1501D01*
G01X1564617D01*
Y220577D01*
G03X1564487Y220625I-130J-152D01*
G01X1564223D01*
G03X1564093Y220577I0J-200D01*
G01X1564092Y220576D01*
G02X1562118I-987J1131D01*
G01X1562117D01*
Y220577D01*
G03X1561987Y220625I-130J-152D01*
G01X1561723D01*
G03X1561593Y220577I0J-200D01*
G01X1561592Y220576D01*
G02X1560605Y220206I-987J1131D01*
G02X1559103Y221708I0J1502D01*
G02X1559370Y222563I1502J0D01*
G01X1559393Y222597D01*
X1559410Y222678D01*
X1559330Y223045D01*
X1559282Y223112D01*
X1559247Y223133D01*
G02X1558518Y224421I773J1288D01*
G37*
G36*
G01X1660880D02*
G02X1663884I1502J0D01*
G02X1663617Y223566I-1502J0D01*
G01X1663594Y223532D01*
X1663577Y223451D01*
X1663657Y223084D01*
X1663705Y223017D01*
X1663740Y222996D01*
G02X1663953Y222840I-777J-1285D01*
G03X1663955Y222839I88J173D01*
G03X1664085Y222791I130J152D01*
G01X1664349D01*
G03X1664479Y222839I0J200D01*
G01X1664480Y222840D01*
G02X1666454I987J-1131D01*
G01X1666455D01*
Y222839D01*
G03X1666585Y222791I130J152D01*
G01X1666849D01*
G03X1666979Y222839I0J200D01*
G01X1666980Y222840D01*
G02X1667967Y223210I987J-1131D01*
G02Y220206I0J-1502D01*
G02X1666980Y220576I0J1501D01*
G01X1666979D01*
Y220577D01*
G03X1666849Y220625I-130J-152D01*
G01X1666585D01*
G03X1666455Y220577I0J-200D01*
G01X1666454Y220576D01*
G02X1664480I-987J1131D01*
G01X1664479D01*
Y220577D01*
G03X1664349Y220625I-130J-152D01*
G01X1664085D01*
G03X1663955Y220577I0J-200D01*
G01X1663954Y220576D01*
G02X1662967Y220206I-987J1131D01*
G02X1661465Y221708I0J1502D01*
G02X1661732Y222563I1502J0D01*
G01X1661755Y222597D01*
X1661772Y222678D01*
X1661692Y223045D01*
X1661644Y223112D01*
X1661609Y223133D01*
G02X1660880Y224421I773J1288D01*
G37*
G36*
G01X1763242D02*
G02X1766246I1502J0D01*
G02X1765979Y223566I-1502J0D01*
G01X1765956Y223532D01*
X1765939Y223451D01*
X1766019Y223084D01*
X1766067Y223017D01*
X1766102Y222996D01*
G02X1766315Y222840I-777J-1285D01*
G03X1766317Y222839I88J173D01*
G03X1766447Y222791I130J152D01*
G01X1766711D01*
G03X1766841Y222839I0J200D01*
G01X1766842Y222840D01*
G02X1768816I987J-1131D01*
G01X1768817D01*
Y222839D01*
G03X1768947Y222791I130J152D01*
G01X1769211D01*
G03X1769341Y222839I0J200D01*
G01X1769342Y222840D01*
G02X1770329Y223210I987J-1131D01*
G02Y220206I0J-1502D01*
G02X1769342Y220576I0J1501D01*
G01X1769341D01*
Y220577D01*
G03X1769211Y220625I-130J-152D01*
G01X1768947D01*
G03X1768817Y220577I0J-200D01*
G01X1768816Y220576D01*
G02X1766842I-987J1131D01*
G01X1766841D01*
Y220577D01*
G03X1766711Y220625I-130J-152D01*
G01X1766447D01*
G03X1766317Y220577I0J-200D01*
G01X1766316Y220576D01*
G02X1765329Y220206I-987J1131D01*
G02X1763827Y221708I0J1502D01*
G02X1764094Y222563I1502J0D01*
G01X1764117Y222597D01*
X1764134Y222678D01*
X1764054Y223045D01*
X1764006Y223112D01*
X1763971Y223133D01*
G02X1763242Y224421I773J1288D01*
G37*
G36*
G01X87146Y229474D02*
Y229768D01*
G03X87081Y229915I-200J-1D01*
G02X86596Y231021I1019J1106D01*
G02X89600I1502J0D01*
G02X89115Y229915I-1504J0D01*
G03X89050Y229768I135J-148D01*
G01Y229474D01*
G03X89115Y229327I200J1D01*
G02X89600Y228221I-1019J-1106D01*
G02X86596I-1502J0D01*
G02X87081Y229327I1504J0D01*
G03X87146Y229474I-135J148D01*
G37*
G36*
G01X189508D02*
Y229768D01*
G03X189443Y229915I-200J-1D01*
G02X188958Y231021I1019J1106D01*
G02X191962I1502J0D01*
G02X191477Y229915I-1504J0D01*
G03X191412Y229768I135J-148D01*
G01Y229474D01*
G03X191477Y229327I200J1D01*
G02X191962Y228221I-1019J-1106D01*
G02X188958I-1502J0D01*
G02X189443Y229327I1504J0D01*
G03X189508Y229474I-135J148D01*
G37*
G36*
G01X291870D02*
Y229768D01*
G03X291805Y229915I-200J-1D01*
G02X291320Y231021I1019J1106D01*
G02X294324I1502J0D01*
G02X293839Y229915I-1504J0D01*
G03X293774Y229768I135J-148D01*
G01Y229474D01*
G03X293839Y229327I200J1D01*
G02X294324Y228221I-1019J-1106D01*
G02X291320I-1502J0D01*
G02X291805Y229327I1504J0D01*
G03X291870Y229474I-135J148D01*
G37*
G36*
G01X394232D02*
Y229768D01*
G03X394167Y229915I-200J-1D01*
G02X393682Y231021I1019J1106D01*
G02X396686I1502J0D01*
G02X396201Y229915I-1504J0D01*
G03X396136Y229768I135J-148D01*
G01Y229474D01*
G03X396201Y229327I200J1D01*
G02X396686Y228221I-1019J-1106D01*
G02X393682I-1502J0D01*
G02X394167Y229327I1504J0D01*
G03X394232Y229474I-135J148D01*
G37*
G36*
G01X544233D02*
Y229768D01*
G03X544168Y229915I-200J-1D01*
G02X543683Y231021I1019J1106D01*
G02X546687I1502J0D01*
G02X546202Y229915I-1504J0D01*
G03X546137Y229768I135J-148D01*
G01Y229474D01*
G03X546202Y229327I200J1D01*
G02X546687Y228221I-1019J-1106D01*
G02X543683I-1502J0D01*
G02X544168Y229327I1504J0D01*
G03X544233Y229474I-135J148D01*
G37*
G36*
G01X646595D02*
Y229768D01*
G03X646530Y229915I-200J-1D01*
G02X646045Y231021I1019J1106D01*
G02X649049I1502J0D01*
G02X648564Y229915I-1504J0D01*
G03X648499Y229768I135J-148D01*
G01Y229474D01*
G03X648564Y229327I200J1D01*
G02X649049Y228221I-1019J-1106D01*
G02X646045I-1502J0D01*
G02X646530Y229327I1504J0D01*
G03X646595Y229474I-135J148D01*
G37*
G36*
G01X748957D02*
Y229768D01*
G03X748892Y229915I-200J-1D01*
G02X748407Y231021I1019J1106D01*
G02X751411I1502J0D01*
G02X750926Y229915I-1504J0D01*
G03X750861Y229768I135J-148D01*
G01Y229474D01*
G03X750926Y229327I200J1D01*
G02X751411Y228221I-1019J-1106D01*
G02X748407I-1502J0D01*
G02X748892Y229327I1504J0D01*
G03X748957Y229474I-135J148D01*
G37*
G36*
G01X851319D02*
Y229768D01*
G03X851254Y229915I-200J-1D01*
G02X850769Y231021I1019J1106D01*
G02X853773I1502J0D01*
G02X853288Y229915I-1504J0D01*
G03X853223Y229768I135J-148D01*
G01Y229474D01*
G03X853288Y229327I200J1D01*
G02X853773Y228221I-1019J-1106D01*
G02X850769I-1502J0D01*
G02X851254Y229327I1504J0D01*
G03X851319Y229474I-135J148D01*
G37*
G36*
G01X1001319D02*
Y229768D01*
G03X1001254Y229915I-200J-1D01*
G02X1000769Y231021I1019J1106D01*
G02X1003773I1502J0D01*
G02X1003288Y229915I-1504J0D01*
G03X1003223Y229768I135J-148D01*
G01Y229474D01*
G03X1003288Y229327I200J1D01*
G02X1003773Y228221I-1019J-1106D01*
G02X1000769I-1502J0D01*
G02X1001254Y229327I1504J0D01*
G03X1001319Y229474I-135J148D01*
G37*
G36*
G01X1103681D02*
Y229768D01*
G03X1103616Y229915I-200J-1D01*
G02X1103131Y231021I1019J1106D01*
G02X1106135I1502J0D01*
G02X1105650Y229915I-1504J0D01*
G03X1105585Y229768I135J-148D01*
G01Y229474D01*
G03X1105650Y229327I200J1D01*
G02X1106135Y228221I-1019J-1106D01*
G02X1103131I-1502J0D01*
G02X1103616Y229327I1504J0D01*
G03X1103681Y229474I-135J148D01*
G37*
G36*
G01X1206043D02*
Y229768D01*
G03X1205978Y229915I-200J-1D01*
G02X1205493Y231021I1019J1106D01*
G02X1208497I1502J0D01*
G02X1208012Y229915I-1504J0D01*
G03X1207947Y229768I135J-148D01*
G01Y229474D01*
G03X1208012Y229327I200J1D01*
G02X1208497Y228221I-1019J-1106D01*
G02X1205493I-1502J0D01*
G02X1205978Y229327I1504J0D01*
G03X1206043Y229474I-135J148D01*
G37*
G36*
G01X1308405D02*
Y229768D01*
G03X1308340Y229915I-200J-1D01*
G02X1307855Y231021I1019J1106D01*
G02X1310859I1502J0D01*
G02X1310374Y229915I-1504J0D01*
G03X1310309Y229768I135J-148D01*
G01Y229474D01*
G03X1310374Y229327I200J1D01*
G02X1310859Y228221I-1019J-1106D01*
G02X1307855I-1502J0D01*
G02X1308340Y229327I1504J0D01*
G03X1308405Y229474I-135J148D01*
G37*
G36*
G01X1458406D02*
Y229768D01*
G03X1458341Y229915I-200J-1D01*
G02X1457856Y231021I1019J1106D01*
G02X1460860I1502J0D01*
G02X1460375Y229915I-1504J0D01*
G03X1460310Y229768I135J-148D01*
G01Y229474D01*
G03X1460375Y229327I200J1D01*
G02X1460860Y228221I-1019J-1106D01*
G02X1457856I-1502J0D01*
G02X1458341Y229327I1504J0D01*
G03X1458406Y229474I-135J148D01*
G37*
G36*
G01X1560768D02*
Y229768D01*
G03X1560703Y229915I-200J-1D01*
G02X1560218Y231021I1019J1106D01*
G02X1563222I1502J0D01*
G02X1562737Y229915I-1504J0D01*
G03X1562672Y229768I135J-148D01*
G01Y229474D01*
G03X1562737Y229327I200J1D01*
G02X1563222Y228221I-1019J-1106D01*
G02X1560218I-1502J0D01*
G02X1560703Y229327I1504J0D01*
G03X1560768Y229474I-135J148D01*
G37*
G36*
G01X1663130D02*
Y229768D01*
G03X1663065Y229915I-200J-1D01*
G02X1662580Y231021I1019J1106D01*
G02X1665584I1502J0D01*
G02X1665099Y229915I-1504J0D01*
G03X1665034Y229768I135J-148D01*
G01Y229474D01*
G03X1665099Y229327I200J1D01*
G02X1665584Y228221I-1019J-1106D01*
G02X1662580I-1502J0D01*
G02X1663065Y229327I1504J0D01*
G03X1663130Y229474I-135J148D01*
G37*
G36*
G01X1765492D02*
Y229768D01*
G03X1765427Y229915I-200J-1D01*
G02X1764942Y231021I1019J1106D01*
G02X1767946I1502J0D01*
G02X1767461Y229915I-1504J0D01*
G03X1767396Y229768I135J-148D01*
G01Y229474D01*
G03X1767461Y229327I200J1D01*
G02X1767946Y228221I-1019J-1106D01*
G02X1764942I-1502J0D01*
G02X1765427Y229327I1504J0D01*
G03X1765492Y229474I-135J148D01*
G37*
G36*
G01X92136Y237321D02*
X92137Y237320D01*
G03X92267Y237272I130J152D01*
G01X92531D01*
G03X92661Y237320I0J200D01*
G01X92662Y237321D01*
G02X93649Y237691I987J-1131D01*
G02Y234687I0J-1502D01*
G02X92662Y235057I0J1501D01*
G01X92661D01*
Y235058D01*
G03X92531Y235106I-130J-152D01*
G01X92267D01*
G03X92137Y235058I0J-200D01*
G01X92136Y235057D01*
G02X90162I-987J1131D01*
G01X90161D01*
Y235058D01*
G03X90031Y235106I-130J-152D01*
G01X89767D01*
G03X89637Y235058I0J-200D01*
G01X89636Y235057D01*
G02X88649Y234687I-987J1131D01*
G02Y237691I0J1502D01*
G02X89636Y237321I0J-1501D01*
G01X89637D01*
Y237320D01*
G03X89767Y237272I130J152D01*
G01X90031D01*
G03X90161Y237320I0J200D01*
G01X90162Y237321D01*
G02X92136I987J-1131D01*
G37*
G36*
G01X194498D02*
X194499Y237320D01*
G03X194629Y237272I130J152D01*
G01X194893D01*
G03X195023Y237320I0J200D01*
G01X195024Y237321D01*
G02X196011Y237691I987J-1131D01*
G02Y234687I0J-1502D01*
G02X195024Y235057I0J1501D01*
G01X195023D01*
Y235058D01*
G03X194893Y235106I-130J-152D01*
G01X194629D01*
G03X194499Y235058I0J-200D01*
G01X194498Y235057D01*
G02X192524I-987J1131D01*
G01X192523D01*
Y235058D01*
G03X192393Y235106I-130J-152D01*
G01X192129D01*
G03X191999Y235058I0J-200D01*
G01X191998Y235057D01*
G02X191011Y234687I-987J1131D01*
G02Y237691I0J1502D01*
G02X191998Y237321I0J-1501D01*
G01X191999D01*
Y237320D01*
G03X192129Y237272I130J152D01*
G01X192393D01*
G03X192523Y237320I0J200D01*
G01X192524Y237321D01*
G02X194498I987J-1131D01*
G37*
G36*
G01X296860D02*
X296861Y237320D01*
G03X296991Y237272I130J152D01*
G01X297255D01*
G03X297385Y237320I0J200D01*
G01X297386Y237321D01*
G02X298373Y237691I987J-1131D01*
G02Y234687I0J-1502D01*
G02X297386Y235057I0J1501D01*
G01X297385D01*
Y235058D01*
G03X297255Y235106I-130J-152D01*
G01X296991D01*
G03X296861Y235058I0J-200D01*
G01X296860Y235057D01*
G02X294886I-987J1131D01*
G01X294885D01*
Y235058D01*
G03X294755Y235106I-130J-152D01*
G01X294491D01*
G03X294361Y235058I0J-200D01*
G01X294360Y235057D01*
G02X293373Y234687I-987J1131D01*
G02Y237691I0J1502D01*
G02X294360Y237321I0J-1501D01*
G01X294361D01*
Y237320D01*
G03X294491Y237272I130J152D01*
G01X294755D01*
G03X294885Y237320I0J200D01*
G01X294886Y237321D01*
G02X296860I987J-1131D01*
G37*
G36*
G01X399222D02*
X399223Y237320D01*
G03X399353Y237272I130J152D01*
G01X399617D01*
G03X399747Y237320I0J200D01*
G01X399748Y237321D01*
G02X400735Y237691I987J-1131D01*
G02Y234687I0J-1502D01*
G02X399748Y235057I0J1501D01*
G01X399747D01*
Y235058D01*
G03X399617Y235106I-130J-152D01*
G01X399353D01*
G03X399223Y235058I0J-200D01*
G01X399222Y235057D01*
G02X397248I-987J1131D01*
G01X397247D01*
Y235058D01*
G03X397117Y235106I-130J-152D01*
G01X396853D01*
G03X396723Y235058I0J-200D01*
G01X396722Y235057D01*
G02X395735Y234687I-987J1131D01*
G02Y237691I0J1502D01*
G02X396722Y237321I0J-1501D01*
G01X396723D01*
Y237320D01*
G03X396853Y237272I130J152D01*
G01X397117D01*
G03X397247Y237320I0J200D01*
G01X397248Y237321D01*
G02X399222I987J-1131D01*
G37*
G36*
G01X549223D02*
X549224Y237320D01*
G03X549354Y237272I130J152D01*
G01X549618D01*
G03X549748Y237320I0J200D01*
G01X549749Y237321D01*
G02X550736Y237691I987J-1131D01*
G02Y234687I0J-1502D01*
G02X549749Y235057I0J1501D01*
G01X549748D01*
Y235058D01*
G03X549618Y235106I-130J-152D01*
G01X549354D01*
G03X549224Y235058I0J-200D01*
G01X549223Y235057D01*
G02X547249I-987J1131D01*
G01X547248D01*
Y235058D01*
G03X547118Y235106I-130J-152D01*
G01X546854D01*
G03X546724Y235058I0J-200D01*
G01X546723Y235057D01*
G02X545736Y234687I-987J1131D01*
G02Y237691I0J1502D01*
G02X546723Y237321I0J-1501D01*
G01X546724D01*
Y237320D01*
G03X546854Y237272I130J152D01*
G01X547118D01*
G03X547248Y237320I0J200D01*
G01X547249Y237321D01*
G02X549223I987J-1131D01*
G37*
G36*
G01X651585D02*
X651586Y237320D01*
G03X651716Y237272I130J152D01*
G01X651980D01*
G03X652110Y237320I0J200D01*
G01X652111Y237321D01*
G02X653098Y237691I987J-1131D01*
G02Y234687I0J-1502D01*
G02X652111Y235057I0J1501D01*
G01X652110D01*
Y235058D01*
G03X651980Y235106I-130J-152D01*
G01X651716D01*
G03X651586Y235058I0J-200D01*
G01X651585Y235057D01*
G02X649611I-987J1131D01*
G01X649610D01*
Y235058D01*
G03X649480Y235106I-130J-152D01*
G01X649216D01*
G03X649086Y235058I0J-200D01*
G01X649085Y235057D01*
G02X648098Y234687I-987J1131D01*
G02Y237691I0J1502D01*
G02X649085Y237321I0J-1501D01*
G01X649086D01*
Y237320D01*
G03X649216Y237272I130J152D01*
G01X649480D01*
G03X649610Y237320I0J200D01*
G01X649611Y237321D01*
G02X651585I987J-1131D01*
G37*
G36*
G01X753947D02*
X753948Y237320D01*
G03X754078Y237272I130J152D01*
G01X754342D01*
G03X754472Y237320I0J200D01*
G01X754473Y237321D01*
G02X755460Y237691I987J-1131D01*
G02Y234687I0J-1502D01*
G02X754473Y235057I0J1501D01*
G01X754472D01*
Y235058D01*
G03X754342Y235106I-130J-152D01*
G01X754078D01*
G03X753948Y235058I0J-200D01*
G01X753947Y235057D01*
G02X751973I-987J1131D01*
G01X751972D01*
Y235058D01*
G03X751842Y235106I-130J-152D01*
G01X751578D01*
G03X751448Y235058I0J-200D01*
G01X751447Y235057D01*
G02X750460Y234687I-987J1131D01*
G02Y237691I0J1502D01*
G02X751447Y237321I0J-1501D01*
G01X751448D01*
Y237320D01*
G03X751578Y237272I130J152D01*
G01X751842D01*
G03X751972Y237320I0J200D01*
G01X751973Y237321D01*
G02X753947I987J-1131D01*
G37*
G36*
G01X856309D02*
X856310Y237320D01*
G03X856440Y237272I130J152D01*
G01X856704D01*
G03X856834Y237320I0J200D01*
G01X856835Y237321D01*
G02X857822Y237691I987J-1131D01*
G02Y234687I0J-1502D01*
G02X856835Y235057I0J1501D01*
G01X856834D01*
Y235058D01*
G03X856704Y235106I-130J-152D01*
G01X856440D01*
G03X856310Y235058I0J-200D01*
G01X856309Y235057D01*
G02X854335I-987J1131D01*
G01X854334D01*
Y235058D01*
G03X854204Y235106I-130J-152D01*
G01X853940D01*
G03X853810Y235058I0J-200D01*
G01X853809Y235057D01*
G02X852822Y234687I-987J1131D01*
G02Y237691I0J1502D01*
G02X853809Y237321I0J-1501D01*
G01X853810D01*
Y237320D01*
G03X853940Y237272I130J152D01*
G01X854204D01*
G03X854334Y237320I0J200D01*
G01X854335Y237321D01*
G02X856309I987J-1131D01*
G37*
G36*
G01X1006309D02*
X1006310Y237320D01*
G03X1006440Y237272I130J152D01*
G01X1006704D01*
G03X1006834Y237320I0J200D01*
G01X1006835Y237321D01*
G02X1007822Y237691I987J-1131D01*
G02Y234687I0J-1502D01*
G02X1006835Y235057I0J1501D01*
G01X1006834D01*
Y235058D01*
G03X1006704Y235106I-130J-152D01*
G01X1006440D01*
G03X1006310Y235058I0J-200D01*
G01X1006309Y235057D01*
G02X1004335I-987J1131D01*
G01X1004334D01*
Y235058D01*
G03X1004204Y235106I-130J-152D01*
G01X1003940D01*
G03X1003810Y235058I0J-200D01*
G01X1003809Y235057D01*
G02X1002822Y234687I-987J1131D01*
G02Y237691I0J1502D01*
G02X1003809Y237321I0J-1501D01*
G01X1003810D01*
Y237320D01*
G03X1003940Y237272I130J152D01*
G01X1004204D01*
G03X1004334Y237320I0J200D01*
G01X1004335Y237321D01*
G02X1006309I987J-1131D01*
G37*
G36*
G01X1108671D02*
X1108672Y237320D01*
G03X1108802Y237272I130J152D01*
G01X1109066D01*
G03X1109196Y237320I0J200D01*
G01X1109197Y237321D01*
G02X1110184Y237691I987J-1131D01*
G02Y234687I0J-1502D01*
G02X1109197Y235057I0J1501D01*
G01X1109196D01*
Y235058D01*
G03X1109066Y235106I-130J-152D01*
G01X1108802D01*
G03X1108672Y235058I0J-200D01*
G01X1108671Y235057D01*
G02X1106697I-987J1131D01*
G01X1106696D01*
Y235058D01*
G03X1106566Y235106I-130J-152D01*
G01X1106302D01*
G03X1106172Y235058I0J-200D01*
G01X1106171Y235057D01*
G02X1105184Y234687I-987J1131D01*
G02Y237691I0J1502D01*
G02X1106171Y237321I0J-1501D01*
G01X1106172D01*
Y237320D01*
G03X1106302Y237272I130J152D01*
G01X1106566D01*
G03X1106696Y237320I0J200D01*
G01X1106697Y237321D01*
G02X1108671I987J-1131D01*
G37*
G36*
G01X1211033D02*
X1211034Y237320D01*
G03X1211164Y237272I130J152D01*
G01X1211428D01*
G03X1211558Y237320I0J200D01*
G01X1211559Y237321D01*
G02X1212546Y237691I987J-1131D01*
G02Y234687I0J-1502D01*
G02X1211559Y235057I0J1501D01*
G01X1211558D01*
Y235058D01*
G03X1211428Y235106I-130J-152D01*
G01X1211164D01*
G03X1211034Y235058I0J-200D01*
G01X1211033Y235057D01*
G02X1209059I-987J1131D01*
G01X1209058D01*
Y235058D01*
G03X1208928Y235106I-130J-152D01*
G01X1208664D01*
G03X1208534Y235058I0J-200D01*
G01X1208533Y235057D01*
G02X1207546Y234687I-987J1131D01*
G02Y237691I0J1502D01*
G02X1208533Y237321I0J-1501D01*
G01X1208534D01*
Y237320D01*
G03X1208664Y237272I130J152D01*
G01X1208928D01*
G03X1209058Y237320I0J200D01*
G01X1209059Y237321D01*
G02X1211033I987J-1131D01*
G37*
G36*
G01X1313395D02*
X1313396Y237320D01*
G03X1313526Y237272I130J152D01*
G01X1313790D01*
G03X1313920Y237320I0J200D01*
G01X1313921Y237321D01*
G02X1314908Y237691I987J-1131D01*
G02Y234687I0J-1502D01*
G02X1313921Y235057I0J1501D01*
G01X1313920D01*
Y235058D01*
G03X1313790Y235106I-130J-152D01*
G01X1313526D01*
G03X1313396Y235058I0J-200D01*
G01X1313395Y235057D01*
G02X1311421I-987J1131D01*
G01X1311420D01*
Y235058D01*
G03X1311290Y235106I-130J-152D01*
G01X1311026D01*
G03X1310896Y235058I0J-200D01*
G01X1310895Y235057D01*
G02X1309908Y234687I-987J1131D01*
G02Y237691I0J1502D01*
G02X1310895Y237321I0J-1501D01*
G01X1310896D01*
Y237320D01*
G03X1311026Y237272I130J152D01*
G01X1311290D01*
G03X1311420Y237320I0J200D01*
G01X1311421Y237321D01*
G02X1313395I987J-1131D01*
G37*
G36*
G01X1463396D02*
X1463397Y237320D01*
G03X1463527Y237272I130J152D01*
G01X1463791D01*
G03X1463921Y237320I0J200D01*
G01X1463922Y237321D01*
G02X1464909Y237691I987J-1131D01*
G02Y234687I0J-1502D01*
G02X1463922Y235057I0J1501D01*
G01X1463921D01*
Y235058D01*
G03X1463791Y235106I-130J-152D01*
G01X1463527D01*
G03X1463397Y235058I0J-200D01*
G01X1463396Y235057D01*
G02X1461422I-987J1131D01*
G01X1461421D01*
Y235058D01*
G03X1461291Y235106I-130J-152D01*
G01X1461027D01*
G03X1460897Y235058I0J-200D01*
G01X1460896Y235057D01*
G02X1459909Y234687I-987J1131D01*
G02Y237691I0J1502D01*
G02X1460896Y237321I0J-1501D01*
G01X1460897D01*
Y237320D01*
G03X1461027Y237272I130J152D01*
G01X1461291D01*
G03X1461421Y237320I0J200D01*
G01X1461422Y237321D01*
G02X1463396I987J-1131D01*
G37*
G36*
G01X1565758D02*
X1565759Y237320D01*
G03X1565889Y237272I130J152D01*
G01X1566153D01*
G03X1566283Y237320I0J200D01*
G01X1566284Y237321D01*
G02X1567271Y237691I987J-1131D01*
G02Y234687I0J-1502D01*
G02X1566284Y235057I0J1501D01*
G01X1566283D01*
Y235058D01*
G03X1566153Y235106I-130J-152D01*
G01X1565889D01*
G03X1565759Y235058I0J-200D01*
G01X1565758Y235057D01*
G02X1563784I-987J1131D01*
G01X1563783D01*
Y235058D01*
G03X1563653Y235106I-130J-152D01*
G01X1563389D01*
G03X1563259Y235058I0J-200D01*
G01X1563258Y235057D01*
G02X1562271Y234687I-987J1131D01*
G02Y237691I0J1502D01*
G02X1563258Y237321I0J-1501D01*
G01X1563259D01*
Y237320D01*
G03X1563389Y237272I130J152D01*
G01X1563653D01*
G03X1563783Y237320I0J200D01*
G01X1563784Y237321D01*
G02X1565758I987J-1131D01*
G37*
G36*
G01X1668120D02*
X1668121Y237320D01*
G03X1668251Y237272I130J152D01*
G01X1668515D01*
G03X1668645Y237320I0J200D01*
G01X1668646Y237321D01*
G02X1669633Y237691I987J-1131D01*
G02Y234687I0J-1502D01*
G02X1668646Y235057I0J1501D01*
G01X1668645D01*
Y235058D01*
G03X1668515Y235106I-130J-152D01*
G01X1668251D01*
G03X1668121Y235058I0J-200D01*
G01X1668120Y235057D01*
G02X1666146I-987J1131D01*
G01X1666145D01*
Y235058D01*
G03X1666015Y235106I-130J-152D01*
G01X1665751D01*
G03X1665621Y235058I0J-200D01*
G01X1665620Y235057D01*
G02X1664633Y234687I-987J1131D01*
G02Y237691I0J1502D01*
G02X1665620Y237321I0J-1501D01*
G01X1665621D01*
Y237320D01*
G03X1665751Y237272I130J152D01*
G01X1666015D01*
G03X1666145Y237320I0J200D01*
G01X1666146Y237321D01*
G02X1668120I987J-1131D01*
G37*
G36*
G01X1770482D02*
X1770483Y237320D01*
G03X1770613Y237272I130J152D01*
G01X1770877D01*
G03X1771007Y237320I0J200D01*
G01X1771008Y237321D01*
G02X1771995Y237691I987J-1131D01*
G02Y234687I0J-1502D01*
G02X1771008Y235057I0J1501D01*
G01X1771007D01*
Y235058D01*
G03X1770877Y235106I-130J-152D01*
G01X1770613D01*
G03X1770483Y235058I0J-200D01*
G01X1770482Y235057D01*
G02X1768508I-987J1131D01*
G01X1768507D01*
Y235058D01*
G03X1768377Y235106I-130J-152D01*
G01X1768113D01*
G03X1767983Y235058I0J-200D01*
G01X1767982Y235057D01*
G02X1766995Y234687I-987J1131D01*
G02Y237691I0J1502D01*
G02X1767982Y237321I0J-1501D01*
G01X1767983D01*
Y237320D01*
G03X1768113Y237272I130J152D01*
G01X1768377D01*
G03X1768507Y237320I0J200D01*
G01X1768508Y237321D01*
G02X1770482I987J-1131D01*
G37*
G36*
G01X92077Y249897D02*
X92078Y249896D01*
G03X92208Y249848I130J152D01*
G01X92472D01*
G03X92602Y249896I0J200D01*
G01X92603Y249897D01*
G02X93590Y250267I987J-1131D01*
G02Y247263I0J-1502D01*
G02X92603Y247633I0J1501D01*
G01X92602D01*
Y247634D01*
G03X92472Y247682I-130J-152D01*
G01X92208D01*
G03X92078Y247634I0J-200D01*
G01X92077Y247633D01*
G02X90103I-987J1131D01*
G01X90102D01*
Y247634D01*
G03X89972Y247682I-130J-152D01*
G01X89708D01*
G03X89578Y247634I0J-200D01*
G01X89577Y247633D01*
G02X88590Y247263I-987J1131D01*
G02Y250267I0J1502D01*
G02X89577Y249897I0J-1501D01*
G01X89578D01*
Y249896D01*
G03X89708Y249848I130J152D01*
G01X89972D01*
G03X90102Y249896I0J200D01*
G01X90103Y249897D01*
G02X92077I987J-1131D01*
G37*
G36*
G01X194439D02*
X194440Y249896D01*
G03X194570Y249848I130J152D01*
G01X194834D01*
G03X194964Y249896I0J200D01*
G01X194965Y249897D01*
G02X195952Y250267I987J-1131D01*
G02Y247263I0J-1502D01*
G02X194965Y247633I0J1501D01*
G01X194964D01*
Y247634D01*
G03X194834Y247682I-130J-152D01*
G01X194570D01*
G03X194440Y247634I0J-200D01*
G01X194439Y247633D01*
G02X192465I-987J1131D01*
G01X192464D01*
Y247634D01*
G03X192334Y247682I-130J-152D01*
G01X192070D01*
G03X191940Y247634I0J-200D01*
G01X191939Y247633D01*
G02X190952Y247263I-987J1131D01*
G02Y250267I0J1502D01*
G02X191939Y249897I0J-1501D01*
G01X191940D01*
Y249896D01*
G03X192070Y249848I130J152D01*
G01X192334D01*
G03X192464Y249896I0J200D01*
G01X192465Y249897D01*
G02X194439I987J-1131D01*
G37*
G36*
G01X296801D02*
X296802Y249896D01*
G03X296932Y249848I130J152D01*
G01X297196D01*
G03X297326Y249896I0J200D01*
G01X297327Y249897D01*
G02X298314Y250267I987J-1131D01*
G02Y247263I0J-1502D01*
G02X297327Y247633I0J1501D01*
G01X297326D01*
Y247634D01*
G03X297196Y247682I-130J-152D01*
G01X296932D01*
G03X296802Y247634I0J-200D01*
G01X296801Y247633D01*
G02X294827I-987J1131D01*
G01X294826D01*
Y247634D01*
G03X294696Y247682I-130J-152D01*
G01X294432D01*
G03X294302Y247634I0J-200D01*
G01X294301Y247633D01*
G02X293314Y247263I-987J1131D01*
G02Y250267I0J1502D01*
G02X294301Y249897I0J-1501D01*
G01X294302D01*
Y249896D01*
G03X294432Y249848I130J152D01*
G01X294696D01*
G03X294826Y249896I0J200D01*
G01X294827Y249897D01*
G02X296801I987J-1131D01*
G37*
G36*
G01X399163D02*
X399164Y249896D01*
G03X399294Y249848I130J152D01*
G01X399558D01*
G03X399688Y249896I0J200D01*
G01X399689Y249897D01*
G02X400676Y250267I987J-1131D01*
G02Y247263I0J-1502D01*
G02X399689Y247633I0J1501D01*
G01X399688D01*
Y247634D01*
G03X399558Y247682I-130J-152D01*
G01X399294D01*
G03X399164Y247634I0J-200D01*
G01X399163Y247633D01*
G02X397189I-987J1131D01*
G01X397188D01*
Y247634D01*
G03X397058Y247682I-130J-152D01*
G01X396794D01*
G03X396664Y247634I0J-200D01*
G01X396663Y247633D01*
G02X395676Y247263I-987J1131D01*
G02Y250267I0J1502D01*
G02X396663Y249897I0J-1501D01*
G01X396664D01*
Y249896D01*
G03X396794Y249848I130J152D01*
G01X397058D01*
G03X397188Y249896I0J200D01*
G01X397189Y249897D01*
G02X399163I987J-1131D01*
G37*
G36*
G01X549164D02*
X549165Y249896D01*
G03X549295Y249848I130J152D01*
G01X549559D01*
G03X549689Y249896I0J200D01*
G01X549690Y249897D01*
G02X550677Y250267I987J-1131D01*
G02Y247263I0J-1502D01*
G02X549690Y247633I0J1501D01*
G01X549689D01*
Y247634D01*
G03X549559Y247682I-130J-152D01*
G01X549295D01*
G03X549165Y247634I0J-200D01*
G01X549164Y247633D01*
G02X547190I-987J1131D01*
G01X547189D01*
Y247634D01*
G03X547059Y247682I-130J-152D01*
G01X546795D01*
G03X546665Y247634I0J-200D01*
G01X546664Y247633D01*
G02X545677Y247263I-987J1131D01*
G02Y250267I0J1502D01*
G02X546664Y249897I0J-1501D01*
G01X546665D01*
Y249896D01*
G03X546795Y249848I130J152D01*
G01X547059D01*
G03X547189Y249896I0J200D01*
G01X547190Y249897D01*
G02X549164I987J-1131D01*
G37*
G36*
G01X651526D02*
X651527Y249896D01*
G03X651657Y249848I130J152D01*
G01X651921D01*
G03X652051Y249896I0J200D01*
G01X652052Y249897D01*
G02X653039Y250267I987J-1131D01*
G02Y247263I0J-1502D01*
G02X652052Y247633I0J1501D01*
G01X652051D01*
Y247634D01*
G03X651921Y247682I-130J-152D01*
G01X651657D01*
G03X651527Y247634I0J-200D01*
G01X651526Y247633D01*
G02X649552I-987J1131D01*
G01X649551D01*
Y247634D01*
G03X649421Y247682I-130J-152D01*
G01X649157D01*
G03X649027Y247634I0J-200D01*
G01X649026Y247633D01*
G02X648039Y247263I-987J1131D01*
G02Y250267I0J1502D01*
G02X649026Y249897I0J-1501D01*
G01X649027D01*
Y249896D01*
G03X649157Y249848I130J152D01*
G01X649421D01*
G03X649551Y249896I0J200D01*
G01X649552Y249897D01*
G02X651526I987J-1131D01*
G37*
G36*
G01X753888D02*
X753889Y249896D01*
G03X754019Y249848I130J152D01*
G01X754283D01*
G03X754413Y249896I0J200D01*
G01X754414Y249897D01*
G02X755401Y250267I987J-1131D01*
G02Y247263I0J-1502D01*
G02X754414Y247633I0J1501D01*
G01X754413D01*
Y247634D01*
G03X754283Y247682I-130J-152D01*
G01X754019D01*
G03X753889Y247634I0J-200D01*
G01X753888Y247633D01*
G02X751914I-987J1131D01*
G01X751913D01*
Y247634D01*
G03X751783Y247682I-130J-152D01*
G01X751519D01*
G03X751389Y247634I0J-200D01*
G01X751388Y247633D01*
G02X750401Y247263I-987J1131D01*
G02Y250267I0J1502D01*
G02X751388Y249897I0J-1501D01*
G01X751389D01*
Y249896D01*
G03X751519Y249848I130J152D01*
G01X751783D01*
G03X751913Y249896I0J200D01*
G01X751914Y249897D01*
G02X753888I987J-1131D01*
G37*
G36*
G01X856250D02*
X856251Y249896D01*
G03X856381Y249848I130J152D01*
G01X856645D01*
G03X856775Y249896I0J200D01*
G01X856776Y249897D01*
G02X857763Y250267I987J-1131D01*
G02Y247263I0J-1502D01*
G02X856776Y247633I0J1501D01*
G01X856775D01*
Y247634D01*
G03X856645Y247682I-130J-152D01*
G01X856381D01*
G03X856251Y247634I0J-200D01*
G01X856250Y247633D01*
G02X854276I-987J1131D01*
G01X854275D01*
Y247634D01*
G03X854145Y247682I-130J-152D01*
G01X853881D01*
G03X853751Y247634I0J-200D01*
G01X853750Y247633D01*
G02X852763Y247263I-987J1131D01*
G02Y250267I0J1502D01*
G02X853750Y249897I0J-1501D01*
G01X853751D01*
Y249896D01*
G03X853881Y249848I130J152D01*
G01X854145D01*
G03X854275Y249896I0J200D01*
G01X854276Y249897D01*
G02X856250I987J-1131D01*
G37*
G36*
G01X1006250D02*
X1006251Y249896D01*
G03X1006381Y249848I130J152D01*
G01X1006645D01*
G03X1006775Y249896I0J200D01*
G01X1006776Y249897D01*
G02X1007763Y250267I987J-1131D01*
G02Y247263I0J-1502D01*
G02X1006776Y247633I0J1501D01*
G01X1006775D01*
Y247634D01*
G03X1006645Y247682I-130J-152D01*
G01X1006381D01*
G03X1006251Y247634I0J-200D01*
G01X1006250Y247633D01*
G02X1004276I-987J1131D01*
G01X1004275D01*
Y247634D01*
G03X1004145Y247682I-130J-152D01*
G01X1003881D01*
G03X1003751Y247634I0J-200D01*
G01X1003750Y247633D01*
G02X1002763Y247263I-987J1131D01*
G02Y250267I0J1502D01*
G02X1003750Y249897I0J-1501D01*
G01X1003751D01*
Y249896D01*
G03X1003881Y249848I130J152D01*
G01X1004145D01*
G03X1004275Y249896I0J200D01*
G01X1004276Y249897D01*
G02X1006250I987J-1131D01*
G37*
G36*
G01X1108612D02*
X1108613Y249896D01*
G03X1108743Y249848I130J152D01*
G01X1109007D01*
G03X1109137Y249896I0J200D01*
G01X1109138Y249897D01*
G02X1110125Y250267I987J-1131D01*
G02Y247263I0J-1502D01*
G02X1109138Y247633I0J1501D01*
G01X1109137D01*
Y247634D01*
G03X1109007Y247682I-130J-152D01*
G01X1108743D01*
G03X1108613Y247634I0J-200D01*
G01X1108612Y247633D01*
G02X1106638I-987J1131D01*
G01X1106637D01*
Y247634D01*
G03X1106507Y247682I-130J-152D01*
G01X1106243D01*
G03X1106113Y247634I0J-200D01*
G01X1106112Y247633D01*
G02X1105125Y247263I-987J1131D01*
G02Y250267I0J1502D01*
G02X1106112Y249897I0J-1501D01*
G01X1106113D01*
Y249896D01*
G03X1106243Y249848I130J152D01*
G01X1106507D01*
G03X1106637Y249896I0J200D01*
G01X1106638Y249897D01*
G02X1108612I987J-1131D01*
G37*
G36*
G01X1463337D02*
X1463338Y249896D01*
G03X1463468Y249848I130J152D01*
G01X1463732D01*
G03X1463862Y249896I0J200D01*
G01X1463863Y249897D01*
G02X1464850Y250267I987J-1131D01*
G02Y247263I0J-1502D01*
G02X1463863Y247633I0J1501D01*
G01X1463862D01*
Y247634D01*
G03X1463732Y247682I-130J-152D01*
G01X1463468D01*
G03X1463338Y247634I0J-200D01*
G01X1463337Y247633D01*
G02X1461363I-987J1131D01*
G01X1461362D01*
Y247634D01*
G03X1461232Y247682I-130J-152D01*
G01X1460968D01*
G03X1460838Y247634I0J-200D01*
G01X1460837Y247633D01*
G02X1459850Y247263I-987J1131D01*
G02Y250267I0J1502D01*
G02X1460837Y249897I0J-1501D01*
G01X1460838D01*
Y249896D01*
G03X1460968Y249848I130J152D01*
G01X1461232D01*
G03X1461362Y249896I0J200D01*
G01X1461363Y249897D01*
G02X1463337I987J-1131D01*
G37*
G36*
G01X1565699D02*
X1565700Y249896D01*
G03X1565830Y249848I130J152D01*
G01X1566094D01*
G03X1566224Y249896I0J200D01*
G01X1566225Y249897D01*
G02X1567212Y250267I987J-1131D01*
G02Y247263I0J-1502D01*
G02X1566225Y247633I0J1501D01*
G01X1566224D01*
Y247634D01*
G03X1566094Y247682I-130J-152D01*
G01X1565830D01*
G03X1565700Y247634I0J-200D01*
G01X1565699Y247633D01*
G02X1563725I-987J1131D01*
G01X1563724D01*
Y247634D01*
G03X1563594Y247682I-130J-152D01*
G01X1563330D01*
G03X1563200Y247634I0J-200D01*
G01X1563199Y247633D01*
G02X1562212Y247263I-987J1131D01*
G02Y250267I0J1502D01*
G02X1563199Y249897I0J-1501D01*
G01X1563200D01*
Y249896D01*
G03X1563330Y249848I130J152D01*
G01X1563594D01*
G03X1563724Y249896I0J200D01*
G01X1563725Y249897D01*
G02X1565699I987J-1131D01*
G37*
G36*
G01X1668061D02*
X1668062Y249896D01*
G03X1668192Y249848I130J152D01*
G01X1668456D01*
G03X1668586Y249896I0J200D01*
G01X1668587Y249897D01*
G02X1669574Y250267I987J-1131D01*
G02Y247263I0J-1502D01*
G02X1668587Y247633I0J1501D01*
G01X1668586D01*
Y247634D01*
G03X1668456Y247682I-130J-152D01*
G01X1668192D01*
G03X1668062Y247634I0J-200D01*
G01X1668061Y247633D01*
G02X1666087I-987J1131D01*
G01X1666086D01*
Y247634D01*
G03X1665956Y247682I-130J-152D01*
G01X1665692D01*
G03X1665562Y247634I0J-200D01*
G01X1665561Y247633D01*
G02X1664574Y247263I-987J1131D01*
G02Y250267I0J1502D01*
G02X1665561Y249897I0J-1501D01*
G01X1665562D01*
Y249896D01*
G03X1665692Y249848I130J152D01*
G01X1665956D01*
G03X1666086Y249896I0J200D01*
G01X1666087Y249897D01*
G02X1668061I987J-1131D01*
G37*
G36*
G01X1770423D02*
X1770424Y249896D01*
G03X1770554Y249848I130J152D01*
G01X1770818D01*
G03X1770948Y249896I0J200D01*
G01X1770949Y249897D01*
G02X1771936Y250267I987J-1131D01*
G02Y247263I0J-1502D01*
G02X1770949Y247633I0J1501D01*
G01X1770948D01*
Y247634D01*
G03X1770818Y247682I-130J-152D01*
G01X1770554D01*
G03X1770424Y247634I0J-200D01*
G01X1770423Y247633D01*
G02X1768449I-987J1131D01*
G01X1768448D01*
Y247634D01*
G03X1768318Y247682I-130J-152D01*
G01X1768054D01*
G03X1767924Y247634I0J-200D01*
G01X1767923Y247633D01*
G02X1766936Y247263I-987J1131D01*
G02Y250267I0J1502D01*
G02X1767923Y249897I0J-1501D01*
G01X1767924D01*
Y249896D01*
G03X1768054Y249848I130J152D01*
G01X1768318D01*
G03X1768448Y249896I0J200D01*
G01X1768449Y249897D01*
G02X1770423I987J-1131D01*
G37*
G36*
G01X970865Y262566D02*
G02Y265570I0J1502D01*
G02X971852Y265200I0J-1501D01*
G01X971853D01*
Y265199D01*
G03X971983Y265151I130J152D01*
G01X972247D01*
G03X972377Y265199I0J200D01*
G01X972378Y265200D01*
G02X973365Y265570I987J-1131D01*
G02Y262566I0J-1502D01*
G02X972378Y262936I0J1501D01*
G01X972377D01*
Y262937D01*
G03X972247Y262985I-130J-152D01*
G01X971983D01*
G03X971853Y262937I0J-200D01*
G01X971852Y262936D01*
G02X970865Y262566I-987J1131D01*
G37*
G36*
G01X58062Y262678D02*
G02Y265682I0J1502D01*
G02X59049Y265312I0J-1501D01*
G01X59050D01*
Y265311D01*
G03X59180Y265263I130J152D01*
G01X59444D01*
G03X59574Y265311I0J200D01*
G01X59575Y265312D01*
G02X60562Y265682I987J-1131D01*
G02Y262678I0J-1502D01*
G02X59575Y263048I0J1501D01*
G01X59574D01*
Y263049D01*
G03X59444Y263097I-130J-152D01*
G01X59180D01*
G03X59050Y263049I0J-200D01*
G01X59049Y263048D01*
G02X58062Y262678I-987J1131D01*
G37*
G36*
G01X160424D02*
G02Y265682I0J1502D01*
G02X161411Y265312I0J-1501D01*
G01X161412D01*
Y265311D01*
G03X161542Y265263I130J152D01*
G01X161806D01*
G03X161936Y265311I0J200D01*
G01X161937Y265312D01*
G02X162924Y265682I987J-1131D01*
G02Y262678I0J-1502D01*
G02X161937Y263048I0J1501D01*
G01X161936D01*
Y263049D01*
G03X161806Y263097I-130J-152D01*
G01X161542D01*
G03X161412Y263049I0J-200D01*
G01X161411Y263048D01*
G02X160424Y262678I-987J1131D01*
G37*
G36*
G01X262786D02*
G02Y265682I0J1502D01*
G02X263773Y265312I0J-1501D01*
G01X263774D01*
Y265311D01*
G03X263904Y265263I130J152D01*
G01X264168D01*
G03X264298Y265311I0J200D01*
G01X264299Y265312D01*
G02X265286Y265682I987J-1131D01*
G02Y262678I0J-1502D01*
G02X264299Y263048I0J1501D01*
G01X264298D01*
Y263049D01*
G03X264168Y263097I-130J-152D01*
G01X263904D01*
G03X263774Y263049I0J-200D01*
G01X263773Y263048D01*
G02X262786Y262678I-987J1131D01*
G37*
G36*
G01X365148D02*
G02Y265682I0J1502D01*
G02X366135Y265312I0J-1501D01*
G01X366136D01*
Y265311D01*
G03X366266Y265263I130J152D01*
G01X366530D01*
G03X366660Y265311I0J200D01*
G01X366661Y265312D01*
G02X367648Y265682I987J-1131D01*
G02Y262678I0J-1502D01*
G02X366661Y263048I0J1501D01*
G01X366660D01*
Y263049D01*
G03X366530Y263097I-130J-152D01*
G01X366266D01*
G03X366136Y263049I0J-200D01*
G01X366135Y263048D01*
G02X365148Y262678I-987J1131D01*
G37*
G36*
G01X515149D02*
G02Y265682I0J1502D01*
G02X516136Y265312I0J-1501D01*
G01X516137D01*
Y265311D01*
G03X516267Y265263I130J152D01*
G01X516531D01*
G03X516661Y265311I0J200D01*
G01X516662Y265312D01*
G02X517649Y265682I987J-1131D01*
G02Y262678I0J-1502D01*
G02X516662Y263048I0J1501D01*
G01X516661D01*
Y263049D01*
G03X516531Y263097I-130J-152D01*
G01X516267D01*
G03X516137Y263049I0J-200D01*
G01X516136Y263048D01*
G02X515149Y262678I-987J1131D01*
G37*
G36*
G01X617511D02*
G02Y265682I0J1502D01*
G02X618498Y265312I0J-1501D01*
G01X618499D01*
Y265311D01*
G03X618629Y265263I130J152D01*
G01X618893D01*
G03X619023Y265311I0J200D01*
G01X619024Y265312D01*
G02X620011Y265682I987J-1131D01*
G02Y262678I0J-1502D01*
G02X619024Y263048I0J1501D01*
G01X619023D01*
Y263049D01*
G03X618893Y263097I-130J-152D01*
G01X618629D01*
G03X618499Y263049I0J-200D01*
G01X618498Y263048D01*
G02X617511Y262678I-987J1131D01*
G37*
G36*
G01X719873D02*
G02Y265682I0J1502D01*
G02X720860Y265312I0J-1501D01*
G01X720861D01*
Y265311D01*
G03X720991Y265263I130J152D01*
G01X721255D01*
G03X721385Y265311I0J200D01*
G01X721386Y265312D01*
G02X722373Y265682I987J-1131D01*
G02Y262678I0J-1502D01*
G02X721386Y263048I0J1501D01*
G01X721385D01*
Y263049D01*
G03X721255Y263097I-130J-152D01*
G01X720991D01*
G03X720861Y263049I0J-200D01*
G01X720860Y263048D01*
G02X719873Y262678I-987J1131D01*
G37*
G36*
G01X822235D02*
G02Y265682I0J1502D01*
G02X823222Y265312I0J-1501D01*
G01X823223D01*
Y265311D01*
G03X823353Y265263I130J152D01*
G01X823617D01*
G03X823747Y265311I0J200D01*
G01X823748Y265312D01*
G02X824735Y265682I987J-1131D01*
G02Y262678I0J-1502D01*
G02X823748Y263048I0J1501D01*
G01X823747D01*
Y263049D01*
G03X823617Y263097I-130J-152D01*
G01X823353D01*
G03X823223Y263049I0J-200D01*
G01X823222Y263048D01*
G02X822235Y262678I-987J1131D01*
G37*
G36*
G01X1074597D02*
G02Y265682I0J1502D01*
G02X1075584Y265312I0J-1501D01*
G01X1075585D01*
Y265311D01*
G03X1075715Y265263I130J152D01*
G01X1075979D01*
G03X1076109Y265311I0J200D01*
G01X1076110Y265312D01*
G02X1077097Y265682I987J-1131D01*
G02Y262678I0J-1502D01*
G02X1076110Y263048I0J1501D01*
G01X1076109D01*
Y263049D01*
G03X1075979Y263097I-130J-152D01*
G01X1075715D01*
G03X1075585Y263049I0J-200D01*
G01X1075584Y263048D01*
G02X1074597Y262678I-987J1131D01*
G37*
G36*
G01X1279321D02*
G02Y265682I0J1502D01*
G02X1280308Y265312I0J-1501D01*
G01X1280309D01*
Y265311D01*
G03X1280439Y265263I130J152D01*
G01X1280703D01*
G03X1280833Y265311I0J200D01*
G01X1280834Y265312D01*
G02X1281821Y265682I987J-1131D01*
G02Y262678I0J-1502D01*
G02X1280834Y263048I0J1501D01*
G01X1280833D01*
Y263049D01*
G03X1280703Y263097I-130J-152D01*
G01X1280439D01*
G03X1280309Y263049I0J-200D01*
G01X1280308Y263048D01*
G02X1279321Y262678I-987J1131D01*
G37*
G36*
G01X1429322D02*
G02Y265682I0J1502D01*
G02X1430309Y265312I0J-1501D01*
G01X1430310D01*
Y265311D01*
G03X1430440Y265263I130J152D01*
G01X1430704D01*
G03X1430834Y265311I0J200D01*
G01X1430835Y265312D01*
G02X1431822Y265682I987J-1131D01*
G02Y262678I0J-1502D01*
G02X1430835Y263048I0J1501D01*
G01X1430834D01*
Y263049D01*
G03X1430704Y263097I-130J-152D01*
G01X1430440D01*
G03X1430310Y263049I0J-200D01*
G01X1430309Y263048D01*
G02X1429322Y262678I-987J1131D01*
G37*
G36*
G01X1531684D02*
G02Y265682I0J1502D01*
G02X1532671Y265312I0J-1501D01*
G01X1532672D01*
Y265311D01*
G03X1532802Y265263I130J152D01*
G01X1533066D01*
G03X1533196Y265311I0J200D01*
G01X1533197Y265312D01*
G02X1534184Y265682I987J-1131D01*
G02Y262678I0J-1502D01*
G02X1533197Y263048I0J1501D01*
G01X1533196D01*
Y263049D01*
G03X1533066Y263097I-130J-152D01*
G01X1532802D01*
G03X1532672Y263049I0J-200D01*
G01X1532671Y263048D01*
G02X1531684Y262678I-987J1131D01*
G37*
G36*
G01X1634046D02*
G02Y265682I0J1502D01*
G02X1635033Y265312I0J-1501D01*
G01X1635034D01*
Y265311D01*
G03X1635164Y265263I130J152D01*
G01X1635428D01*
G03X1635558Y265311I0J200D01*
G01X1635559Y265312D01*
G02X1636546Y265682I987J-1131D01*
G02Y262678I0J-1502D01*
G02X1635559Y263048I0J1501D01*
G01X1635558D01*
Y263049D01*
G03X1635428Y263097I-130J-152D01*
G01X1635164D01*
G03X1635034Y263049I0J-200D01*
G01X1635033Y263048D01*
G02X1634046Y262678I-987J1131D01*
G37*
G36*
G01X1736408D02*
G02Y265682I0J1502D01*
G02X1737395Y265312I0J-1501D01*
G01X1737396D01*
Y265311D01*
G03X1737526Y265263I130J152D01*
G01X1737790D01*
G03X1737920Y265311I0J200D01*
G01X1737921Y265312D01*
G02X1738908Y265682I987J-1131D01*
G02Y262678I0J-1502D01*
G02X1737921Y263048I0J1501D01*
G01X1737920D01*
Y263049D01*
G03X1737790Y263097I-130J-152D01*
G01X1737526D01*
G03X1737396Y263049I0J-200D01*
G01X1737395Y263048D01*
G02X1736408Y262678I-987J1131D01*
G37*
G36*
G01X97747Y264395D02*
G02Y267399I0J1502D01*
G02X98734Y267029I0J-1501D01*
G01X98735D01*
Y267028D01*
G03X98865Y266980I130J152D01*
G01X99129D01*
G03X99259Y267028I0J200D01*
G01X99260Y267029D01*
G02X100247Y267399I987J-1131D01*
G02Y264395I0J-1502D01*
G02X99260Y264765I0J1501D01*
G01X99259D01*
Y264766D01*
G03X99129Y264814I-130J-152D01*
G01X98865D01*
G03X98735Y264766I0J-200D01*
G01X98734Y264765D01*
G02X97747Y264395I-987J1131D01*
G37*
G36*
G01X200109D02*
G02Y267399I0J1502D01*
G02X201096Y267029I0J-1501D01*
G01X201097D01*
Y267028D01*
G03X201227Y266980I130J152D01*
G01X201491D01*
G03X201621Y267028I0J200D01*
G01X201622Y267029D01*
G02X202609Y267399I987J-1131D01*
G02Y264395I0J-1502D01*
G02X201622Y264765I0J1501D01*
G01X201621D01*
Y264766D01*
G03X201491Y264814I-130J-152D01*
G01X201227D01*
G03X201097Y264766I0J-200D01*
G01X201096Y264765D01*
G02X200109Y264395I-987J1131D01*
G37*
G36*
G01X302471D02*
G02Y267399I0J1502D01*
G02X303458Y267029I0J-1501D01*
G01X303459D01*
Y267028D01*
G03X303589Y266980I130J152D01*
G01X303853D01*
G03X303983Y267028I0J200D01*
G01X303984Y267029D01*
G02X304971Y267399I987J-1131D01*
G02Y264395I0J-1502D01*
G02X303984Y264765I0J1501D01*
G01X303983D01*
Y264766D01*
G03X303853Y264814I-130J-152D01*
G01X303589D01*
G03X303459Y264766I0J-200D01*
G01X303458Y264765D01*
G02X302471Y264395I-987J1131D01*
G37*
G36*
G01X404833D02*
G02Y267399I0J1502D01*
G02X405820Y267029I0J-1501D01*
G01X405821D01*
Y267028D01*
G03X405951Y266980I130J152D01*
G01X406215D01*
G03X406345Y267028I0J200D01*
G01X406346Y267029D01*
G02X407333Y267399I987J-1131D01*
G02Y264395I0J-1502D01*
G02X406346Y264765I0J1501D01*
G01X406345D01*
Y264766D01*
G03X406215Y264814I-130J-152D01*
G01X405951D01*
G03X405821Y264766I0J-200D01*
G01X405820Y264765D01*
G02X404833Y264395I-987J1131D01*
G37*
G36*
G01X554834D02*
G02Y267399I0J1502D01*
G02X555821Y267029I0J-1501D01*
G01X555822D01*
Y267028D01*
G03X555952Y266980I130J152D01*
G01X556216D01*
G03X556346Y267028I0J200D01*
G01X556347Y267029D01*
G02X557334Y267399I987J-1131D01*
G02Y264395I0J-1502D01*
G02X556347Y264765I0J1501D01*
G01X556346D01*
Y264766D01*
G03X556216Y264814I-130J-152D01*
G01X555952D01*
G03X555822Y264766I0J-200D01*
G01X555821Y264765D01*
G02X554834Y264395I-987J1131D01*
G37*
G36*
G01X657196D02*
G02Y267399I0J1502D01*
G02X658183Y267029I0J-1501D01*
G01X658184D01*
Y267028D01*
G03X658314Y266980I130J152D01*
G01X658578D01*
G03X658708Y267028I0J200D01*
G01X658709Y267029D01*
G02X659696Y267399I987J-1131D01*
G02Y264395I0J-1502D01*
G02X658709Y264765I0J1501D01*
G01X658708D01*
Y264766D01*
G03X658578Y264814I-130J-152D01*
G01X658314D01*
G03X658184Y264766I0J-200D01*
G01X658183Y264765D01*
G02X657196Y264395I-987J1131D01*
G37*
G36*
G01X759558D02*
G02Y267399I0J1502D01*
G02X760545Y267029I0J-1501D01*
G01X760546D01*
Y267028D01*
G03X760676Y266980I130J152D01*
G01X760940D01*
G03X761070Y267028I0J200D01*
G01X761071Y267029D01*
G02X762058Y267399I987J-1131D01*
G02Y264395I0J-1502D01*
G02X761071Y264765I0J1501D01*
G01X761070D01*
Y264766D01*
G03X760940Y264814I-130J-152D01*
G01X760676D01*
G03X760546Y264766I0J-200D01*
G01X760545Y264765D01*
G02X759558Y264395I-987J1131D01*
G37*
G36*
G01X861920D02*
G02Y267399I0J1502D01*
G02X862907Y267029I0J-1501D01*
G01X862908D01*
Y267028D01*
G03X863038Y266980I130J152D01*
G01X863302D01*
G03X863432Y267028I0J200D01*
G01X863433Y267029D01*
G02X864420Y267399I987J-1131D01*
G02Y264395I0J-1502D01*
G02X863433Y264765I0J1501D01*
G01X863432D01*
Y264766D01*
G03X863302Y264814I-130J-152D01*
G01X863038D01*
G03X862908Y264766I0J-200D01*
G01X862907Y264765D01*
G02X861920Y264395I-987J1131D01*
G37*
G36*
G01X1011920D02*
G02Y267399I0J1502D01*
G02X1012907Y267029I0J-1501D01*
G01X1012908D01*
Y267028D01*
G03X1013038Y266980I130J152D01*
G01X1013302D01*
G03X1013432Y267028I0J200D01*
G01X1013433Y267029D01*
G02X1014420Y267399I987J-1131D01*
G02Y264395I0J-1502D01*
G02X1013433Y264765I0J1501D01*
G01X1013432D01*
Y264766D01*
G03X1013302Y264814I-130J-152D01*
G01X1013038D01*
G03X1012908Y264766I0J-200D01*
G01X1012907Y264765D01*
G02X1011920Y264395I-987J1131D01*
G37*
G36*
G01X1114282D02*
G02Y267399I0J1502D01*
G02X1115269Y267029I0J-1501D01*
G01X1115270D01*
Y267028D01*
G03X1115400Y266980I130J152D01*
G01X1115664D01*
G03X1115794Y267028I0J200D01*
G01X1115795Y267029D01*
G02X1116782Y267399I987J-1131D01*
G02Y264395I0J-1502D01*
G02X1115795Y264765I0J1501D01*
G01X1115794D01*
Y264766D01*
G03X1115664Y264814I-130J-152D01*
G01X1115400D01*
G03X1115270Y264766I0J-200D01*
G01X1115269Y264765D01*
G02X1114282Y264395I-987J1131D01*
G37*
G36*
G01X1469007D02*
G02Y267399I0J1502D01*
G02X1469994Y267029I0J-1501D01*
G01X1469995D01*
Y267028D01*
G03X1470125Y266980I130J152D01*
G01X1470389D01*
G03X1470519Y267028I0J200D01*
G01X1470520Y267029D01*
G02X1471507Y267399I987J-1131D01*
G02Y264395I0J-1502D01*
G02X1470520Y264765I0J1501D01*
G01X1470519D01*
Y264766D01*
G03X1470389Y264814I-130J-152D01*
G01X1470125D01*
G03X1469995Y264766I0J-200D01*
G01X1469994Y264765D01*
G02X1469007Y264395I-987J1131D01*
G37*
G36*
G01X1571369D02*
G02Y267399I0J1502D01*
G02X1572356Y267029I0J-1501D01*
G01X1572357D01*
Y267028D01*
G03X1572487Y266980I130J152D01*
G01X1572751D01*
G03X1572881Y267028I0J200D01*
G01X1572882Y267029D01*
G02X1573869Y267399I987J-1131D01*
G02Y264395I0J-1502D01*
G02X1572882Y264765I0J1501D01*
G01X1572881D01*
Y264766D01*
G03X1572751Y264814I-130J-152D01*
G01X1572487D01*
G03X1572357Y264766I0J-200D01*
G01X1572356Y264765D01*
G02X1571369Y264395I-987J1131D01*
G37*
G36*
G01X1673731D02*
G02Y267399I0J1502D01*
G02X1674718Y267029I0J-1501D01*
G01X1674719D01*
Y267028D01*
G03X1674849Y266980I130J152D01*
G01X1675113D01*
G03X1675243Y267028I0J200D01*
G01X1675244Y267029D01*
G02X1676231Y267399I987J-1131D01*
G02Y264395I0J-1502D01*
G02X1675244Y264765I0J1501D01*
G01X1675243D01*
Y264766D01*
G03X1675113Y264814I-130J-152D01*
G01X1674849D01*
G03X1674719Y264766I0J-200D01*
G01X1674718Y264765D01*
G02X1673731Y264395I-987J1131D01*
G37*
G36*
G01X1776093D02*
G02Y267399I0J1502D01*
G02X1777080Y267029I0J-1501D01*
G01X1777081D01*
Y267028D01*
G03X1777211Y266980I130J152D01*
G01X1777475D01*
G03X1777605Y267028I0J200D01*
G01X1777606Y267029D01*
G02X1778593Y267399I987J-1131D01*
G02Y264395I0J-1502D01*
G02X1777606Y264765I0J1501D01*
G01X1777605D01*
Y264766D01*
G03X1777475Y264814I-130J-152D01*
G01X1777211D01*
G03X1777081Y264766I0J-200D01*
G01X1777080Y264765D01*
G02X1776093Y264395I-987J1131D01*
G37*
G36*
G01X68209Y270978D02*
X68503D01*
G03X68650Y271043I-1J200D01*
G02X69756Y271528I1106J-1019D01*
G02X70743Y271158I0J-1501D01*
G01X70744D01*
Y271157D01*
G03X70874Y271109I130J152D01*
G01X71138D01*
G03X71268Y271157I0J200D01*
G01X71269Y271158D01*
G02X72256Y271528I987J-1131D01*
G02X73758Y270026I0J-1502D01*
G02X73388Y269039I-1501J0D01*
G01Y269038D01*
X73387D01*
G03X73339Y268908I152J-130D01*
G01Y268644D01*
G03X73387Y268514I200J0D01*
G01X73388Y268513D01*
G02X73758Y267526I-1131J-987D01*
G02X72256Y266024I-1502J0D01*
G02X71269Y266394I0J1501D01*
G01X71268D01*
Y266395D01*
G03X71138Y266443I-130J-152D01*
G01X70874D01*
G03X70744Y266395I0J-200D01*
G01X70743Y266394D01*
G02X69756Y266024I-987J1131D01*
G02X68650Y266509I0J1504D01*
G03X68503Y266574I-148J-135D01*
G01X68209D01*
G03X68062Y266509I1J-200D01*
G02X66956Y266024I-1106J1019D01*
G02X65454Y267526I0J1502D01*
G02X65824Y268513I1501J0D01*
G01Y268514D01*
X65825D01*
G03X65873Y268644I-152J130D01*
G01Y268908D01*
G03X65825Y269038I-200J0D01*
G01X65824Y269039D01*
G02X65454Y270026I1131J987D01*
G02X66956Y271528I1502J0D01*
G02X68062Y271043I0J-1504D01*
G03X68209Y270978I148J135D01*
G37*
G36*
G01X170571D02*
X170865D01*
G03X171012Y271043I-1J200D01*
G02X172118Y271528I1106J-1019D01*
G02X173105Y271158I0J-1501D01*
G01X173106D01*
Y271157D01*
G03X173236Y271109I130J152D01*
G01X173500D01*
G03X173630Y271157I0J200D01*
G01X173631Y271158D01*
G02X174618Y271528I987J-1131D01*
G02X176120Y270026I0J-1502D01*
G02X175750Y269039I-1501J0D01*
G01Y269038D01*
X175749D01*
G03X175701Y268908I152J-130D01*
G01Y268644D01*
G03X175749Y268514I200J0D01*
G01X175750Y268513D01*
G02X176120Y267526I-1131J-987D01*
G02X174618Y266024I-1502J0D01*
G02X173631Y266394I0J1501D01*
G01X173630D01*
Y266395D01*
G03X173500Y266443I-130J-152D01*
G01X173236D01*
G03X173106Y266395I0J-200D01*
G01X173105Y266394D01*
G02X172118Y266024I-987J1131D01*
G02X171012Y266509I0J1504D01*
G03X170865Y266574I-148J-135D01*
G01X170571D01*
G03X170424Y266509I1J-200D01*
G02X169318Y266024I-1106J1019D01*
G02X167816Y267526I0J1502D01*
G02X168186Y268513I1501J0D01*
G01Y268514D01*
X168187D01*
G03X168235Y268644I-152J130D01*
G01Y268908D01*
G03X168187Y269038I-200J0D01*
G01X168186Y269039D01*
G02X167816Y270026I1131J987D01*
G02X169318Y271528I1502J0D01*
G02X170424Y271043I0J-1504D01*
G03X170571Y270978I148J135D01*
G37*
G36*
G01X272933D02*
X273227D01*
G03X273374Y271043I-1J200D01*
G02X274480Y271528I1106J-1019D01*
G02X275467Y271158I0J-1501D01*
G01X275468D01*
Y271157D01*
G03X275598Y271109I130J152D01*
G01X275862D01*
G03X275992Y271157I0J200D01*
G01X275993Y271158D01*
G02X276980Y271528I987J-1131D01*
G02X278482Y270026I0J-1502D01*
G02X278112Y269039I-1501J0D01*
G01Y269038D01*
X278111D01*
G03X278063Y268908I152J-130D01*
G01Y268644D01*
G03X278111Y268514I200J0D01*
G01X278112Y268513D01*
G02X278482Y267526I-1131J-987D01*
G02X276980Y266024I-1502J0D01*
G02X275993Y266394I0J1501D01*
G01X275992D01*
Y266395D01*
G03X275862Y266443I-130J-152D01*
G01X275598D01*
G03X275468Y266395I0J-200D01*
G01X275467Y266394D01*
G02X274480Y266024I-987J1131D01*
G02X273374Y266509I0J1504D01*
G03X273227Y266574I-148J-135D01*
G01X272933D01*
G03X272786Y266509I1J-200D01*
G02X271680Y266024I-1106J1019D01*
G02X270178Y267526I0J1502D01*
G02X270548Y268513I1501J0D01*
G01Y268514D01*
X270549D01*
G03X270597Y268644I-152J130D01*
G01Y268908D01*
G03X270549Y269038I-200J0D01*
G01X270548Y269039D01*
G02X270178Y270026I1131J987D01*
G02X271680Y271528I1502J0D01*
G02X272786Y271043I0J-1504D01*
G03X272933Y270978I148J135D01*
G37*
G36*
G01X375295D02*
X375589D01*
G03X375736Y271043I-1J200D01*
G02X376842Y271528I1106J-1019D01*
G02X377829Y271158I0J-1501D01*
G01X377830D01*
Y271157D01*
G03X377960Y271109I130J152D01*
G01X378224D01*
G03X378354Y271157I0J200D01*
G01X378355Y271158D01*
G02X379342Y271528I987J-1131D01*
G02X380844Y270026I0J-1502D01*
G02X380474Y269039I-1501J0D01*
G01Y269038D01*
X380473D01*
G03X380425Y268908I152J-130D01*
G01Y268644D01*
G03X380473Y268514I200J0D01*
G01X380474Y268513D01*
G02X380844Y267526I-1131J-987D01*
G02X379342Y266024I-1502J0D01*
G02X378355Y266394I0J1501D01*
G01X378354D01*
Y266395D01*
G03X378224Y266443I-130J-152D01*
G01X377960D01*
G03X377830Y266395I0J-200D01*
G01X377829Y266394D01*
G02X376842Y266024I-987J1131D01*
G02X375736Y266509I0J1504D01*
G03X375589Y266574I-148J-135D01*
G01X375295D01*
G03X375148Y266509I1J-200D01*
G02X374042Y266024I-1106J1019D01*
G02X372540Y267526I0J1502D01*
G02X372910Y268513I1501J0D01*
G01Y268514D01*
X372911D01*
G03X372959Y268644I-152J130D01*
G01Y268908D01*
G03X372911Y269038I-200J0D01*
G01X372910Y269039D01*
G02X372540Y270026I1131J987D01*
G02X374042Y271528I1502J0D01*
G02X375148Y271043I0J-1504D01*
G03X375295Y270978I148J135D01*
G37*
G36*
G01X525296D02*
X525590D01*
G03X525737Y271043I-1J200D01*
G02X526843Y271528I1106J-1019D01*
G02X527830Y271158I0J-1501D01*
G01X527831D01*
Y271157D01*
G03X527961Y271109I130J152D01*
G01X528225D01*
G03X528355Y271157I0J200D01*
G01X528356Y271158D01*
G02X529343Y271528I987J-1131D01*
G02X530845Y270026I0J-1502D01*
G02X530475Y269039I-1501J0D01*
G01Y269038D01*
X530474D01*
G03X530426Y268908I152J-130D01*
G01Y268644D01*
G03X530474Y268514I200J0D01*
G01X530475Y268513D01*
G02X530845Y267526I-1131J-987D01*
G02X529343Y266024I-1502J0D01*
G02X528356Y266394I0J1501D01*
G01X528355D01*
Y266395D01*
G03X528225Y266443I-130J-152D01*
G01X527961D01*
G03X527831Y266395I0J-200D01*
G01X527830Y266394D01*
G02X526843Y266024I-987J1131D01*
G02X525737Y266509I0J1504D01*
G03X525590Y266574I-148J-135D01*
G01X525296D01*
G03X525149Y266509I1J-200D01*
G02X524043Y266024I-1106J1019D01*
G02X522541Y267526I0J1502D01*
G02X522911Y268513I1501J0D01*
G01Y268514D01*
X522912D01*
G03X522960Y268644I-152J130D01*
G01Y268908D01*
G03X522912Y269038I-200J0D01*
G01X522911Y269039D01*
G02X522541Y270026I1131J987D01*
G02X524043Y271528I1502J0D01*
G02X525149Y271043I0J-1504D01*
G03X525296Y270978I148J135D01*
G37*
G36*
G01X627658D02*
X627952D01*
G03X628099Y271043I-1J200D01*
G02X629205Y271528I1106J-1019D01*
G02X630192Y271158I0J-1501D01*
G01X630193D01*
Y271157D01*
G03X630323Y271109I130J152D01*
G01X630587D01*
G03X630717Y271157I0J200D01*
G01X630718Y271158D01*
G02X631705Y271528I987J-1131D01*
G02X633207Y270026I0J-1502D01*
G02X632837Y269039I-1501J0D01*
G01Y269038D01*
X632836D01*
G03X632788Y268908I152J-130D01*
G01Y268644D01*
G03X632836Y268514I200J0D01*
G01X632837Y268513D01*
G02X633207Y267526I-1131J-987D01*
G02X631705Y266024I-1502J0D01*
G02X630718Y266394I0J1501D01*
G01X630717D01*
Y266395D01*
G03X630587Y266443I-130J-152D01*
G01X630323D01*
G03X630193Y266395I0J-200D01*
G01X630192Y266394D01*
G02X629205Y266024I-987J1131D01*
G02X628099Y266509I0J1504D01*
G03X627952Y266574I-148J-135D01*
G01X627658D01*
G03X627511Y266509I1J-200D01*
G02X626405Y266024I-1106J1019D01*
G02X624903Y267526I0J1502D01*
G02X625273Y268513I1501J0D01*
G01Y268514D01*
X625274D01*
G03X625322Y268644I-152J130D01*
G01Y268908D01*
G03X625274Y269038I-200J0D01*
G01X625273Y269039D01*
G02X624903Y270026I1131J987D01*
G02X626405Y271528I1502J0D01*
G02X627511Y271043I0J-1504D01*
G03X627658Y270978I148J135D01*
G37*
G36*
G01X730020D02*
X730314D01*
G03X730461Y271043I-1J200D01*
G02X731567Y271528I1106J-1019D01*
G02X732554Y271158I0J-1501D01*
G01X732555D01*
Y271157D01*
G03X732685Y271109I130J152D01*
G01X732949D01*
G03X733079Y271157I0J200D01*
G01X733080Y271158D01*
G02X734067Y271528I987J-1131D01*
G02X735569Y270026I0J-1502D01*
G02X735199Y269039I-1501J0D01*
G01Y269038D01*
X735198D01*
G03X735150Y268908I152J-130D01*
G01Y268644D01*
G03X735198Y268514I200J0D01*
G01X735199Y268513D01*
G02X735569Y267526I-1131J-987D01*
G02X734067Y266024I-1502J0D01*
G02X733080Y266394I0J1501D01*
G01X733079D01*
Y266395D01*
G03X732949Y266443I-130J-152D01*
G01X732685D01*
G03X732555Y266395I0J-200D01*
G01X732554Y266394D01*
G02X731567Y266024I-987J1131D01*
G02X730461Y266509I0J1504D01*
G03X730314Y266574I-148J-135D01*
G01X730020D01*
G03X729873Y266509I1J-200D01*
G02X728767Y266024I-1106J1019D01*
G02X727265Y267526I0J1502D01*
G02X727635Y268513I1501J0D01*
G01Y268514D01*
X727636D01*
G03X727684Y268644I-152J130D01*
G01Y268908D01*
G03X727636Y269038I-200J0D01*
G01X727635Y269039D01*
G02X727265Y270026I1131J987D01*
G02X728767Y271528I1502J0D01*
G02X729873Y271043I0J-1504D01*
G03X730020Y270978I148J135D01*
G37*
G36*
G01X832382D02*
X832676D01*
G03X832823Y271043I-1J200D01*
G02X833929Y271528I1106J-1019D01*
G02X834916Y271158I0J-1501D01*
G01X834917D01*
Y271157D01*
G03X835047Y271109I130J152D01*
G01X835311D01*
G03X835441Y271157I0J200D01*
G01X835442Y271158D01*
G02X836429Y271528I987J-1131D01*
G02X837931Y270026I0J-1502D01*
G02X837561Y269039I-1501J0D01*
G01Y269038D01*
X837560D01*
G03X837512Y268908I152J-130D01*
G01Y268644D01*
G03X837560Y268514I200J0D01*
G01X837561Y268513D01*
G02X837931Y267526I-1131J-987D01*
G02X836429Y266024I-1502J0D01*
G02X835442Y266394I0J1501D01*
G01X835441D01*
Y266395D01*
G03X835311Y266443I-130J-152D01*
G01X835047D01*
G03X834917Y266395I0J-200D01*
G01X834916Y266394D01*
G02X833929Y266024I-987J1131D01*
G02X832823Y266509I0J1504D01*
G03X832676Y266574I-148J-135D01*
G01X832382D01*
G03X832235Y266509I1J-200D01*
G02X831129Y266024I-1106J1019D01*
G02X829627Y267526I0J1502D01*
G02X829997Y268513I1501J0D01*
G01Y268514D01*
X829998D01*
G03X830046Y268644I-152J130D01*
G01Y268908D01*
G03X829998Y269038I-200J0D01*
G01X829997Y269039D01*
G02X829627Y270026I1131J987D01*
G02X831129Y271528I1502J0D01*
G02X832235Y271043I0J-1504D01*
G03X832382Y270978I148J135D01*
G37*
G36*
G01X982382D02*
X982676D01*
G03X982823Y271043I-1J200D01*
G02X983929Y271528I1106J-1019D01*
G02X984916Y271158I0J-1501D01*
G01X984917D01*
Y271157D01*
G03X985047Y271109I130J152D01*
G01X985311D01*
G03X985441Y271157I0J200D01*
G01X985442Y271158D01*
G02X986429Y271528I987J-1131D01*
G02X987931Y270026I0J-1502D01*
G02X987561Y269039I-1501J0D01*
G01Y269038D01*
X987560D01*
G03X987512Y268908I152J-130D01*
G01Y268644D01*
G03X987560Y268514I200J0D01*
G01X987561Y268513D01*
G02X987931Y267526I-1131J-987D01*
G02X986429Y266024I-1502J0D01*
G02X985442Y266394I0J1501D01*
G01X985441D01*
Y266395D01*
G03X985311Y266443I-130J-152D01*
G01X985047D01*
G03X984917Y266395I0J-200D01*
G01X984916Y266394D01*
G02X983929Y266024I-987J1131D01*
G02X982823Y266509I0J1504D01*
G03X982676Y266574I-148J-135D01*
G01X982382D01*
G03X982235Y266509I1J-200D01*
G02X981129Y266024I-1106J1019D01*
G02X979627Y267526I0J1502D01*
G02X979997Y268513I1501J0D01*
G01Y268514D01*
X979998D01*
G03X980046Y268644I-152J130D01*
G01Y268908D01*
G03X979998Y269038I-200J0D01*
G01X979997Y269039D01*
G02X979627Y270026I1131J987D01*
G02X981129Y271528I1502J0D01*
G02X982235Y271043I0J-1504D01*
G03X982382Y270978I148J135D01*
G37*
G36*
G01X1084744D02*
X1085038D01*
G03X1085185Y271043I-1J200D01*
G02X1086291Y271528I1106J-1019D01*
G02X1087278Y271158I0J-1501D01*
G01X1087279D01*
Y271157D01*
G03X1087409Y271109I130J152D01*
G01X1087673D01*
G03X1087803Y271157I0J200D01*
G01X1087804Y271158D01*
G02X1088791Y271528I987J-1131D01*
G02X1090293Y270026I0J-1502D01*
G02X1089923Y269039I-1501J0D01*
G01Y269038D01*
X1089922D01*
G03X1089874Y268908I152J-130D01*
G01Y268644D01*
G03X1089922Y268514I200J0D01*
G01X1089923Y268513D01*
G02X1090293Y267526I-1131J-987D01*
G02X1088791Y266024I-1502J0D01*
G02X1087804Y266394I0J1501D01*
G01X1087803D01*
Y266395D01*
G03X1087673Y266443I-130J-152D01*
G01X1087409D01*
G03X1087279Y266395I0J-200D01*
G01X1087278Y266394D01*
G02X1086291Y266024I-987J1131D01*
G02X1085185Y266509I0J1504D01*
G03X1085038Y266574I-148J-135D01*
G01X1084744D01*
G03X1084597Y266509I1J-200D01*
G02X1083491Y266024I-1106J1019D01*
G02X1081989Y267526I0J1502D01*
G02X1082359Y268513I1501J0D01*
G01Y268514D01*
X1082360D01*
G03X1082408Y268644I-152J130D01*
G01Y268908D01*
G03X1082360Y269038I-200J0D01*
G01X1082359Y269039D01*
G02X1081989Y270026I1131J987D01*
G02X1083491Y271528I1502J0D01*
G02X1084597Y271043I0J-1504D01*
G03X1084744Y270978I148J135D01*
G37*
G36*
G01X1187106D02*
X1187400D01*
G03X1187547Y271043I-1J200D01*
G02X1188653Y271528I1106J-1019D01*
G02X1189640Y271158I0J-1501D01*
G01X1189641D01*
Y271157D01*
G03X1189771Y271109I130J152D01*
G01X1190035D01*
G03X1190165Y271157I0J200D01*
G01X1190166Y271158D01*
G02X1191153Y271528I987J-1131D01*
G02X1192655Y270026I0J-1502D01*
G02X1192285Y269039I-1501J0D01*
G01Y269038D01*
X1192284D01*
G03X1192236Y268908I152J-130D01*
G01Y268644D01*
G03X1192284Y268514I200J0D01*
G01X1192285Y268513D01*
G02X1192655Y267526I-1131J-987D01*
G02X1191153Y266024I-1502J0D01*
G02X1190166Y266394I0J1501D01*
G01X1190165D01*
Y266395D01*
G03X1190035Y266443I-130J-152D01*
G01X1189771D01*
G03X1189641Y266395I0J-200D01*
G01X1189640Y266394D01*
G02X1188653Y266024I-987J1131D01*
G02X1187547Y266509I0J1504D01*
G03X1187400Y266574I-148J-135D01*
G01X1187106D01*
G03X1186959Y266509I1J-200D01*
G02X1185853Y266024I-1106J1019D01*
G02X1184351Y267526I0J1502D01*
G02X1184721Y268513I1501J0D01*
G01Y268514D01*
X1184722D01*
G03X1184770Y268644I-152J130D01*
G01Y268908D01*
G03X1184722Y269038I-200J0D01*
G01X1184721Y269039D01*
G02X1184351Y270026I1131J987D01*
G02X1185853Y271528I1502J0D01*
G02X1186959Y271043I0J-1504D01*
G03X1187106Y270978I148J135D01*
G37*
G36*
G01X1289468D02*
X1289762D01*
G03X1289909Y271043I-1J200D01*
G02X1291015Y271528I1106J-1019D01*
G02X1292002Y271158I0J-1501D01*
G01X1292003D01*
Y271157D01*
G03X1292133Y271109I130J152D01*
G01X1292397D01*
G03X1292527Y271157I0J200D01*
G01X1292528Y271158D01*
G02X1293515Y271528I987J-1131D01*
G02X1295017Y270026I0J-1502D01*
G02X1294647Y269039I-1501J0D01*
G01Y269038D01*
X1294646D01*
G03X1294598Y268908I152J-130D01*
G01Y268644D01*
G03X1294646Y268514I200J0D01*
G01X1294647Y268513D01*
G02X1295017Y267526I-1131J-987D01*
G02X1293515Y266024I-1502J0D01*
G02X1292528Y266394I0J1501D01*
G01X1292527D01*
Y266395D01*
G03X1292397Y266443I-130J-152D01*
G01X1292133D01*
G03X1292003Y266395I0J-200D01*
G01X1292002Y266394D01*
G02X1291015Y266024I-987J1131D01*
G02X1289909Y266509I0J1504D01*
G03X1289762Y266574I-148J-135D01*
G01X1289468D01*
G03X1289321Y266509I1J-200D01*
G02X1288215Y266024I-1106J1019D01*
G02X1286713Y267526I0J1502D01*
G02X1287083Y268513I1501J0D01*
G01Y268514D01*
X1287084D01*
G03X1287132Y268644I-152J130D01*
G01Y268908D01*
G03X1287084Y269038I-200J0D01*
G01X1287083Y269039D01*
G02X1286713Y270026I1131J987D01*
G02X1288215Y271528I1502J0D01*
G02X1289321Y271043I0J-1504D01*
G03X1289468Y270978I148J135D01*
G37*
G36*
G01X1439469D02*
X1439763D01*
G03X1439910Y271043I-1J200D01*
G02X1441016Y271528I1106J-1019D01*
G02X1442003Y271158I0J-1501D01*
G01X1442004D01*
Y271157D01*
G03X1442134Y271109I130J152D01*
G01X1442398D01*
G03X1442528Y271157I0J200D01*
G01X1442529Y271158D01*
G02X1443516Y271528I987J-1131D01*
G02X1445018Y270026I0J-1502D01*
G02X1444648Y269039I-1501J0D01*
G01Y269038D01*
X1444647D01*
G03X1444599Y268908I152J-130D01*
G01Y268644D01*
G03X1444647Y268514I200J0D01*
G01X1444648Y268513D01*
G02X1445018Y267526I-1131J-987D01*
G02X1443516Y266024I-1502J0D01*
G02X1442529Y266394I0J1501D01*
G01X1442528D01*
Y266395D01*
G03X1442398Y266443I-130J-152D01*
G01X1442134D01*
G03X1442004Y266395I0J-200D01*
G01X1442003Y266394D01*
G02X1441016Y266024I-987J1131D01*
G02X1439910Y266509I0J1504D01*
G03X1439763Y266574I-148J-135D01*
G01X1439469D01*
G03X1439322Y266509I1J-200D01*
G02X1438216Y266024I-1106J1019D01*
G02X1436714Y267526I0J1502D01*
G02X1437084Y268513I1501J0D01*
G01Y268514D01*
X1437085D01*
G03X1437133Y268644I-152J130D01*
G01Y268908D01*
G03X1437085Y269038I-200J0D01*
G01X1437084Y269039D01*
G02X1436714Y270026I1131J987D01*
G02X1438216Y271528I1502J0D01*
G02X1439322Y271043I0J-1504D01*
G03X1439469Y270978I148J135D01*
G37*
G36*
G01X1541831D02*
X1542125D01*
G03X1542272Y271043I-1J200D01*
G02X1543378Y271528I1106J-1019D01*
G02X1544365Y271158I0J-1501D01*
G01X1544366D01*
Y271157D01*
G03X1544496Y271109I130J152D01*
G01X1544760D01*
G03X1544890Y271157I0J200D01*
G01X1544891Y271158D01*
G02X1545878Y271528I987J-1131D01*
G02X1547380Y270026I0J-1502D01*
G02X1547010Y269039I-1501J0D01*
G01Y269038D01*
X1547009D01*
G03X1546961Y268908I152J-130D01*
G01Y268644D01*
G03X1547009Y268514I200J0D01*
G01X1547010Y268513D01*
G02X1547380Y267526I-1131J-987D01*
G02X1545878Y266024I-1502J0D01*
G02X1544891Y266394I0J1501D01*
G01X1544890D01*
Y266395D01*
G03X1544760Y266443I-130J-152D01*
G01X1544496D01*
G03X1544366Y266395I0J-200D01*
G01X1544365Y266394D01*
G02X1543378Y266024I-987J1131D01*
G02X1542272Y266509I0J1504D01*
G03X1542125Y266574I-148J-135D01*
G01X1541831D01*
G03X1541684Y266509I1J-200D01*
G02X1540578Y266024I-1106J1019D01*
G02X1539076Y267526I0J1502D01*
G02X1539446Y268513I1501J0D01*
G01Y268514D01*
X1539447D01*
G03X1539495Y268644I-152J130D01*
G01Y268908D01*
G03X1539447Y269038I-200J0D01*
G01X1539446Y269039D01*
G02X1539076Y270026I1131J987D01*
G02X1540578Y271528I1502J0D01*
G02X1541684Y271043I0J-1504D01*
G03X1541831Y270978I148J135D01*
G37*
G36*
G01X1644193D02*
X1644487D01*
G03X1644634Y271043I-1J200D01*
G02X1645740Y271528I1106J-1019D01*
G02X1646727Y271158I0J-1501D01*
G01X1646728D01*
Y271157D01*
G03X1646858Y271109I130J152D01*
G01X1647122D01*
G03X1647252Y271157I0J200D01*
G01X1647253Y271158D01*
G02X1648240Y271528I987J-1131D01*
G02X1649742Y270026I0J-1502D01*
G02X1649372Y269039I-1501J0D01*
G01Y269038D01*
X1649371D01*
G03X1649323Y268908I152J-130D01*
G01Y268644D01*
G03X1649371Y268514I200J0D01*
G01X1649372Y268513D01*
G02X1649742Y267526I-1131J-987D01*
G02X1648240Y266024I-1502J0D01*
G02X1647253Y266394I0J1501D01*
G01X1647252D01*
Y266395D01*
G03X1647122Y266443I-130J-152D01*
G01X1646858D01*
G03X1646728Y266395I0J-200D01*
G01X1646727Y266394D01*
G02X1645740Y266024I-987J1131D01*
G02X1644634Y266509I0J1504D01*
G03X1644487Y266574I-148J-135D01*
G01X1644193D01*
G03X1644046Y266509I1J-200D01*
G02X1642940Y266024I-1106J1019D01*
G02X1641438Y267526I0J1502D01*
G02X1641808Y268513I1501J0D01*
G01Y268514D01*
X1641809D01*
G03X1641857Y268644I-152J130D01*
G01Y268908D01*
G03X1641809Y269038I-200J0D01*
G01X1641808Y269039D01*
G02X1641438Y270026I1131J987D01*
G02X1642940Y271528I1502J0D01*
G02X1644046Y271043I0J-1504D01*
G03X1644193Y270978I148J135D01*
G37*
G36*
G01X1746555D02*
X1746849D01*
G03X1746996Y271043I-1J200D01*
G02X1748102Y271528I1106J-1019D01*
G02X1749089Y271158I0J-1501D01*
G01X1749090D01*
Y271157D01*
G03X1749220Y271109I130J152D01*
G01X1749484D01*
G03X1749614Y271157I0J200D01*
G01X1749615Y271158D01*
G02X1750602Y271528I987J-1131D01*
G02X1752104Y270026I0J-1502D01*
G02X1751734Y269039I-1501J0D01*
G01Y269038D01*
X1751733D01*
G03X1751685Y268908I152J-130D01*
G01Y268644D01*
G03X1751733Y268514I200J0D01*
G01X1751734Y268513D01*
G02X1752104Y267526I-1131J-987D01*
G02X1750602Y266024I-1502J0D01*
G02X1749615Y266394I0J1501D01*
G01X1749614D01*
Y266395D01*
G03X1749484Y266443I-130J-152D01*
G01X1749220D01*
G03X1749090Y266395I0J-200D01*
G01X1749089Y266394D01*
G02X1748102Y266024I-987J1131D01*
G02X1746996Y266509I0J1504D01*
G03X1746849Y266574I-148J-135D01*
G01X1746555D01*
G03X1746408Y266509I1J-200D01*
G02X1745302Y266024I-1106J1019D01*
G02X1743800Y267526I0J1502D01*
G02X1744170Y268513I1501J0D01*
G01Y268514D01*
X1744171D01*
G03X1744219Y268644I-152J130D01*
G01Y268908D01*
G03X1744171Y269038I-200J0D01*
G01X1744170Y269039D01*
G02X1743800Y270026I1131J987D01*
G02X1745302Y271528I1502J0D01*
G02X1746408Y271043I0J-1504D01*
G03X1746555Y270978I148J135D01*
G37*
G36*
G01X91287Y272197D02*
G02X92393Y271712I0J-1504D01*
G03X92540Y271647I148J135D01*
G01X92834D01*
G03X92981Y271712I-1J200D01*
G02X94087Y272197I1106J-1019D01*
G02X95589Y270695I0J-1502D01*
G02X95219Y269708I-1501J0D01*
G01Y269707D01*
X95218D01*
G03X95170Y269577I152J-130D01*
G01Y269313D01*
G03X95218Y269183I200J0D01*
G01X95219Y269182D01*
G02X95589Y268195I-1131J-987D01*
G02X94087Y266693I-1502J0D01*
G02X92981Y267178I0J1504D01*
G03X92834Y267243I-148J-135D01*
G01X92540D01*
G03X92393Y267178I1J-200D01*
G02X91287Y266693I-1106J1019D01*
G02X90300Y267063I0J1501D01*
G01X90299D01*
Y267064D01*
G03X90169Y267112I-130J-152D01*
G01X89905D01*
G03X89775Y267064I0J-200D01*
G01X89774Y267063D01*
G02X88787Y266693I-987J1131D01*
G02X87285Y268195I0J1502D01*
G02X87655Y269182I1501J0D01*
G01Y269183D01*
X87656D01*
G03X87704Y269313I-152J130D01*
G01Y269577D01*
G03X87656Y269707I-200J0D01*
G01X87655Y269708D01*
G02X87285Y270695I1131J987D01*
G02X88787Y272197I1502J0D01*
G02X89774Y271827I0J-1501D01*
G01X89775D01*
Y271826D01*
G03X89905Y271778I130J152D01*
G01X90169D01*
G03X90299Y271826I0J200D01*
G01X90300Y271827D01*
G02X91287Y272197I987J-1131D01*
G37*
G36*
G01X193649D02*
G02X194755Y271712I0J-1504D01*
G03X194902Y271647I148J135D01*
G01X195196D01*
G03X195343Y271712I-1J200D01*
G02X196449Y272197I1106J-1019D01*
G02X197951Y270695I0J-1502D01*
G02X197581Y269708I-1501J0D01*
G01Y269707D01*
X197580D01*
G03X197532Y269577I152J-130D01*
G01Y269313D01*
G03X197580Y269183I200J0D01*
G01X197581Y269182D01*
G02X197951Y268195I-1131J-987D01*
G02X196449Y266693I-1502J0D01*
G02X195343Y267178I0J1504D01*
G03X195196Y267243I-148J-135D01*
G01X194902D01*
G03X194755Y267178I1J-200D01*
G02X193649Y266693I-1106J1019D01*
G02X192662Y267063I0J1501D01*
G01X192661D01*
Y267064D01*
G03X192531Y267112I-130J-152D01*
G01X192267D01*
G03X192137Y267064I0J-200D01*
G01X192136Y267063D01*
G02X191149Y266693I-987J1131D01*
G02X189647Y268195I0J1502D01*
G02X190017Y269182I1501J0D01*
G01Y269183D01*
X190018D01*
G03X190066Y269313I-152J130D01*
G01Y269577D01*
G03X190018Y269707I-200J0D01*
G01X190017Y269708D01*
G02X189647Y270695I1131J987D01*
G02X191149Y272197I1502J0D01*
G02X192136Y271827I0J-1501D01*
G01X192137D01*
Y271826D01*
G03X192267Y271778I130J152D01*
G01X192531D01*
G03X192661Y271826I0J200D01*
G01X192662Y271827D01*
G02X193649Y272197I987J-1131D01*
G37*
G36*
G01X296011D02*
G02X297117Y271712I0J-1504D01*
G03X297264Y271647I148J135D01*
G01X297558D01*
G03X297705Y271712I-1J200D01*
G02X298811Y272197I1106J-1019D01*
G02X300313Y270695I0J-1502D01*
G02X299943Y269708I-1501J0D01*
G01Y269707D01*
X299942D01*
G03X299894Y269577I152J-130D01*
G01Y269313D01*
G03X299942Y269183I200J0D01*
G01X299943Y269182D01*
G02X300313Y268195I-1131J-987D01*
G02X298811Y266693I-1502J0D01*
G02X297705Y267178I0J1504D01*
G03X297558Y267243I-148J-135D01*
G01X297264D01*
G03X297117Y267178I1J-200D01*
G02X296011Y266693I-1106J1019D01*
G02X295024Y267063I0J1501D01*
G01X295023D01*
Y267064D01*
G03X294893Y267112I-130J-152D01*
G01X294629D01*
G03X294499Y267064I0J-200D01*
G01X294498Y267063D01*
G02X293511Y266693I-987J1131D01*
G02X292009Y268195I0J1502D01*
G02X292379Y269182I1501J0D01*
G01Y269183D01*
X292380D01*
G03X292428Y269313I-152J130D01*
G01Y269577D01*
G03X292380Y269707I-200J0D01*
G01X292379Y269708D01*
G02X292009Y270695I1131J987D01*
G02X293511Y272197I1502J0D01*
G02X294498Y271827I0J-1501D01*
G01X294499D01*
Y271826D01*
G03X294629Y271778I130J152D01*
G01X294893D01*
G03X295023Y271826I0J200D01*
G01X295024Y271827D01*
G02X296011Y272197I987J-1131D01*
G37*
G36*
G01X398373D02*
G02X399479Y271712I0J-1504D01*
G03X399626Y271647I148J135D01*
G01X399920D01*
G03X400067Y271712I-1J200D01*
G02X401173Y272197I1106J-1019D01*
G02X402675Y270695I0J-1502D01*
G02X402305Y269708I-1501J0D01*
G01Y269707D01*
X402304D01*
G03X402256Y269577I152J-130D01*
G01Y269313D01*
G03X402304Y269183I200J0D01*
G01X402305Y269182D01*
G02X402675Y268195I-1131J-987D01*
G02X401173Y266693I-1502J0D01*
G02X400067Y267178I0J1504D01*
G03X399920Y267243I-148J-135D01*
G01X399626D01*
G03X399479Y267178I1J-200D01*
G02X398373Y266693I-1106J1019D01*
G02X397386Y267063I0J1501D01*
G01X397385D01*
Y267064D01*
G03X397255Y267112I-130J-152D01*
G01X396991D01*
G03X396861Y267064I0J-200D01*
G01X396860Y267063D01*
G02X395873Y266693I-987J1131D01*
G02X394371Y268195I0J1502D01*
G02X394741Y269182I1501J0D01*
G01Y269183D01*
X394742D01*
G03X394790Y269313I-152J130D01*
G01Y269577D01*
G03X394742Y269707I-200J0D01*
G01X394741Y269708D01*
G02X394371Y270695I1131J987D01*
G02X395873Y272197I1502J0D01*
G02X396860Y271827I0J-1501D01*
G01X396861D01*
Y271826D01*
G03X396991Y271778I130J152D01*
G01X397255D01*
G03X397385Y271826I0J200D01*
G01X397386Y271827D01*
G02X398373Y272197I987J-1131D01*
G37*
G36*
G01X548374D02*
G02X549480Y271712I0J-1504D01*
G03X549627Y271647I148J135D01*
G01X549921D01*
G03X550068Y271712I-1J200D01*
G02X551174Y272197I1106J-1019D01*
G02X552676Y270695I0J-1502D01*
G02X552306Y269708I-1501J0D01*
G01Y269707D01*
X552305D01*
G03X552257Y269577I152J-130D01*
G01Y269313D01*
G03X552305Y269183I200J0D01*
G01X552306Y269182D01*
G02X552676Y268195I-1131J-987D01*
G02X551174Y266693I-1502J0D01*
G02X550068Y267178I0J1504D01*
G03X549921Y267243I-148J-135D01*
G01X549627D01*
G03X549480Y267178I1J-200D01*
G02X548374Y266693I-1106J1019D01*
G02X547387Y267063I0J1501D01*
G01X547386D01*
Y267064D01*
G03X547256Y267112I-130J-152D01*
G01X546992D01*
G03X546862Y267064I0J-200D01*
G01X546861Y267063D01*
G02X545874Y266693I-987J1131D01*
G02X544372Y268195I0J1502D01*
G02X544742Y269182I1501J0D01*
G01Y269183D01*
X544743D01*
G03X544791Y269313I-152J130D01*
G01Y269577D01*
G03X544743Y269707I-200J0D01*
G01X544742Y269708D01*
G02X544372Y270695I1131J987D01*
G02X545874Y272197I1502J0D01*
G02X546861Y271827I0J-1501D01*
G01X546862D01*
Y271826D01*
G03X546992Y271778I130J152D01*
G01X547256D01*
G03X547386Y271826I0J200D01*
G01X547387Y271827D01*
G02X548374Y272197I987J-1131D01*
G37*
G36*
G01X650736D02*
G02X651842Y271712I0J-1504D01*
G03X651989Y271647I148J135D01*
G01X652283D01*
G03X652430Y271712I-1J200D01*
G02X653536Y272197I1106J-1019D01*
G02X655038Y270695I0J-1502D01*
G02X654668Y269708I-1501J0D01*
G01Y269707D01*
X654667D01*
G03X654619Y269577I152J-130D01*
G01Y269313D01*
G03X654667Y269183I200J0D01*
G01X654668Y269182D01*
G02X655038Y268195I-1131J-987D01*
G02X653536Y266693I-1502J0D01*
G02X652430Y267178I0J1504D01*
G03X652283Y267243I-148J-135D01*
G01X651989D01*
G03X651842Y267178I1J-200D01*
G02X650736Y266693I-1106J1019D01*
G02X649749Y267063I0J1501D01*
G01X649748D01*
Y267064D01*
G03X649618Y267112I-130J-152D01*
G01X649354D01*
G03X649224Y267064I0J-200D01*
G01X649223Y267063D01*
G02X648236Y266693I-987J1131D01*
G02X646734Y268195I0J1502D01*
G02X647104Y269182I1501J0D01*
G01Y269183D01*
X647105D01*
G03X647153Y269313I-152J130D01*
G01Y269577D01*
G03X647105Y269707I-200J0D01*
G01X647104Y269708D01*
G02X646734Y270695I1131J987D01*
G02X648236Y272197I1502J0D01*
G02X649223Y271827I0J-1501D01*
G01X649224D01*
Y271826D01*
G03X649354Y271778I130J152D01*
G01X649618D01*
G03X649748Y271826I0J200D01*
G01X649749Y271827D01*
G02X650736Y272197I987J-1131D01*
G37*
G36*
G01X753098D02*
G02X754204Y271712I0J-1504D01*
G03X754351Y271647I148J135D01*
G01X754645D01*
G03X754792Y271712I-1J200D01*
G02X755898Y272197I1106J-1019D01*
G02X757400Y270695I0J-1502D01*
G02X757030Y269708I-1501J0D01*
G01Y269707D01*
X757029D01*
G03X756981Y269577I152J-130D01*
G01Y269313D01*
G03X757029Y269183I200J0D01*
G01X757030Y269182D01*
G02X757400Y268195I-1131J-987D01*
G02X755898Y266693I-1502J0D01*
G02X754792Y267178I0J1504D01*
G03X754645Y267243I-148J-135D01*
G01X754351D01*
G03X754204Y267178I1J-200D01*
G02X753098Y266693I-1106J1019D01*
G02X752111Y267063I0J1501D01*
G01X752110D01*
Y267064D01*
G03X751980Y267112I-130J-152D01*
G01X751716D01*
G03X751586Y267064I0J-200D01*
G01X751585Y267063D01*
G02X750598Y266693I-987J1131D01*
G02X749096Y268195I0J1502D01*
G02X749466Y269182I1501J0D01*
G01Y269183D01*
X749467D01*
G03X749515Y269313I-152J130D01*
G01Y269577D01*
G03X749467Y269707I-200J0D01*
G01X749466Y269708D01*
G02X749096Y270695I1131J987D01*
G02X750598Y272197I1502J0D01*
G02X751585Y271827I0J-1501D01*
G01X751586D01*
Y271826D01*
G03X751716Y271778I130J152D01*
G01X751980D01*
G03X752110Y271826I0J200D01*
G01X752111Y271827D01*
G02X753098Y272197I987J-1131D01*
G37*
G36*
G01X855460D02*
G02X856566Y271712I0J-1504D01*
G03X856713Y271647I148J135D01*
G01X857007D01*
G03X857154Y271712I-1J200D01*
G02X858260Y272197I1106J-1019D01*
G02X859762Y270695I0J-1502D01*
G02X859392Y269708I-1501J0D01*
G01Y269707D01*
X859391D01*
G03X859343Y269577I152J-130D01*
G01Y269313D01*
G03X859391Y269183I200J0D01*
G01X859392Y269182D01*
G02X859762Y268195I-1131J-987D01*
G02X858260Y266693I-1502J0D01*
G02X857154Y267178I0J1504D01*
G03X857007Y267243I-148J-135D01*
G01X856713D01*
G03X856566Y267178I1J-200D01*
G02X855460Y266693I-1106J1019D01*
G02X854473Y267063I0J1501D01*
G01X854472D01*
Y267064D01*
G03X854342Y267112I-130J-152D01*
G01X854078D01*
G03X853948Y267064I0J-200D01*
G01X853947Y267063D01*
G02X852960Y266693I-987J1131D01*
G02X851458Y268195I0J1502D01*
G02X851828Y269182I1501J0D01*
G01Y269183D01*
X851829D01*
G03X851877Y269313I-152J130D01*
G01Y269577D01*
G03X851829Y269707I-200J0D01*
G01X851828Y269708D01*
G02X851458Y270695I1131J987D01*
G02X852960Y272197I1502J0D01*
G02X853947Y271827I0J-1501D01*
G01X853948D01*
Y271826D01*
G03X854078Y271778I130J152D01*
G01X854342D01*
G03X854472Y271826I0J200D01*
G01X854473Y271827D01*
G02X855460Y272197I987J-1131D01*
G37*
G36*
G01X1005460D02*
G02X1006566Y271712I0J-1504D01*
G03X1006713Y271647I148J135D01*
G01X1007007D01*
G03X1007154Y271712I-1J200D01*
G02X1008260Y272197I1106J-1019D01*
G02X1009762Y270695I0J-1502D01*
G02X1009392Y269708I-1501J0D01*
G01Y269707D01*
X1009391D01*
G03X1009343Y269577I152J-130D01*
G01Y269313D01*
G03X1009391Y269183I200J0D01*
G01X1009392Y269182D01*
G02X1009762Y268195I-1131J-987D01*
G02X1008260Y266693I-1502J0D01*
G02X1007154Y267178I0J1504D01*
G03X1007007Y267243I-148J-135D01*
G01X1006713D01*
G03X1006566Y267178I1J-200D01*
G02X1005460Y266693I-1106J1019D01*
G02X1004473Y267063I0J1501D01*
G01X1004472D01*
Y267064D01*
G03X1004342Y267112I-130J-152D01*
G01X1004078D01*
G03X1003948Y267064I0J-200D01*
G01X1003947Y267063D01*
G02X1002960Y266693I-987J1131D01*
G02X1001458Y268195I0J1502D01*
G02X1001828Y269182I1501J0D01*
G01Y269183D01*
X1001829D01*
G03X1001877Y269313I-152J130D01*
G01Y269577D01*
G03X1001829Y269707I-200J0D01*
G01X1001828Y269708D01*
G02X1001458Y270695I1131J987D01*
G02X1002960Y272197I1502J0D01*
G02X1003947Y271827I0J-1501D01*
G01X1003948D01*
Y271826D01*
G03X1004078Y271778I130J152D01*
G01X1004342D01*
G03X1004472Y271826I0J200D01*
G01X1004473Y271827D01*
G02X1005460Y272197I987J-1131D01*
G37*
G36*
G01X1107822D02*
G02X1108928Y271712I0J-1504D01*
G03X1109075Y271647I148J135D01*
G01X1109369D01*
G03X1109516Y271712I-1J200D01*
G02X1110622Y272197I1106J-1019D01*
G02X1112124Y270695I0J-1502D01*
G02X1111754Y269708I-1501J0D01*
G01Y269707D01*
X1111753D01*
G03X1111705Y269577I152J-130D01*
G01Y269313D01*
G03X1111753Y269183I200J0D01*
G01X1111754Y269182D01*
G02X1112124Y268195I-1131J-987D01*
G02X1110622Y266693I-1502J0D01*
G02X1109516Y267178I0J1504D01*
G03X1109369Y267243I-148J-135D01*
G01X1109075D01*
G03X1108928Y267178I1J-200D01*
G02X1107822Y266693I-1106J1019D01*
G02X1106835Y267063I0J1501D01*
G01X1106834D01*
Y267064D01*
G03X1106704Y267112I-130J-152D01*
G01X1106440D01*
G03X1106310Y267064I0J-200D01*
G01X1106309Y267063D01*
G02X1105322Y266693I-987J1131D01*
G02X1103820Y268195I0J1502D01*
G02X1104190Y269182I1501J0D01*
G01Y269183D01*
X1104191D01*
G03X1104239Y269313I-152J130D01*
G01Y269577D01*
G03X1104191Y269707I-200J0D01*
G01X1104190Y269708D01*
G02X1103820Y270695I1131J987D01*
G02X1105322Y272197I1502J0D01*
G02X1106309Y271827I0J-1501D01*
G01X1106310D01*
Y271826D01*
G03X1106440Y271778I130J152D01*
G01X1106704D01*
G03X1106834Y271826I0J200D01*
G01X1106835Y271827D01*
G02X1107822Y272197I987J-1131D01*
G37*
G36*
G01X1210184D02*
G02X1211290Y271712I0J-1504D01*
G03X1211437Y271647I148J135D01*
G01X1211731D01*
G03X1211878Y271712I-1J200D01*
G02X1212984Y272197I1106J-1019D01*
G02X1214486Y270695I0J-1502D01*
G02X1214116Y269708I-1501J0D01*
G01Y269707D01*
X1214115D01*
G03X1214067Y269577I152J-130D01*
G01Y269313D01*
G03X1214115Y269183I200J0D01*
G01X1214116Y269182D01*
G02X1214486Y268195I-1131J-987D01*
G02X1212984Y266693I-1502J0D01*
G02X1211878Y267178I0J1504D01*
G03X1211731Y267243I-148J-135D01*
G01X1211437D01*
G03X1211290Y267178I1J-200D01*
G02X1210184Y266693I-1106J1019D01*
G02X1209197Y267063I0J1501D01*
G01X1209196D01*
Y267064D01*
G03X1209066Y267112I-130J-152D01*
G01X1208802D01*
G03X1208672Y267064I0J-200D01*
G01X1208671Y267063D01*
G02X1207684Y266693I-987J1131D01*
G02X1206182Y268195I0J1502D01*
G02X1206552Y269182I1501J0D01*
G01Y269183D01*
X1206553D01*
G03X1206601Y269313I-152J130D01*
G01Y269577D01*
G03X1206553Y269707I-200J0D01*
G01X1206552Y269708D01*
G02X1206182Y270695I1131J987D01*
G02X1207684Y272197I1502J0D01*
G02X1208671Y271827I0J-1501D01*
G01X1208672D01*
Y271826D01*
G03X1208802Y271778I130J152D01*
G01X1209066D01*
G03X1209196Y271826I0J200D01*
G01X1209197Y271827D01*
G02X1210184Y272197I987J-1131D01*
G37*
G36*
G01X1312546D02*
G02X1313652Y271712I0J-1504D01*
G03X1313799Y271647I148J135D01*
G01X1314093D01*
G03X1314240Y271712I-1J200D01*
G02X1315346Y272197I1106J-1019D01*
G02X1316848Y270695I0J-1502D01*
G02X1316478Y269708I-1501J0D01*
G01Y269707D01*
X1316477D01*
G03X1316429Y269577I152J-130D01*
G01Y269313D01*
G03X1316477Y269183I200J0D01*
G01X1316478Y269182D01*
G02X1316848Y268195I-1131J-987D01*
G02X1315346Y266693I-1502J0D01*
G02X1314240Y267178I0J1504D01*
G03X1314093Y267243I-148J-135D01*
G01X1313799D01*
G03X1313652Y267178I1J-200D01*
G02X1312546Y266693I-1106J1019D01*
G02X1311559Y267063I0J1501D01*
G01X1311558D01*
Y267064D01*
G03X1311428Y267112I-130J-152D01*
G01X1311164D01*
G03X1311034Y267064I0J-200D01*
G01X1311033Y267063D01*
G02X1310046Y266693I-987J1131D01*
G02X1308544Y268195I0J1502D01*
G02X1308914Y269182I1501J0D01*
G01Y269183D01*
X1308915D01*
G03X1308963Y269313I-152J130D01*
G01Y269577D01*
G03X1308915Y269707I-200J0D01*
G01X1308914Y269708D01*
G02X1308544Y270695I1131J987D01*
G02X1310046Y272197I1502J0D01*
G02X1311033Y271827I0J-1501D01*
G01X1311034D01*
Y271826D01*
G03X1311164Y271778I130J152D01*
G01X1311428D01*
G03X1311558Y271826I0J200D01*
G01X1311559Y271827D01*
G02X1312546Y272197I987J-1131D01*
G37*
G36*
G01X1462547D02*
G02X1463653Y271712I0J-1504D01*
G03X1463800Y271647I148J135D01*
G01X1464094D01*
G03X1464241Y271712I-1J200D01*
G02X1465347Y272197I1106J-1019D01*
G02X1466849Y270695I0J-1502D01*
G02X1466479Y269708I-1501J0D01*
G01Y269707D01*
X1466478D01*
G03X1466430Y269577I152J-130D01*
G01Y269313D01*
G03X1466478Y269183I200J0D01*
G01X1466479Y269182D01*
G02X1466849Y268195I-1131J-987D01*
G02X1465347Y266693I-1502J0D01*
G02X1464241Y267178I0J1504D01*
G03X1464094Y267243I-148J-135D01*
G01X1463800D01*
G03X1463653Y267178I1J-200D01*
G02X1462547Y266693I-1106J1019D01*
G02X1461560Y267063I0J1501D01*
G01X1461559D01*
Y267064D01*
G03X1461429Y267112I-130J-152D01*
G01X1461165D01*
G03X1461035Y267064I0J-200D01*
G01X1461034Y267063D01*
G02X1460047Y266693I-987J1131D01*
G02X1458545Y268195I0J1502D01*
G02X1458915Y269182I1501J0D01*
G01Y269183D01*
X1458916D01*
G03X1458964Y269313I-152J130D01*
G01Y269577D01*
G03X1458916Y269707I-200J0D01*
G01X1458915Y269708D01*
G02X1458545Y270695I1131J987D01*
G02X1460047Y272197I1502J0D01*
G02X1461034Y271827I0J-1501D01*
G01X1461035D01*
Y271826D01*
G03X1461165Y271778I130J152D01*
G01X1461429D01*
G03X1461559Y271826I0J200D01*
G01X1461560Y271827D01*
G02X1462547Y272197I987J-1131D01*
G37*
G36*
G01X1564909D02*
G02X1566015Y271712I0J-1504D01*
G03X1566162Y271647I148J135D01*
G01X1566456D01*
G03X1566603Y271712I-1J200D01*
G02X1567709Y272197I1106J-1019D01*
G02X1569211Y270695I0J-1502D01*
G02X1568841Y269708I-1501J0D01*
G01Y269707D01*
X1568840D01*
G03X1568792Y269577I152J-130D01*
G01Y269313D01*
G03X1568840Y269183I200J0D01*
G01X1568841Y269182D01*
G02X1569211Y268195I-1131J-987D01*
G02X1567709Y266693I-1502J0D01*
G02X1566603Y267178I0J1504D01*
G03X1566456Y267243I-148J-135D01*
G01X1566162D01*
G03X1566015Y267178I1J-200D01*
G02X1564909Y266693I-1106J1019D01*
G02X1563922Y267063I0J1501D01*
G01X1563921D01*
Y267064D01*
G03X1563791Y267112I-130J-152D01*
G01X1563527D01*
G03X1563397Y267064I0J-200D01*
G01X1563396Y267063D01*
G02X1562409Y266693I-987J1131D01*
G02X1560907Y268195I0J1502D01*
G02X1561277Y269182I1501J0D01*
G01Y269183D01*
X1561278D01*
G03X1561326Y269313I-152J130D01*
G01Y269577D01*
G03X1561278Y269707I-200J0D01*
G01X1561277Y269708D01*
G02X1560907Y270695I1131J987D01*
G02X1562409Y272197I1502J0D01*
G02X1563396Y271827I0J-1501D01*
G01X1563397D01*
Y271826D01*
G03X1563527Y271778I130J152D01*
G01X1563791D01*
G03X1563921Y271826I0J200D01*
G01X1563922Y271827D01*
G02X1564909Y272197I987J-1131D01*
G37*
G36*
G01X1667271D02*
G02X1668377Y271712I0J-1504D01*
G03X1668524Y271647I148J135D01*
G01X1668818D01*
G03X1668965Y271712I-1J200D01*
G02X1670071Y272197I1106J-1019D01*
G02X1671573Y270695I0J-1502D01*
G02X1671203Y269708I-1501J0D01*
G01Y269707D01*
X1671202D01*
G03X1671154Y269577I152J-130D01*
G01Y269313D01*
G03X1671202Y269183I200J0D01*
G01X1671203Y269182D01*
G02X1671573Y268195I-1131J-987D01*
G02X1670071Y266693I-1502J0D01*
G02X1668965Y267178I0J1504D01*
G03X1668818Y267243I-148J-135D01*
G01X1668524D01*
G03X1668377Y267178I1J-200D01*
G02X1667271Y266693I-1106J1019D01*
G02X1666284Y267063I0J1501D01*
G01X1666283D01*
Y267064D01*
G03X1666153Y267112I-130J-152D01*
G01X1665889D01*
G03X1665759Y267064I0J-200D01*
G01X1665758Y267063D01*
G02X1664771Y266693I-987J1131D01*
G02X1663269Y268195I0J1502D01*
G02X1663639Y269182I1501J0D01*
G01Y269183D01*
X1663640D01*
G03X1663688Y269313I-152J130D01*
G01Y269577D01*
G03X1663640Y269707I-200J0D01*
G01X1663639Y269708D01*
G02X1663269Y270695I1131J987D01*
G02X1664771Y272197I1502J0D01*
G02X1665758Y271827I0J-1501D01*
G01X1665759D01*
Y271826D01*
G03X1665889Y271778I130J152D01*
G01X1666153D01*
G03X1666283Y271826I0J200D01*
G01X1666284Y271827D01*
G02X1667271Y272197I987J-1131D01*
G37*
G36*
G01X1769633D02*
G02X1770739Y271712I0J-1504D01*
G03X1770886Y271647I148J135D01*
G01X1771180D01*
G03X1771327Y271712I-1J200D01*
G02X1772433Y272197I1106J-1019D01*
G02X1773935Y270695I0J-1502D01*
G02X1773565Y269708I-1501J0D01*
G01Y269707D01*
X1773564D01*
G03X1773516Y269577I152J-130D01*
G01Y269313D01*
G03X1773564Y269183I200J0D01*
G01X1773565Y269182D01*
G02X1773935Y268195I-1131J-987D01*
G02X1772433Y266693I-1502J0D01*
G02X1771327Y267178I0J1504D01*
G03X1771180Y267243I-148J-135D01*
G01X1770886D01*
G03X1770739Y267178I1J-200D01*
G02X1769633Y266693I-1106J1019D01*
G02X1768646Y267063I0J1501D01*
G01X1768645D01*
Y267064D01*
G03X1768515Y267112I-130J-152D01*
G01X1768251D01*
G03X1768121Y267064I0J-200D01*
G01X1768120Y267063D01*
G02X1767133Y266693I-987J1131D01*
G02X1765631Y268195I0J1502D01*
G02X1766001Y269182I1501J0D01*
G01Y269183D01*
X1766002D01*
G03X1766050Y269313I-152J130D01*
G01Y269577D01*
G03X1766002Y269707I-200J0D01*
G01X1766001Y269708D01*
G02X1765631Y270695I1131J987D01*
G02X1767133Y272197I1502J0D01*
G02X1768120Y271827I0J-1501D01*
G01X1768121D01*
Y271826D01*
G03X1768251Y271778I130J152D01*
G01X1768515D01*
G03X1768645Y271826I0J200D01*
G01X1768646Y271827D01*
G02X1769633Y272197I987J-1131D01*
G37*
G36*
G01X895451Y272012D02*
G02X898455I1502J0D01*
G01Y272011D01*
G02X898306Y271359I-1502J0D01*
G01X898288Y271321D01*
X898285Y271236D01*
X898417Y270919D01*
G03X898535Y270807I185J77D01*
G01X898536D01*
G02X899550Y269387I-487J-1420D01*
G02X896546I-1502J0D01*
G01Y269388D01*
G02X896695Y270040I1502J0D01*
G01X896713Y270078D01*
X896716Y270163D01*
X896584Y270480D01*
G03X896466Y270592I-185J-77D01*
G01X896465D01*
G02X895451Y272012I487J1420D01*
G37*
G36*
G01X1732403Y384277D02*
X1732089D01*
G03X1731931Y384200I0J-200D01*
G02X1730746Y383621I-1185J923D01*
G02Y386625I0J1502D01*
G02X1731931Y386046I0J-1502D01*
G03X1732089Y385969I158J123D01*
G01X1732403D01*
G03X1732561Y386046I0J200D01*
G02X1733746Y386625I1185J-923D01*
G02Y383621I0J-1502D01*
G02X1732561Y384200I0J1502D01*
G03X1732403Y384277I-158J-123D01*
G37*
G36*
G01X1776179Y387151D02*
G02X1779183I1502J0D01*
G02X1778813Y386164I-1501J0D01*
G01Y386163D01*
X1778812D01*
G03X1778764Y386033I152J-130D01*
G01Y385769D01*
G03X1778812Y385639I200J0D01*
G01X1778813Y385638D01*
G02Y383664I-1131J-987D01*
G01Y383663D01*
X1778812D01*
G03X1778764Y383533I152J-130D01*
G01Y383269D01*
G03X1778812Y383139I200J0D01*
G01X1778813Y383138D01*
G02X1779183Y382151I-1131J-987D01*
G02X1776179I-1502J0D01*
G02X1776549Y383138I1501J0D01*
G01Y383139D01*
X1776550D01*
G03X1776598Y383269I-152J130D01*
G01Y383533D01*
G03X1776550Y383663I-200J0D01*
G01X1776549Y383664D01*
G02Y385638I1131J987D01*
G01Y385639D01*
X1776550D01*
G03X1776598Y385769I-152J130D01*
G01Y386033D01*
G03X1776550Y386163I-200J0D01*
G01X1776549Y386164D01*
G02X1776179Y387151I1131J987D01*
G37*
G36*
G01X1771260Y386750D02*
X1770966D01*
G03X1770819Y386685I1J-200D01*
G02X1769713Y386200I-1106J1019D01*
G02Y389204I0J1502D01*
G02X1770819Y388719I0J-1504D01*
G03X1770966Y388654I148J135D01*
G01X1771260D01*
G03X1771407Y388719I-1J200D01*
G02X1772513Y389204I1106J-1019D01*
G02Y386200I0J-1502D01*
G02X1771407Y386685I0J1504D01*
G03X1771260Y386750I-148J-135D01*
G37*
G36*
G01X1761698Y388817D02*
G02X1763200Y390319I1502J0D01*
G02X1764055Y390052I0J-1502D01*
G01X1764089Y390029D01*
X1764170Y390012D01*
X1764537Y390092D01*
X1764604Y390140D01*
X1764625Y390175D01*
G02X1765913Y390904I1288J-773D01*
G02Y387900I0J-1502D01*
G02X1765058Y388167I0J1502D01*
G01X1765024Y388190D01*
X1764943Y388207D01*
X1764576Y388127D01*
X1764509Y388079D01*
X1764488Y388044D01*
G02X1764332Y387831I-1285J777D01*
G03X1764331Y387829I173J-88D01*
G03X1764283Y387699I152J-130D01*
G01Y387435D01*
G03X1764331Y387305I200J0D01*
G01X1764332Y387304D01*
G02Y385330I-1131J-987D01*
G01Y385329D01*
X1764331D01*
G03X1764283Y385199I152J-130D01*
G01Y384935D01*
G03X1764331Y384805I200J0D01*
G01X1764332Y384804D01*
G02X1764702Y383817I-1131J-987D01*
G02X1761698I-1502J0D01*
G02X1762068Y384804I1501J0D01*
G01Y384805D01*
X1762069D01*
G03X1762117Y384935I-152J130D01*
G01Y385199D01*
G03X1762069Y385329I-200J0D01*
G01X1762068Y385330D01*
G02Y387304I1131J987D01*
G01Y387305D01*
X1762069D01*
G03X1762117Y387435I-152J130D01*
G01Y387699D01*
G03X1762069Y387829I-200J0D01*
G01X1762068Y387830D01*
G02X1761698Y388817I1131J987D01*
G37*
G36*
G01X1754624Y396776D02*
G02Y399780I0J1502D01*
G02X1755611Y399410I0J-1501D01*
G01X1755612D01*
Y399409D01*
G03X1755742Y399361I130J152D01*
G01X1756006D01*
G03X1756136Y399409I0J200D01*
G01X1756137Y399410D01*
G02X1757124Y399780I987J-1131D01*
G02Y396776I0J-1502D01*
G02X1756137Y397146I0J1501D01*
G01X1756136D01*
Y397147D01*
G03X1756006Y397195I-130J-152D01*
G01X1755742D01*
G03X1755612Y397147I0J-200D01*
G01X1755611Y397146D01*
G02X1754624Y396776I-987J1131D01*
G37*
G36*
G01X1752851Y400479D02*
G02Y403483I0J1502D01*
G02X1753838Y403113I0J-1501D01*
G01X1753839D01*
Y403112D01*
G03X1753969Y403064I130J152D01*
G01X1754233D01*
G03X1754363Y403112I0J200D01*
G01X1754364Y403113D01*
G02X1755351Y403483I987J-1131D01*
G02Y400479I0J-1502D01*
G02X1754364Y400849I0J1501D01*
G01X1754363D01*
Y400850D01*
G03X1754233Y400898I-130J-152D01*
G01X1753969D01*
G03X1753839Y400850I0J-200D01*
G01X1753838Y400849D01*
G02X1752851Y400479I-987J1131D01*
G37*
G36*
G01X1801150Y409056D02*
X1801444D01*
G03X1801591Y409121I-1J200D01*
G02X1803803I1106J-1017D01*
G03X1803950Y409056I148J135D01*
G01X1804244D01*
G03X1804391Y409121I-1J200D01*
G02X1805497Y409606I1106J-1019D01*
G02Y406602I0J-1502D01*
G02X1804391Y407087I0J1504D01*
G03X1804244Y407152I-148J-135D01*
G01X1803950D01*
G03X1803803Y407087I1J-200D01*
G02X1801591I-1106J1017D01*
G03X1801444Y407152I-148J-135D01*
G01X1801150D01*
G03X1801003Y407087I1J-200D01*
G02X1799897Y406602I-1106J1019D01*
G02Y409606I0J1502D01*
G02X1801003Y409121I0J-1504D01*
G03X1801150Y409056I148J135D01*
G37*
G36*
G01X1755692Y414743D02*
X1755693Y414742D01*
G03X1755823Y414694I130J152D01*
G01X1756087D01*
G03X1756217Y414742I0J200D01*
G01X1756218Y414743D01*
G02X1757205Y415113I987J-1131D01*
G02Y412109I0J-1502D01*
G02X1756218Y412479I0J1501D01*
G01X1756217D01*
Y412480D01*
G03X1756087Y412528I-130J-152D01*
G01X1755823D01*
G03X1755693Y412480I0J-200D01*
G01X1755692Y412479D01*
G02X1753718I-987J1131D01*
G01X1753717D01*
Y412480D01*
G03X1753587Y412528I-130J-152D01*
G01X1753323D01*
G03X1753193Y412480I0J-200D01*
G01X1753192Y412479D01*
G02X1751218I-987J1131D01*
G01X1751217D01*
Y412480D01*
G03X1751087Y412528I-130J-152D01*
G01X1750823D01*
G03X1750693Y412480I0J-200D01*
G01X1750692Y412479D01*
G02X1749705Y412109I-987J1131D01*
G02Y415113I0J1502D01*
G02X1750692Y414743I0J-1501D01*
G01X1750693D01*
Y414742D01*
G03X1750823Y414694I130J152D01*
G01X1751087D01*
G03X1751217Y414742I0J200D01*
G01X1751218Y414743D01*
G02X1753192I987J-1131D01*
G01X1753193D01*
Y414742D01*
G03X1753323Y414694I130J152D01*
G01X1753587D01*
G03X1753717Y414742I0J200D01*
G01X1753718Y414743D01*
G02X1755692I987J-1131D01*
G37*
G36*
G01X1800867Y421327D02*
X1801161D01*
G03X1801308Y421392I-1J200D01*
G02X1803520I1106J-1017D01*
G03X1803667Y421327I148J135D01*
G01X1803961D01*
G03X1804108Y421392I-1J200D01*
G02X1805214Y421877I1106J-1019D01*
G02Y418873I0J-1502D01*
G02X1804108Y419358I0J1504D01*
G03X1803961Y419423I-148J-135D01*
G01X1803667D01*
G03X1803520Y419358I1J-200D01*
G02X1801308I-1106J1017D01*
G03X1801161Y419423I-148J-135D01*
G01X1800867D01*
G03X1800720Y419358I1J-200D01*
G02X1799614Y418873I-1106J1019D01*
G02Y421877I0J1502D01*
G02X1800720Y421392I0J-1504D01*
G03X1800867Y421327I148J135D01*
G37*
G36*
G01X352653Y421489D02*
G02X355657I1502J0D01*
G02X355251Y420462I-1502J0D01*
G01X355225Y420435D01*
X355197Y420364D01*
Y420014D01*
X355225Y419943D01*
X355251Y419916D01*
G02Y417862I-1096J-1027D01*
G01X355225Y417835D01*
X355197Y417764D01*
Y417414D01*
X355225Y417343D01*
X355251Y417316D01*
G02X355657Y416289I-1096J-1027D01*
G02X352653I-1502J0D01*
G02X353059Y417316I1502J0D01*
G01X353085Y417343D01*
X353113Y417414D01*
Y417764D01*
X353085Y417835D01*
X353059Y417862D01*
G02Y419916I1096J1027D01*
G01X353085Y419943D01*
X353113Y420014D01*
Y420364D01*
X353085Y420435D01*
X353059Y420462D01*
G02X352653Y421489I1096J1027D01*
G37*
G36*
G01X1723913D02*
G02X1726917I1502J0D01*
G02X1726511Y420462I-1502J0D01*
G01X1726485Y420435D01*
X1726457Y420364D01*
Y420014D01*
X1726485Y419943D01*
X1726511Y419916D01*
G02Y417862I-1096J-1027D01*
G01X1726485Y417835D01*
X1726457Y417764D01*
Y417414D01*
X1726485Y417343D01*
X1726511Y417316D01*
G02X1726917Y416289I-1096J-1027D01*
G02X1723913I-1502J0D01*
G02X1724319Y417316I1502J0D01*
G01X1724345Y417343D01*
X1724373Y417414D01*
Y417764D01*
X1724345Y417835D01*
X1724319Y417862D01*
G02Y419916I1096J1027D01*
G01X1724345Y419943D01*
X1724373Y420014D01*
Y420364D01*
X1724345Y420435D01*
X1724319Y420462D01*
G02X1723913Y421489I1096J1027D01*
G37*
G36*
G01X337570Y422088D02*
G02X340574I1502J0D01*
G02X340168Y421061I-1502J0D01*
G01X340142Y421034D01*
X340114Y420963D01*
Y420613D01*
X340142Y420542D01*
X340168Y420515D01*
G02Y418461I-1096J-1027D01*
G01X340142Y418434D01*
X340114Y418363D01*
Y418013D01*
X340142Y417942D01*
X340168Y417915D01*
G02X340574Y416888I-1096J-1027D01*
G02X337570I-1502J0D01*
G02X337976Y417915I1502J0D01*
G01X338002Y417942D01*
X338030Y418013D01*
Y418363D01*
X338002Y418434D01*
X337976Y418461D01*
G02Y420515I1096J1027D01*
G01X338002Y420542D01*
X338030Y420613D01*
Y420963D01*
X338002Y421034D01*
X337976Y421061D01*
G02X337570Y422088I1096J1027D01*
G37*
G36*
G01X1755457Y425199D02*
X1755458Y425198D01*
G03X1755588Y425150I130J152D01*
G01X1755852D01*
G03X1755982Y425198I0J200D01*
G01X1755983Y425199D01*
G02X1756970Y425569I987J-1131D01*
G02Y422565I0J-1502D01*
G02X1755983Y422935I0J1501D01*
G01X1755982D01*
Y422936D01*
G03X1755852Y422984I-130J-152D01*
G01X1755588D01*
G03X1755458Y422936I0J-200D01*
G01X1755457Y422935D01*
G02X1753483I-987J1131D01*
G01X1753482D01*
Y422936D01*
G03X1753352Y422984I-130J-152D01*
G01X1753088D01*
G03X1752958Y422936I0J-200D01*
G01X1752957Y422935D01*
G02X1750983I-987J1131D01*
G01X1750982D01*
Y422936D01*
G03X1750852Y422984I-130J-152D01*
G01X1750588D01*
G03X1750458Y422936I0J-200D01*
G01X1750457Y422935D01*
G02X1749470Y422565I-987J1131D01*
G02Y425569I0J1502D01*
G02X1750457Y425199I0J-1501D01*
G01X1750458D01*
Y425198D01*
G03X1750588Y425150I130J152D01*
G01X1750852D01*
G03X1750982Y425198I0J200D01*
G01X1750983Y425199D01*
G02X1752957I987J-1131D01*
G01X1752958D01*
Y425198D01*
G03X1753088Y425150I130J152D01*
G01X1753352D01*
G03X1753482Y425198I0J200D01*
G01X1753483Y425199D01*
G02X1755457I987J-1131D01*
G37*
G36*
G01X1727413Y426689D02*
G02X1730417I1502J0D01*
G02X1730011Y425662I-1502J0D01*
G01X1729985Y425635D01*
X1729957Y425564D01*
Y425214D01*
X1729985Y425143D01*
X1730011Y425116D01*
G02Y423062I-1096J-1027D01*
G01X1729985Y423035D01*
X1729957Y422964D01*
Y422614D01*
X1729985Y422543D01*
X1730011Y422516D01*
G02Y420462I-1096J-1027D01*
G01X1729985Y420435D01*
X1729957Y420364D01*
Y420014D01*
X1729985Y419943D01*
X1730011Y419916D01*
G02Y417862I-1096J-1027D01*
G01X1729985Y417835D01*
X1729957Y417764D01*
Y417414D01*
X1729985Y417343D01*
X1730011Y417316D01*
G02Y415262I-1096J-1027D01*
G01X1729985Y415235D01*
X1729957Y415164D01*
Y414814D01*
X1729985Y414743D01*
X1730011Y414716D01*
G02Y412662I-1096J-1027D01*
G01X1729985Y412635D01*
X1729957Y412564D01*
Y412214D01*
X1729985Y412143D01*
X1730011Y412116D01*
G02Y410062I-1096J-1027D01*
G01X1729985Y410035D01*
X1729957Y409964D01*
Y409614D01*
X1729985Y409543D01*
X1730011Y409516D01*
G02Y407462I-1096J-1027D01*
G01X1729985Y407435D01*
X1729957Y407364D01*
Y407014D01*
X1729985Y406943D01*
X1730011Y406916D01*
G02X1730417Y405889I-1096J-1027D01*
G02X1730197Y405108I-1502J2D01*
G01Y405106D01*
X1730196D01*
G03X1730173Y404958I172J-103D01*
G01X1730245Y404647D01*
X1730289Y404583D01*
X1730322Y404562D01*
G02X1731010Y403300I-813J-1262D01*
G02X1728006I-1502J0D01*
G02X1728226Y404081I1502J-2D01*
G01Y404083D01*
X1728227D01*
G03X1728250Y404231I-172J103D01*
G01X1728178Y404542D01*
X1728134Y404606D01*
X1728101Y404627D01*
G02X1727413Y405889I813J1262D01*
G02X1727819Y406916I1502J0D01*
G01X1727845Y406943D01*
X1727873Y407014D01*
Y407364D01*
X1727845Y407435D01*
X1727819Y407462D01*
G02Y409516I1096J1027D01*
G01X1727845Y409543D01*
X1727873Y409614D01*
Y409964D01*
X1727845Y410035D01*
X1727819Y410062D01*
G02Y412116I1096J1027D01*
G01X1727845Y412143D01*
X1727873Y412214D01*
Y412564D01*
X1727845Y412635D01*
X1727819Y412662D01*
G02Y414716I1096J1027D01*
G01X1727845Y414743D01*
X1727873Y414814D01*
Y415164D01*
X1727845Y415235D01*
X1727819Y415262D01*
G02Y417316I1096J1027D01*
G01X1727845Y417343D01*
X1727873Y417414D01*
Y417764D01*
X1727845Y417835D01*
X1727819Y417862D01*
G02Y419916I1096J1027D01*
G01X1727845Y419943D01*
X1727873Y420014D01*
Y420364D01*
X1727845Y420435D01*
X1727819Y420462D01*
G02Y422516I1096J1027D01*
G01X1727845Y422543D01*
X1727873Y422614D01*
Y422964D01*
X1727845Y423035D01*
X1727819Y423062D01*
G02Y425116I1096J1027D01*
G01X1727845Y425143D01*
X1727873Y425214D01*
Y425564D01*
X1727845Y425635D01*
X1727819Y425662D01*
G02X1727413Y426689I1096J1027D01*
G37*
G36*
G01X1791973Y427439D02*
G02X1794977I1502J0D01*
G02X1794607Y426452I-1501J0D01*
G01Y426451D01*
X1794606D01*
G03X1794558Y426321I152J-130D01*
G01Y426057D01*
G03X1794606Y425927I200J0D01*
G01X1794607Y425926D01*
G02X1794977Y424939I-1131J-987D01*
G02X1791973I-1502J0D01*
G02X1792343Y425926I1501J0D01*
G01Y425927D01*
X1792344D01*
G03X1792392Y426057I-152J130D01*
G01Y426321D01*
G03X1792344Y426451I-200J0D01*
G01X1792343Y426452D01*
G02X1791973Y427439I1131J987D01*
G37*
G36*
G01X1728350Y433971D02*
Y434265D01*
G03X1728285Y434412I-200J-1D01*
G02X1727800Y435518I1019J1106D01*
G02X1730804I1502J0D01*
G02X1730319Y434412I-1504J0D01*
G03X1730254Y434265I135J-148D01*
G01Y433971D01*
G03X1730319Y433824I200J1D01*
G02X1730804Y432718I-1019J-1106D01*
G02X1727800I-1502J0D01*
G02X1728285Y433824I1504J0D01*
G03X1728350Y433971I-135J148D01*
G37*
G36*
G01X290951Y440869D02*
G02X292453Y442371I1502J0D01*
G02X293559Y441886I0J-1504D01*
G03X293706Y441821I148J135D01*
G01X294000D01*
G03X294147Y441886I-1J200D01*
G02X295253Y442371I1106J-1019D01*
G02X296755Y440869I0J-1502D01*
G02X296349Y439842I-1502J0D01*
G01X296323Y439815D01*
X296295Y439744D01*
Y439394D01*
X296323Y439323D01*
X296349Y439296D01*
G02Y437242I-1096J-1027D01*
G01X296323Y437215D01*
X296295Y437144D01*
Y436794D01*
X296323Y436723D01*
X296349Y436696D01*
G02Y434642I-1096J-1027D01*
G01X296323Y434615D01*
X296295Y434544D01*
Y434194D01*
X296323Y434123D01*
X296349Y434096D01*
G02Y432042I-1096J-1027D01*
G01X296323Y432015D01*
X296295Y431944D01*
Y431594D01*
X296323Y431523D01*
X296349Y431496D01*
G02X296755Y430469I-1096J-1027D01*
G02X295253Y428967I-1502J0D01*
G02X294147Y429452I0J1504D01*
G03X294000Y429517I-148J-135D01*
G01X293706D01*
G03X293559Y429452I1J-200D01*
G02X292453Y428967I-1106J1019D01*
G02X290951Y430469I0J1502D01*
G02X291357Y431496I1502J0D01*
G01X291383Y431523D01*
X291411Y431594D01*
Y431944D01*
X291383Y432015D01*
X291357Y432042D01*
G02Y434096I1096J1027D01*
G01X291383Y434123D01*
X291411Y434194D01*
Y434544D01*
X291383Y434615D01*
X291357Y434642D01*
G02Y436696I1096J1027D01*
G01X291383Y436723D01*
X291411Y436794D01*
Y437144D01*
X291383Y437215D01*
X291357Y437242D01*
G02Y439296I1096J1027D01*
G01X291383Y439323D01*
X291411Y439394D01*
Y439744D01*
X291383Y439815D01*
X291357Y439842D01*
G02X290951Y440869I1096J1027D01*
G37*
G36*
G01X1662211D02*
G02X1663713Y442371I1502J0D01*
G02X1664819Y441886I0J-1504D01*
G03X1664966Y441821I148J135D01*
G01X1665260D01*
G03X1665407Y441886I-1J200D01*
G02X1666513Y442371I1106J-1019D01*
G02X1668015Y440869I0J-1502D01*
G02X1667609Y439842I-1502J0D01*
G01X1667583Y439815D01*
X1667555Y439744D01*
Y439394D01*
X1667583Y439323D01*
X1667609Y439296D01*
G02Y437242I-1096J-1027D01*
G01X1667583Y437215D01*
X1667555Y437144D01*
Y436794D01*
X1667583Y436723D01*
X1667609Y436696D01*
G02Y434642I-1096J-1027D01*
G01X1667583Y434615D01*
X1667555Y434544D01*
Y434194D01*
X1667583Y434123D01*
X1667609Y434096D01*
G02Y432042I-1096J-1027D01*
G01X1667583Y432015D01*
X1667555Y431944D01*
Y431594D01*
X1667583Y431523D01*
X1667609Y431496D01*
G02X1668015Y430469I-1096J-1027D01*
G02X1666513Y428967I-1502J0D01*
G02X1665407Y429452I0J1504D01*
G03X1665260Y429517I-148J-135D01*
G01X1664966D01*
G03X1664819Y429452I1J-200D01*
G02X1663713Y428967I-1106J1019D01*
G02X1662211Y430469I0J1502D01*
G02X1662617Y431496I1502J0D01*
G01X1662643Y431523D01*
X1662671Y431594D01*
Y431944D01*
X1662643Y432015D01*
X1662617Y432042D01*
G02Y434096I1096J1027D01*
G01X1662643Y434123D01*
X1662671Y434194D01*
Y434544D01*
X1662643Y434615D01*
X1662617Y434642D01*
G02Y436696I1096J1027D01*
G01X1662643Y436723D01*
X1662671Y436794D01*
Y437144D01*
X1662643Y437215D01*
X1662617Y437242D01*
G02Y439296I1096J1027D01*
G01X1662643Y439323D01*
X1662671Y439394D01*
Y439744D01*
X1662643Y439815D01*
X1662617Y439842D01*
G02X1662211Y440869I1096J1027D01*
G37*
G36*
G01X1738227Y440571D02*
Y440865D01*
G03X1738162Y441012I-200J-1D01*
G02X1737677Y442118I1019J1106D01*
G02X1740681I1502J0D01*
G02X1740196Y441012I-1504J0D01*
G03X1740131Y440865I135J-148D01*
G01Y440571D01*
G03X1740196Y440424I200J1D01*
G02X1740681Y439318I-1019J-1106D01*
G02X1737677I-1502J0D01*
G02X1738162Y440424I1504J0D01*
G03X1738227Y440571I-135J148D01*
G37*
G36*
G01X1746227D02*
Y440865D01*
G03X1746162Y441012I-200J-1D01*
G02X1745677Y442118I1019J1106D01*
G02X1748681I1502J0D01*
G02X1748196Y441012I-1504J0D01*
G03X1748131Y440865I135J-148D01*
G01Y440571D01*
G03X1748196Y440424I200J1D01*
G02X1748681Y439318I-1019J-1106D01*
G02X1745677I-1502J0D01*
G02X1746162Y440424I1504J0D01*
G03X1746227Y440571I-135J148D01*
G37*
G36*
G01X1782432Y442174D02*
Y442468D01*
G03X1782367Y442615I-200J-1D01*
G02X1781882Y443721I1019J1106D01*
G02X1783384Y445223I1502J0D01*
G02X1784490Y444738I0J-1504D01*
G03X1784637Y444673I148J135D01*
G01X1784931D01*
G03X1785078Y444738I-1J200D01*
G02X1786184Y445223I1106J-1019D01*
G02X1787686Y443721I0J-1502D01*
G02X1787201Y442615I-1504J0D01*
G03X1787136Y442468I135J-148D01*
G01Y442174D01*
G03X1787201Y442027I200J1D01*
G02Y439815I-1017J-1106D01*
G03X1787136Y439668I135J-148D01*
G01Y439374D01*
G03X1787201Y439227I200J1D01*
G02Y437015I-1017J-1106D01*
G03X1787136Y436868I135J-148D01*
G01Y436574D01*
G03X1787201Y436427I200J1D01*
G02X1787686Y435321I-1019J-1106D01*
G02X1786184Y433819I-1502J0D01*
G02X1785078Y434304I0J1504D01*
G03X1784931Y434369I-148J-135D01*
G01X1784637D01*
G03X1784490Y434304I1J-200D01*
G02X1783384Y433819I-1106J1019D01*
G02X1781882Y435321I0J1502D01*
G02X1782367Y436427I1504J0D01*
G03X1782432Y436574I-135J148D01*
G01Y436868D01*
G03X1782367Y437015I-200J-1D01*
G02Y439227I1017J1106D01*
G03X1782432Y439374I-135J148D01*
G01Y439668D01*
G03X1782367Y439815I-200J-1D01*
G02Y442027I1017J1106D01*
G03X1782432Y442174I-135J148D01*
G37*
G36*
G01X1755892Y442346D02*
Y442640D01*
G03X1755827Y442787I-200J-1D01*
G02X1755342Y443893I1019J1106D01*
G02X1758346I1502J0D01*
G02X1757861Y442787I-1504J0D01*
G03X1757796Y442640I135J-148D01*
G01Y442346D01*
G03X1757861Y442199I200J1D01*
G02Y439987I-1017J-1106D01*
G03X1757796Y439840I135J-148D01*
G01Y439546D01*
G03X1757861Y439399I200J1D01*
G02X1758346Y438293I-1019J-1106D01*
G02X1755342I-1502J0D01*
G02X1755827Y439399I1504J0D01*
G03X1755892Y439546I-135J148D01*
G01Y439840D01*
G03X1755827Y439987I-200J-1D01*
G02Y442199I1017J1106D01*
G03X1755892Y442346I-135J148D01*
G37*
G36*
G01X1765885D02*
Y442640D01*
G03X1765820Y442787I-200J-1D01*
G02X1765335Y443893I1019J1106D01*
G02X1768339I1502J0D01*
G02X1767854Y442787I-1504J0D01*
G03X1767789Y442640I135J-148D01*
G01Y442346D01*
G03X1767854Y442199I200J1D01*
G02Y439987I-1017J-1106D01*
G03X1767789Y439840I135J-148D01*
G01Y439546D01*
G03X1767854Y439399I200J1D01*
G02X1768339Y438293I-1019J-1106D01*
G02X1765335I-1502J0D01*
G02X1765820Y439399I1504J0D01*
G03X1765885Y439546I-135J148D01*
G01Y439840D01*
G03X1765820Y439987I-200J-1D01*
G02Y442199I1017J1106D01*
G03X1765885Y442346I-135J148D01*
G37*
G36*
G01X263195Y445730D02*
G03X263555Y446227I-28J399D01*
G02X263509Y446595I1456J369D01*
G02X266513I1502J0D01*
G02X265117Y445097I-1502J0D01*
G03X264757Y444600I28J-399D01*
G02X264803Y444232I-1456J-369D01*
G02X261799I-1502J0D01*
G02X263195Y445730I1502J0D01*
G37*
G36*
G01X291805Y454177D02*
G02X293307Y455679I1502J0D01*
G02X294294Y455309I0J-1501D01*
G01X294295D01*
Y455308D01*
G03X294425Y455260I130J152D01*
G01X294689D01*
G03X294819Y455308I0J200D01*
G01X294820Y455309D01*
G02X295807Y455679I987J-1131D01*
G02X297309Y454177I0J-1502D01*
G02X296939Y453190I-1501J0D01*
G01Y453189D01*
X296938D01*
G03X296890Y453059I152J-130D01*
G01Y452795D01*
G03X296938Y452665I200J0D01*
G01X296939Y452664D01*
G02X297309Y451677I-1131J-987D01*
G02X295807Y450175I-1502J0D01*
G02X294820Y450545I0J1501D01*
G01X294819D01*
Y450546D01*
G03X294689Y450594I-130J-152D01*
G01X294425D01*
G03X294295Y450546I0J-200D01*
G01X294294Y450545D01*
G02X293307Y450175I-987J1131D01*
G02X291805Y451677I0J1502D01*
G02X292175Y452664I1501J0D01*
G01Y452665D01*
X292176D01*
G03X292224Y452795I-152J130D01*
G01Y453059D01*
G03X292176Y453189I-200J0D01*
G01X292175Y453190D01*
G02X291805Y454177I1131J987D01*
G37*
G36*
G01X1663065D02*
G02X1664567Y455679I1502J0D01*
G02X1665554Y455309I0J-1501D01*
G01X1665555D01*
Y455308D01*
G03X1665685Y455260I130J152D01*
G01X1665949D01*
G03X1666079Y455308I0J200D01*
G01X1666080Y455309D01*
G02X1667067Y455679I987J-1131D01*
G02X1668569Y454177I0J-1502D01*
G02X1668199Y453190I-1501J0D01*
G01Y453189D01*
X1668198D01*
G03X1668150Y453059I152J-130D01*
G01Y452795D01*
G03X1668198Y452665I200J0D01*
G01X1668199Y452664D01*
G02X1668569Y451677I-1131J-987D01*
G02X1667067Y450175I-1502J0D01*
G02X1666080Y450545I0J1501D01*
G01X1666079D01*
Y450546D01*
G03X1665949Y450594I-130J-152D01*
G01X1665685D01*
G03X1665555Y450546I0J-200D01*
G01X1665554Y450545D01*
G02X1664567Y450175I-987J1131D01*
G02X1663065Y451677I0J1502D01*
G02X1663435Y452664I1501J0D01*
G01Y452665D01*
X1663436D01*
G03X1663484Y452795I-152J130D01*
G01Y453059D01*
G03X1663436Y453189I-200J0D01*
G01X1663435Y453190D01*
G02X1663065Y454177I1131J987D01*
G37*
G36*
G01X146923Y457759D02*
X146629D01*
G03X146482Y457694I1J-200D01*
G02X145376Y457209I-1106J1019D01*
G02Y460213I0J1502D01*
G02X146482Y459728I0J-1504D01*
G03X146629Y459663I148J135D01*
G01X146923D01*
G03X147070Y459728I-1J200D01*
G02X148176Y460213I1106J-1019D01*
G02X149678Y458711I0J-1502D01*
G02X149418Y457867I-1502J1D01*
G01Y457866D01*
X149393Y457830D01*
X149379Y457746D01*
X149483Y457365D01*
X149539Y457299D01*
X149579Y457280D01*
G02X150442Y455921I-639J-1359D01*
G01Y455918D01*
G02X150418Y455652I-1502J1D01*
G01X150410Y455610D01*
X150431Y455527D01*
X150670Y455224D01*
X150746Y455184D01*
X150789Y455182D01*
G02X152205Y453682I-86J-1500D01*
G02X149201I-1502J0D01*
G01Y453685D01*
G02X149225Y453951I1502J-1D01*
G01X149233Y453993D01*
X149212Y454076D01*
X148973Y454379D01*
X148897Y454419D01*
X148854Y454421D01*
G02X147438Y455921I86J1500D01*
G02X147698Y456765I1502J-1D01*
G01Y456766D01*
X147723Y456802D01*
X147737Y456886D01*
X147633Y457267D01*
X147577Y457333D01*
X147537Y457352D01*
G02X147070Y457694I637J1360D01*
G03X146923Y457759I-148J-135D01*
G37*
G36*
G01X1731671Y461214D02*
X1731357D01*
G03X1731199Y461137I0J-200D01*
G02X1730014Y460558I-1185J923D01*
G02Y463562I0J1502D01*
G02X1731199Y462983I0J-1502D01*
G03X1731357Y462906I158J123D01*
G01X1731671D01*
G03X1731829Y462983I0J200D01*
G02X1733014Y463562I1185J-923D01*
G02Y460558I0J-1502D01*
G02X1731829Y461137I0J1502D01*
G03X1731671Y461214I-158J-123D01*
G37*
G36*
G01X69628Y464652D02*
G02X71130Y466154I1502J0D01*
G02X72117Y465784I0J-1501D01*
G01X72118D01*
Y465783D01*
G03X72248Y465735I130J152D01*
G01X72512D01*
G03X72642Y465783I0J200D01*
G01X72643Y465784D01*
G02X73630Y466154I987J-1131D01*
G02X75132Y464652I0J-1502D01*
G02X74762Y463665I-1501J0D01*
G01Y463664D01*
X74761D01*
G03X74713Y463534I152J-130D01*
G01Y463270D01*
G03X74761Y463140I200J0D01*
G01X74762Y463139D01*
G02Y461165I-1131J-987D01*
G01Y461164D01*
X74761D01*
G03X74713Y461034I152J-130D01*
G01Y460770D01*
G03X74761Y460640I200J0D01*
G01X74762Y460639D01*
G02X75132Y459652I-1131J-987D01*
G02X73630Y458150I-1502J0D01*
G02X72643Y458520I0J1501D01*
G01X72642D01*
Y458521D01*
G03X72512Y458569I-130J-152D01*
G01X72248D01*
G03X72118Y458521I0J-200D01*
G01X72117Y458520D01*
G02X71130Y458150I-987J1131D01*
G02X69628Y459652I0J1502D01*
G02X69998Y460639I1501J0D01*
G01Y460640D01*
X69999D01*
G03X70047Y460770I-152J130D01*
G01Y461034D01*
G03X69999Y461164I-200J0D01*
G01X69998Y461165D01*
G02Y463139I1131J987D01*
G01Y463140D01*
X69999D01*
G03X70047Y463270I-152J130D01*
G01Y463534D01*
G03X69999Y463664I-200J0D01*
G01X69998Y463665D01*
G02X69628Y464652I1131J987D01*
G37*
G36*
G01X1744806Y468499D02*
G02Y471503I0J1502D01*
G02X1745793Y471133I0J-1501D01*
G01X1745794D01*
Y471132D01*
G03X1745924Y471084I130J152D01*
G01X1746188D01*
G03X1746318Y471132I0J200D01*
G01X1746319Y471133D01*
G02X1747306Y471503I987J-1131D01*
G02Y468499I0J-1502D01*
G02X1746319Y468869I0J1501D01*
G01X1746318D01*
Y468870D01*
G03X1746188Y468918I-130J-152D01*
G01X1745924D01*
G03X1745794Y468870I0J-200D01*
G01X1745793Y468869D01*
G02X1744806Y468499I-987J1131D01*
G37*
G36*
G01X1729002Y475551D02*
G02Y478555I0J1502D01*
G02X1729989Y478185I0J-1501D01*
G01X1729990D01*
Y478184D01*
G03X1730120Y478136I130J152D01*
G01X1730384D01*
G03X1730514Y478184I0J200D01*
G01X1730515Y478185D01*
G02X1731502Y478555I987J-1131D01*
G02Y475551I0J-1502D01*
G02X1730515Y475921I0J1501D01*
G01X1730514D01*
Y475922D01*
G03X1730384Y475970I-130J-152D01*
G01X1730120D01*
G03X1729990Y475922I0J-200D01*
G01X1729989Y475921D01*
G02X1729002Y475551I-987J1131D01*
G37*
G36*
G01X54172Y477078D02*
Y477372D01*
G03X54107Y477519I-200J-1D01*
G02X53622Y478625I1019J1106D01*
G02X56626I1502J0D01*
G02X56141Y477519I-1504J0D01*
G03X56076Y477372I135J-148D01*
G01Y477078D01*
G03X56141Y476931I200J1D01*
G02X56626Y475825I-1019J-1106D01*
G02X53622I-1502J0D01*
G02X54107Y476931I1504J0D01*
G03X54172Y477078I-135J148D01*
G37*
G36*
G01X1733450Y479217D02*
G02X1734952Y480719I1502J0D01*
G02X1735827Y480438I0J-1503D01*
G01X1735860Y480414D01*
X1735939Y480396D01*
X1736263Y480456D01*
G03X1736394Y480542I-35J197D01*
G02X1737646Y481215I1252J-828D01*
G02X1739148Y479713I0J-1502D01*
G02X1738778Y478726I-1501J0D01*
G01Y478725D01*
X1738777D01*
G03X1738729Y478595I152J-130D01*
G01Y478331D01*
G03X1738777Y478201I200J0D01*
G01X1738778Y478200D01*
G02X1739148Y477213I-1131J-987D01*
G02X1737646Y475711I-1502J0D01*
G02X1736771Y475992I0J1503D01*
G01X1736738Y476016D01*
X1736659Y476034D01*
X1736335Y475974D01*
G03X1736204Y475888I35J-197D01*
G02X1734952Y475215I-1252J828D01*
G02X1733450Y476717I0J1502D01*
G02X1733820Y477704I1501J0D01*
G01Y477705D01*
X1733821D01*
G03X1733869Y477835I-152J130D01*
G01Y478099D01*
G03X1733821Y478229I-200J0D01*
G01X1733820Y478230D01*
G02X1733450Y479217I1131J987D01*
G37*
G36*
G01X352168Y481071D02*
G02X355172I1502J0D01*
G02X354802Y480084I-1501J0D01*
G01Y480083D01*
X354801D01*
G03X354753Y479953I152J-130D01*
G01Y479689D01*
G03X354801Y479559I200J0D01*
G01X354802Y479558D01*
G02Y477584I-1131J-987D01*
G01Y477583D01*
X354801D01*
G03X354753Y477453I152J-130D01*
G01Y477189D01*
G03X354801Y477059I200J0D01*
G01X354802Y477058D01*
G02Y475084I-1131J-987D01*
G01Y475083D01*
X354801D01*
G03X354753Y474953I152J-130D01*
G01Y474689D01*
G03X354801Y474559I200J0D01*
G01X354802Y474558D01*
G02X355172Y473571I-1131J-987D01*
G02X352168I-1502J0D01*
G02X352538Y474558I1501J0D01*
G01Y474559D01*
X352539D01*
G03X352587Y474689I-152J130D01*
G01Y474953D01*
G03X352539Y475083I-200J0D01*
G01X352538Y475084D01*
G02Y477058I1131J987D01*
G01Y477059D01*
X352539D01*
G03X352587Y477189I-152J130D01*
G01Y477453D01*
G03X352539Y477583I-200J0D01*
G01X352538Y477584D01*
G02Y479558I1131J987D01*
G01Y479559D01*
X352539D01*
G03X352587Y479689I-152J130D01*
G01Y479953D01*
G03X352539Y480083I-200J0D01*
G01X352538Y480084D01*
G02X352168Y481071I1131J987D01*
G37*
G36*
G01X1723428D02*
G02X1726432I1502J0D01*
G02X1726062Y480084I-1501J0D01*
G01Y480083D01*
X1726061D01*
G03X1726013Y479953I152J-130D01*
G01Y479689D01*
G03X1726061Y479559I200J0D01*
G01X1726062Y479558D01*
G02Y477584I-1131J-987D01*
G01Y477583D01*
X1726061D01*
G03X1726013Y477453I152J-130D01*
G01Y477189D01*
G03X1726061Y477059I200J0D01*
G01X1726062Y477058D01*
G02Y475084I-1131J-987D01*
G01Y475083D01*
X1726061D01*
G03X1726013Y474953I152J-130D01*
G01Y474689D01*
G03X1726061Y474559I200J0D01*
G01X1726062Y474558D01*
G02X1726432Y473571I-1131J-987D01*
G02X1723428I-1502J0D01*
G02X1723798Y474558I1501J0D01*
G01Y474559D01*
X1723799D01*
G03X1723847Y474689I-152J130D01*
G01Y474953D01*
G03X1723799Y475083I-200J0D01*
G01X1723798Y475084D01*
G02Y477058I1131J987D01*
G01Y477059D01*
X1723799D01*
G03X1723847Y477189I-152J130D01*
G01Y477453D01*
G03X1723799Y477583I-200J0D01*
G01X1723798Y477584D01*
G02Y479558I1131J987D01*
G01Y479559D01*
X1723799D01*
G03X1723847Y479689I-152J130D01*
G01Y479953D01*
G03X1723799Y480083I-200J0D01*
G01X1723798Y480084D01*
G02X1723428Y481071I1131J987D01*
G37*
G36*
G01X54726Y486270D02*
X54727Y486269D01*
G03X54857Y486221I130J152D01*
G01X55121D01*
G03X55251Y486269I0J200D01*
G01X55252Y486270D01*
G02X56239Y486640I987J-1131D01*
G02X57741Y485138I0J-1502D01*
G02X57474Y484283I-1502J0D01*
G01X57451Y484249D01*
X57434Y484168D01*
X57514Y483801D01*
X57562Y483734D01*
X57597Y483713D01*
G02X58326Y482425I-773J-1288D01*
G02X55322I-1502J0D01*
G02X55589Y483280I1502J0D01*
G01X55612Y483314D01*
X55629Y483395D01*
X55549Y483762D01*
X55501Y483829D01*
X55466Y483850D01*
G02X55253Y484006I777J1285D01*
G03X55251Y484007I-88J-173D01*
G03X55121Y484055I-130J-152D01*
G01X54857D01*
G03X54727Y484007I0J-200D01*
G01X54726Y484006D01*
G02X52752I-987J1131D01*
G01X52751D01*
Y484007D01*
G03X52621Y484055I-130J-152D01*
G01X52357D01*
G03X52227Y484007I0J-200D01*
G01X52226Y484006D01*
G02X51239Y483636I-987J1131D01*
G02X50118Y484139I0J1501D01*
G01X50089Y484172D01*
X50012Y484206D01*
X49667Y484204D01*
G03X49519Y484138I0J-200D01*
G01X49518Y484137D01*
G02X48390Y483626I-1129J991D01*
G02Y486630I0J1502D01*
G02X49511Y486127I0J-1501D01*
G01X49540Y486094D01*
X49617Y486060D01*
X49962Y486062D01*
G03X50110Y486128I0J200D01*
G01X50111Y486129D01*
G02X51239Y486640I1129J-991D01*
G02X52226Y486270I0J-1501D01*
G01X52227D01*
Y486269D01*
G03X52357Y486221I130J152D01*
G01X52621D01*
G03X52751Y486269I0J200D01*
G01X52752Y486270D01*
G02X54726I987J-1131D01*
G37*
G36*
G01X1746579Y486712D02*
X1746580Y486711D01*
G03X1746710Y486663I130J152D01*
G01X1746974D01*
G03X1747104Y486711I0J200D01*
G01X1747105Y486712D01*
G02X1748092Y487082I987J-1131D01*
G02Y484078I0J-1502D01*
G02X1747105Y484448I0J1501D01*
G01X1747104D01*
Y484449D01*
G03X1746974Y484497I-130J-152D01*
G01X1746710D01*
G03X1746580Y484449I0J-200D01*
G01X1746579Y484448D01*
G02X1744605I-987J1131D01*
G01X1744604D01*
Y484449D01*
G03X1744474Y484497I-130J-152D01*
G01X1744210D01*
G03X1744080Y484449I0J-200D01*
G01X1744079Y484448D01*
G02X1743092Y484078I-987J1131D01*
G02Y487082I0J1502D01*
G02X1744079Y486712I0J-1501D01*
G01X1744080D01*
Y486711D01*
G03X1744210Y486663I130J152D01*
G01X1744474D01*
G03X1744604Y486711I0J200D01*
G01X1744605Y486712D01*
G02X1746579I987J-1131D01*
G37*
G36*
G01X61198Y493714D02*
G02X64202I1502J0D01*
G02X63832Y492727I-1501J0D01*
G01Y492726D01*
X63831D01*
G03X63783Y492596I152J-130D01*
G01Y492332D01*
G03X63831Y492202I200J0D01*
G01X63832Y492201D01*
G02X64202Y491214I-1131J-987D01*
G02X61198I-1502J0D01*
G02X61568Y492201I1501J0D01*
G01Y492202D01*
X61569D01*
G03X61617Y492332I-152J130D01*
G01Y492596D01*
G03X61569Y492726I-200J0D01*
G01X61568Y492727D01*
G02X61198Y493714I1131J987D01*
G37*
G36*
G01X64901Y495487D02*
G02X67905I1502J0D01*
G02X67535Y494500I-1501J0D01*
G01Y494499D01*
X67534D01*
G03X67486Y494369I152J-130D01*
G01Y494105D01*
G03X67534Y493975I200J0D01*
G01X67535Y493974D01*
G02X67905Y492987I-1131J-987D01*
G02X64901I-1502J0D01*
G02X65271Y493974I1501J0D01*
G01Y493975D01*
X65272D01*
G03X65320Y494105I-152J130D01*
G01Y494369D01*
G03X65272Y494499I-200J0D01*
G01X65271Y494500D01*
G02X64901Y495487I1131J987D01*
G37*
G36*
G01X1746515Y494089D02*
Y494383D01*
G03X1746450Y494530I-200J-1D01*
G02X1745965Y495636I1019J1106D01*
G02X1748969I1502J0D01*
G02X1748484Y494530I-1504J0D01*
G03X1748419Y494383I135J-148D01*
G01Y494089D01*
G03X1748484Y493942I200J1D01*
G02X1748969Y492836I-1019J-1106D01*
G02X1745965I-1502J0D01*
G02X1746450Y493942I1504J0D01*
G03X1746515Y494089I-135J148D01*
G37*
G36*
G01X70615Y496494D02*
Y496808D01*
G03X70538Y496966I-200J0D01*
G02X69959Y498151I923J1185D01*
G02X71461Y499653I1502J0D01*
G02X72448Y499283I0J-1501D01*
G01X72449D01*
Y499282D01*
G03X72579Y499234I130J152D01*
G01X72843D01*
G03X72973Y499282I0J200D01*
G01X72974Y499283D01*
G02X73961Y499653I987J-1131D01*
G02X75463Y498151I0J-1502D01*
G02X74884Y496966I-1502J0D01*
G03X74807Y496808I123J-158D01*
G01Y496494D01*
G03X74884Y496336I200J0D01*
G02X75463Y495151I-923J-1185D01*
G02X73961Y493649I-1502J0D01*
G02X72974Y494019I0J1501D01*
G01X72973D01*
Y494020D01*
G03X72843Y494068I-130J-152D01*
G01X72579D01*
G03X72449Y494020I0J-200D01*
G01X72448Y494019D01*
G02X71461Y493649I-987J1131D01*
G02X69959Y495151I0J1502D01*
G02X70538Y496336I1502J0D01*
G03X70615Y496494I-123J158D01*
G37*
G36*
G01X76531Y498633D02*
G02X79535I1502J0D01*
G02X79165Y497646I-1501J0D01*
G01Y497645D01*
X79164D01*
G03X79116Y497515I152J-130D01*
G01Y497251D01*
G03X79164Y497121I200J0D01*
G01X79165Y497120D01*
G02Y495146I-1131J-987D01*
G01Y495145D01*
X79164D01*
G03X79116Y495015I152J-130D01*
G01Y494751D01*
G03X79164Y494621I200J0D01*
G01X79165Y494620D01*
G02Y492646I-1131J-987D01*
G01Y492645D01*
X79164D01*
G03X79116Y492515I152J-130D01*
G01Y492251D01*
G03X79164Y492121I200J0D01*
G01X79165Y492120D01*
G02X79535Y491133I-1131J-987D01*
G02X76531I-1502J0D01*
G02X76901Y492120I1501J0D01*
G01Y492121D01*
X76902D01*
G03X76950Y492251I-152J130D01*
G01Y492515D01*
G03X76902Y492645I-200J0D01*
G01X76901Y492646D01*
G02Y494620I1131J987D01*
G01Y494621D01*
X76902D01*
G03X76950Y494751I-152J130D01*
G01Y495015D01*
G03X76902Y495145I-200J0D01*
G01X76901Y495146D01*
G02Y497120I1131J987D01*
G01Y497121D01*
X76902D01*
G03X76950Y497251I-152J130D01*
G01Y497515D01*
G03X76902Y497645I-200J0D01*
G01X76901Y497646D01*
G02X76531Y498633I1131J987D01*
G37*
G36*
G01X43288Y505957D02*
X43289Y505956D01*
G03X43419Y505908I130J152D01*
G01X43683D01*
G03X43813Y505956I0J200D01*
G01X43814Y505957D01*
G02X44801Y506327I987J-1131D01*
G02Y503323I0J-1502D01*
G02X43814Y503693I0J1501D01*
G01X43813D01*
Y503694D01*
G03X43683Y503742I-130J-152D01*
G01X43419D01*
G03X43289Y503694I0J-200D01*
G01X43288Y503693D01*
G02X41314I-987J1131D01*
G01X41313D01*
Y503694D01*
G03X41183Y503742I-130J-152D01*
G01X40919D01*
G03X40789Y503694I0J-200D01*
G01X40788Y503693D01*
G02X39801Y503323I-987J1131D01*
G02Y506327I0J1502D01*
G02X40788Y505957I0J-1501D01*
G01X40789D01*
Y505956D01*
G03X40919Y505908I130J152D01*
G01X41183D01*
G03X41313Y505956I0J200D01*
G01X41314Y505957D01*
G02X43288I987J-1131D01*
G37*
G36*
G01X43229Y518533D02*
X43230Y518532D01*
G03X43360Y518484I130J152D01*
G01X43624D01*
G03X43754Y518532I0J200D01*
G01X43755Y518533D01*
G02X44742Y518903I987J-1131D01*
G02Y515899I0J-1502D01*
G02X43755Y516269I0J1501D01*
G01X43754D01*
Y516270D01*
G03X43624Y516318I-130J-152D01*
G01X43360D01*
G03X43230Y516270I0J-200D01*
G01X43229Y516269D01*
G02X41255I-987J1131D01*
G01X41254D01*
Y516270D01*
G03X41124Y516318I-130J-152D01*
G01X40860D01*
G03X40730Y516270I0J-200D01*
G01X40729Y516269D01*
G02X39742Y515899I-987J1131D01*
G02Y518903I0J1502D01*
G02X40729Y518533I0J-1501D01*
G01X40730D01*
Y518532D01*
G03X40860Y518484I130J152D01*
G01X41124D01*
G03X41254Y518532I0J200D01*
G01X41255Y518533D01*
G02X43229I987J-1131D01*
G37*
G36*
G01X44341Y523822D02*
Y524116D01*
G03X44276Y524263I-200J-1D01*
G02X43791Y525369I1019J1106D01*
G02X46795I1502J0D01*
G02X46310Y524263I-1504J0D01*
G03X46245Y524116I135J-148D01*
G01Y523822D01*
G03X46310Y523675I200J1D01*
G02X46795Y522569I-1019J-1106D01*
G02X43791I-1502J0D01*
G02X44276Y523675I1504J0D01*
G03X44341Y523822I-135J148D01*
G37*
G36*
G01X51367Y540458D02*
G02X54371I1502J0D01*
G02X54001Y539471I-1501J0D01*
G01Y539470D01*
X54000D01*
G03X53952Y539340I152J-130D01*
G01Y539076D01*
G03X54000Y538946I200J0D01*
G01X54001Y538945D01*
G02X54371Y537958I-1131J-987D01*
G02X51367I-1502J0D01*
G02X51737Y538945I1501J0D01*
G01Y538946D01*
X51738D01*
G03X51786Y539076I-152J130D01*
G01Y539340D01*
G03X51738Y539470I-200J0D01*
G01X51737Y539471D01*
G02X51367Y540458I1131J987D01*
G37*
G36*
G01X55070Y542231D02*
G02X58074I1502J0D01*
G02X57704Y541244I-1501J0D01*
G01Y541243D01*
X57703D01*
G03X57655Y541113I152J-130D01*
G01Y540849D01*
G03X57703Y540719I200J0D01*
G01X57704Y540718D01*
G02X58074Y539731I-1131J-987D01*
G02X55070I-1502J0D01*
G02X55440Y540718I1501J0D01*
G01Y540719D01*
X55441D01*
G03X55489Y540849I-152J130D01*
G01Y541113D01*
G03X55441Y541243I-200J0D01*
G01X55440Y541244D01*
G02X55070Y542231I1131J987D01*
G37*
G36*
G01X74175Y549490D02*
X74176Y549489D01*
G03X74306Y549441I130J152D01*
G01X74570D01*
G03X74700Y549489I0J200D01*
G01X74701Y549490D01*
G02X75688Y549860I987J-1131D01*
G02Y546856I0J-1502D01*
G02X74701Y547226I0J1501D01*
G01X74700D01*
Y547227D01*
G03X74570Y547275I-130J-152D01*
G01X74306D01*
G03X74176Y547227I0J-200D01*
G01X74175Y547226D01*
G02X72201I-987J1131D01*
G01X72200D01*
Y547227D01*
G03X72070Y547275I-130J-152D01*
G01X71806D01*
G03X71676Y547227I0J-200D01*
G01X71675Y547226D01*
G02X69701I-987J1131D01*
G01X69700D01*
Y547227D01*
G03X69570Y547275I-130J-152D01*
G01X69306D01*
G03X69176Y547227I0J-200D01*
G01X69175Y547226D01*
G02X69127Y547185I-999J1121D01*
G01X69091Y547157D01*
X69051Y547074D01*
X69053Y546714D01*
G03X69129Y546558I200J1D01*
G02X69704Y545377I-927J-1182D01*
G02X69334Y544390I-1501J0D01*
G01Y544389D01*
X69333D01*
G03X69285Y544259I152J-130D01*
G01Y543995D01*
G03X69333Y543865I200J0D01*
G01X69334Y543864D01*
G02Y541890I-1131J-987D01*
G01Y541889D01*
X69333D01*
G03X69285Y541759I152J-130D01*
G01Y541495D01*
G03X69333Y541365I200J0D01*
G01X69334Y541364D01*
G02Y539390I-1131J-987D01*
G01Y539389D01*
X69333D01*
G03X69285Y539259I152J-130D01*
G01Y538995D01*
G03X69333Y538865I200J0D01*
G01X69334Y538864D01*
G02X69704Y537877I-1131J-987D01*
G02X66700I-1502J0D01*
G02X67070Y538864I1501J0D01*
G01Y538865D01*
X67071D01*
G03X67119Y538995I-152J130D01*
G01Y539259D01*
G03X67071Y539389I-200J0D01*
G01X67070Y539390D01*
G02Y541364I1131J987D01*
G01Y541365D01*
X67071D01*
G03X67119Y541495I-152J130D01*
G01Y541759D01*
G03X67071Y541889I-200J0D01*
G01X67070Y541890D01*
G02Y543864I1131J987D01*
G01Y543865D01*
X67071D01*
G03X67119Y543995I-152J130D01*
G01Y544259D01*
G03X67071Y544389I-200J0D01*
G01X67070Y544390D01*
G02X66700Y545377I1131J987D01*
G01Y545378D01*
G02X67263Y546550I1502J0D01*
G01X67299Y546578D01*
X67339Y546661D01*
X67337Y547021D01*
G03X67261Y547177I-200J-1D01*
G02X66686Y548358I927J1182D01*
G02X68188Y549860I1502J0D01*
G02X69175Y549490I0J-1501D01*
G01X69176D01*
Y549489D01*
G03X69306Y549441I130J152D01*
G01X69570D01*
G03X69700Y549489I0J200D01*
G01X69701Y549490D01*
G02X71675I987J-1131D01*
G01X71676D01*
Y549489D01*
G03X71806Y549441I130J152D01*
G01X72070D01*
G03X72200Y549489I0J200D01*
G01X72201Y549490D01*
G02X74175I987J-1131D01*
G37*
G36*
G01X222698Y549800D02*
G02X225702I1502J0D01*
G02X225163Y548648I-1501J0D01*
G01X225162Y548647D01*
G03X225092Y548509I129J-152D01*
G01X225071Y548221D01*
G03X225120Y548075I200J-14D01*
G01X225121Y548074D01*
G02X225502Y547075I-1121J-1000D01*
G02X222498I-1502J0D01*
G02X223037Y548227I1501J0D01*
G01X223038Y548228D01*
G03X223108Y548366I-129J152D01*
G01X223129Y548654D01*
G03X223080Y548800I-200J14D01*
G01X223079Y548801D01*
G02X222698Y549800I1121J1000D01*
G37*
G36*
G01X45390Y554242D02*
X45096D01*
G03X44949Y554177I1J-200D01*
G02X43843Y553692I-1106J1019D01*
G02Y556696I0J1502D01*
G02X44949Y556211I0J-1504D01*
G03X45096Y556146I148J135D01*
G01X45390D01*
G03X45537Y556211I-1J200D01*
G02X46643Y556696I1106J-1019D01*
G02Y553692I0J-1502D01*
G02X45537Y554177I0J1504D01*
G03X45390Y554242I-148J-135D01*
G37*
G36*
G01Y562242D02*
X45096D01*
G03X44949Y562177I1J-200D01*
G02X43843Y561692I-1106J1019D01*
G02Y564696I0J1502D01*
G02X44949Y564211I0J-1504D01*
G03X45096Y564146I148J135D01*
G01X45390D01*
G03X45537Y564211I-1J200D01*
G02X46643Y564696I1106J-1019D01*
G02Y561692I0J-1502D01*
G02X45537Y562177I0J1504D01*
G03X45390Y562242I-148J-135D01*
G37*
G36*
G01X77232Y564994D02*
Y565300D01*
G03X77161Y565452I-200J-1D01*
G02X76631Y566597I972J1145D01*
G02X79635I1502J0D01*
G02X79105Y565452I-1502J0D01*
G03X79034Y565300I129J-153D01*
G01Y564994D01*
G03X79105Y564842I200J1D01*
G02X79635Y563697I-972J-1145D01*
G02X79229Y562670I-1502J0D01*
G01X79203Y562643D01*
X79175Y562572D01*
Y562222D01*
X79203Y562151D01*
X79229Y562124D01*
G02Y560070I-1096J-1027D01*
G01X79203Y560043D01*
X79175Y559972D01*
Y559622D01*
X79203Y559551D01*
X79229Y559524D01*
G02Y557470I-1096J-1027D01*
G01X79203Y557443D01*
X79175Y557372D01*
Y557022D01*
X79203Y556951D01*
X79229Y556924D01*
G02Y554870I-1096J-1027D01*
G01X79203Y554843D01*
X79175Y554772D01*
Y554422D01*
X79203Y554351D01*
X79229Y554324D01*
G02X79635Y553297I-1096J-1027D01*
G02X76631I-1502J0D01*
G02X77037Y554324I1502J0D01*
G01X77063Y554351D01*
X77091Y554422D01*
Y554772D01*
X77063Y554843D01*
X77037Y554870D01*
G02Y556924I1096J1027D01*
G01X77063Y556951D01*
X77091Y557022D01*
Y557372D01*
X77063Y557443D01*
X77037Y557470D01*
G02Y559524I1096J1027D01*
G01X77063Y559551D01*
X77091Y559622D01*
Y559972D01*
X77063Y560043D01*
X77037Y560070D01*
G02Y562124I1096J1027D01*
G01X77063Y562151D01*
X77091Y562222D01*
Y562572D01*
X77063Y562643D01*
X77037Y562670D01*
G02X76631Y563697I1096J1027D01*
G02X77161Y564842I1502J0D01*
G03X77232Y564994I-129J153D01*
G37*
G36*
G01X45390Y570242D02*
X45096D01*
G03X44949Y570177I1J-200D01*
G02X43843Y569692I-1106J1019D01*
G02Y572696I0J1502D01*
G02X44949Y572211I0J-1504D01*
G03X45096Y572146I148J135D01*
G01X45390D01*
G03X45537Y572211I-1J200D01*
G02X46643Y572696I1106J-1019D01*
G02Y569692I0J-1502D01*
G02X45537Y570177I0J1504D01*
G03X45390Y570242I-148J-135D01*
G37*
G36*
G01X46653Y582174D02*
X46947D01*
G03X47094Y582239I-1J200D01*
G02X49306I1106J-1017D01*
G03X49453Y582174I148J135D01*
G01X49747D01*
G03X49894Y582239I-1J200D01*
G02X51000Y582724I1106J-1019D01*
G02Y579720I0J-1502D01*
G02X49894Y580205I0J1504D01*
G03X49747Y580270I-148J-135D01*
G01X49453D01*
G03X49306Y580205I1J-200D01*
G02X47094I-1106J1017D01*
G03X46947Y580270I-148J-135D01*
G01X46653D01*
G03X46506Y580205I1J-200D01*
G02X45400Y579720I-1106J1019D01*
G02Y582724I0J1502D01*
G02X46506Y582239I0J-1504D01*
G03X46653Y582174I148J135D01*
G37*
G36*
G01Y592167D02*
X46947D01*
G03X47094Y592232I-1J200D01*
G02X49306I1106J-1017D01*
G03X49453Y592167I148J135D01*
G01X49747D01*
G03X49894Y592232I-1J200D01*
G02X51000Y592717I1106J-1019D01*
G02Y589713I0J-1502D01*
G02X49894Y590198I0J1504D01*
G03X49747Y590263I-148J-135D01*
G01X49453D01*
G03X49306Y590198I1J-200D01*
G02X47094I-1106J1017D01*
G03X46947Y590263I-148J-135D01*
G01X46653D01*
G03X46506Y590198I1J-200D01*
G02X45400Y589713I-1106J1019D01*
G02Y592717I0J1502D01*
G02X46506Y592232I0J-1504D01*
G03X46653Y592167I148J135D01*
G37*
G36*
G01X49625Y611514D02*
X49919D01*
G03X50066Y611579I-1J200D01*
G02X52278I1106J-1017D01*
G03X52425Y611514I148J135D01*
G01X52719D01*
G03X52866Y611579I-1J200D01*
G02X53972Y612064I1106J-1019D01*
G02X55474Y610562I0J-1502D01*
G02X54989Y609456I-1504J0D01*
G03X54924Y609309I135J-148D01*
G01Y609015D01*
G03X54989Y608868I200J1D01*
G02X55474Y607762I-1019J-1106D01*
G02X53972Y606260I-1502J0D01*
G02X52866Y606745I0J1504D01*
G03X52719Y606810I-148J-135D01*
G01X52425D01*
G03X52278Y606745I1J-200D01*
G02X50066I-1106J1017D01*
G03X49919Y606810I-148J-135D01*
G01X49625D01*
G03X49478Y606745I1J-200D01*
G02X47266I-1106J1017D01*
G03X47119Y606810I-148J-135D01*
G01X46825D01*
G03X46678Y606745I1J-200D01*
G02X45572Y606260I-1106J1019D01*
G02X44070Y607762I0J1502D01*
G02X44555Y608868I1504J0D01*
G03X44620Y609015I-135J148D01*
G01Y609309D01*
G03X44555Y609456I-200J-1D01*
G02X44070Y610562I1019J1106D01*
G02X45572Y612064I1502J0D01*
G02X46678Y611579I0J-1504D01*
G03X46825Y611514I148J135D01*
G01X47119D01*
G03X47266Y611579I-1J200D01*
G02X49478I1106J-1017D01*
G03X49625Y611514I148J135D01*
G37*
G36*
G01X68718Y617966D02*
Y618260D01*
G03X68653Y618407I-200J-1D01*
G02X68168Y619513I1019J1106D01*
G02X71172I1502J0D01*
G02X70687Y618407I-1504J0D01*
G03X70622Y618260I135J-148D01*
G01Y617966D01*
G03X70687Y617819I200J1D01*
G02Y615607I-1017J-1106D01*
G03X70622Y615460I135J-148D01*
G01Y615166D01*
G03X70687Y615019I200J1D01*
G02X71172Y613913I-1019J-1106D01*
G02X68168I-1502J0D01*
G02X68653Y615019I1504J0D01*
G03X68718Y615166I-135J148D01*
G01Y615460D01*
G03X68653Y615607I-200J-1D01*
G02Y617819I1017J1106D01*
G03X68718Y617966I-135J148D01*
G37*
G36*
G01X80788Y618211D02*
Y618505D01*
G03X80723Y618652I-200J-1D01*
G02X80238Y619758I1019J1106D01*
G02X83242I1502J0D01*
G02X82757Y618652I-1504J0D01*
G03X82692Y618505I135J-148D01*
G01Y618211D01*
G03X82757Y618064I200J1D01*
G02Y615852I-1017J-1106D01*
G03X82692Y615705I135J-148D01*
G01Y615411D01*
G03X82757Y615264I200J1D01*
G02X83242Y614158I-1019J-1106D01*
G02X80238I-1502J0D01*
G02X80723Y615264I1504J0D01*
G03X80788Y615411I-135J148D01*
G01Y615705D01*
G03X80723Y615852I-200J-1D01*
G02Y618064I1017J1106D01*
G03X80788Y618211I-135J148D01*
G37*
G36*
G01X60902Y619106D02*
Y619400D01*
G03X60837Y619547I-200J-1D01*
G02X60352Y620653I1019J1106D01*
G02X63356I1502J0D01*
G02X62871Y619547I-1504J0D01*
G03X62806Y619400I135J-148D01*
G01Y619106D01*
G03X62871Y618959I200J1D01*
G02X63356Y617853I-1019J-1106D01*
G02X60352I-1502J0D01*
G02X60837Y618959I1504J0D01*
G03X60902Y619106I-135J148D01*
G37*
G36*
G01X35293Y661450D02*
G02Y664454I0J1502D01*
G02X36320Y664048I0J-1502D01*
G01X36347Y664023D01*
X36415Y663995D01*
X36723Y663990D01*
G03X36857Y664039I3J200D01*
G02X37847Y664412I991J-1129D01*
G02Y661408I0J-1502D01*
G02X36820Y661814I0J1502D01*
G01X36793Y661839D01*
X36725Y661867D01*
X36417Y661872D01*
G03X36283Y661823I-3J-200D01*
G02X35293Y661450I-991J1129D01*
G37*
G36*
G01X35250Y670006D02*
G02Y673010I0J1502D01*
G02X36258Y672621I-1J-1502D01*
G01X36259Y672620D01*
G03X36393Y672569I133J149D01*
G01X36661D01*
G03X36795Y672620I1J200D01*
G01X36796Y672621D01*
G02X37804Y673010I1009J-1113D01*
G02Y670006I0J-1502D01*
G02X36796Y670395I1J1502D01*
G01X36795Y670396D01*
G03X36661Y670447I-133J-149D01*
G01X36393D01*
G03X36259Y670396I-1J-200D01*
G01X36258Y670395D01*
G02X35250Y670006I-1009J1113D01*
G37*
G36*
G01X196282Y611886D02*
G02X195930Y611037I-1201J1D01*
G01X192854Y607961D01*
G02X192004Y607608I-851J849D01*
G01X159573D01*
G03X159431Y607549I0J-200D01*
G01X154811Y602930D01*
G03X154752Y602788I141J-142D01*
G01Y574727D01*
G03X154811Y574585I200J0D01*
G01X163538Y565859D01*
G03X163680Y565800I142J141D01*
G01X175628D01*
G03X175794Y565889I0J200D01*
G01X175979Y566165D01*
G03X175998Y566353I-166J112D01*
G02X175893Y566758I1387J576D01*
G01Y566760D01*
G03X175796Y566908I-198J-24D01*
G01X175521Y567072D01*
G03X175344Y567085I-102J-172D01*
G02X174776Y566973I-569J1390D01*
G02X173314Y568132I0J1502D01*
G01Y568133D01*
G03X173233Y568250I-194J-48D01*
G01X173012Y568404D01*
G03X172875Y568438I-114J-165D01*
G01X172874D01*
G02X172686Y568426I-189J1490D01*
G02X171184Y569928I0J1502D01*
G02X171205Y570176I1502J-2D01*
G01Y570178D01*
X171211Y570214D01*
X171197Y570284D01*
X171036Y570541D01*
G03X170921Y570627I-169J-107D01*
G02X169837Y572070I418J1443D01*
G02X172841I1502J0D01*
G02X172820Y571822I-1502J2D01*
G01Y571820D01*
X172814Y571784D01*
X172828Y571714D01*
X172989Y571457D01*
G03X173104Y571371I169J107D01*
G02X173163Y571352I-431J-1439D01*
G03X173167Y571350I91J176D01*
G01X173202Y571339D01*
X173275Y571343D01*
X173591Y571482D01*
X173644Y571535D01*
X173659Y571569D01*
G02X175033Y572464I1374J-607D01*
G02X176509Y571243I0J-1503D01*
G01X176516Y571205D01*
X176555Y571142D01*
X176803Y570958D01*
G03X176942Y570920I119J161D01*
G01X176943D01*
G02X177097Y570928I155J-1494D01*
G01X177099D01*
G02X178601Y569426I0J-1502D01*
G02X178332Y568568I-1503J0D01*
G03X178298Y568431I164J-114D01*
G01X178327Y568169D01*
G03X178392Y568043I199J23D01*
G02X178887Y566929I-1006J-1114D01*
G02X178772Y566353I-1502J0D01*
G03X178791Y566165I185J-76D01*
G01X178976Y565889D01*
G03X179142Y565800I166J111D01*
G01X202248D01*
G02X203301Y565174I-2J-1202D01*
G03X204179I439J240D01*
G02X205232Y565800I1055J-576D01*
G01X207258D01*
G03X207400Y565859I0J200D01*
G01X237121Y595579D01*
G03X237180Y595721I-141J142D01*
G01Y678202D01*
G02X237532Y679051I1201J-1D01*
G01X240608Y682127D01*
G02X241458Y682480I851J-849D01*
G01X250877D01*
G02X251727Y682127I-1J-1202D01*
G01X252673Y681181D01*
G02X253026Y680331I-849J-851D01*
G01Y637978D01*
G03X253162Y637789I200J0D01*
G02Y634939I-474J-1425D01*
G01X253101Y634918D01*
X253026Y634814D01*
Y582068D01*
G02X252673Y581218I-1202J1D01*
G01X226823Y555368D01*
G02X225976Y555016I-850J850D01*
G01X225498Y555014D01*
G02X225423Y555029I1J200D01*
G01X225061Y555174D01*
G02X224997Y555216I76J185D01*
G01X224853Y555355D01*
X224850Y555358D01*
G03X224502Y555500I-349J-358D01*
G01X224500D01*
G03X224000Y555000I0J-500D01*
G01Y554998D01*
G03X224142Y554650I500J1D01*
G01X224145Y554647D01*
X224284Y554503D01*
G02X224326Y554439I-143J-140D01*
G01X224471Y554077D01*
G02X224486Y554002I-185J-76D01*
G01X224484Y553524D01*
G02X224132Y552677I-1202J3D01*
G01X220542Y549087D01*
G02X219692Y548734I-851J849D01*
G01X187677D01*
G02X186832Y549083I2J1202D01*
G01X186489Y549423D01*
G02X186446Y549488I142J141D01*
G01X186292Y549856D01*
G02X186276Y549933I184J78D01*
G01Y550128D01*
Y550131D01*
G03X186105Y550500I-500J-8D01*
G01X186099Y550505D01*
X185896Y550689D01*
G03X185618Y550679I-134J-149D01*
G01X185415Y550469D01*
G03X185413Y550467I140J-142D01*
G03X185276Y550129I363J-344D01*
G01Y549933D01*
G02X185260Y549856I-200J1D01*
G01X185106Y549488D01*
G02X185063Y549423I-185J76D01*
G01X184720Y549083D01*
G02X183875Y548734I-847J853D01*
G01X154442D01*
G02X153592Y549087I1J1202D01*
G01X142453Y560226D01*
G02X142100Y561076I849J851D01*
G01Y623132D01*
G02X142453Y623982I1202J-1D01*
G01X145072Y626601D01*
G02X145922Y626954I851J-849D01*
G01X180222D01*
G03X180408Y627079I1J200D01*
G01X180547Y627422D01*
G03X180502Y627640I-185J75D01*
G02X186368I2933J3010D01*
G01X186324Y627597D01*
X186300Y627478D01*
X186462Y627079D01*
G03X186648Y626954I185J75D01*
G01X190332D01*
G02X191182Y626601I-1J-1202D01*
G01X195930Y621853D01*
G02X196282Y621004I-849J-850D01*
G01Y611886D01*
G37*
G36*
G01X36910Y680606D02*
G02Y683610I0J1502D01*
G02X37952Y683190I0J-1503D01*
G01X37981Y683162D01*
X38051Y683134D01*
X38408D01*
X38478Y683162D01*
X38507Y683190D01*
G02X39549Y683610I1042J-1083D01*
G02Y680606I0J-1502D01*
G02X38507Y681026I0J1503D01*
G01X38478Y681054D01*
X38408Y681082D01*
X38051D01*
X37981Y681054D01*
X37952Y681026D01*
G02X36910Y680606I-1042J1083D01*
G37*
G36*
G01X201544Y693687D02*
G03X201138Y694079I-400J-8D01*
G01X201115D01*
G02Y697083I0J1502D01*
G02X202617Y695610I0J-1502D01*
G03X203023Y695218I400J8D01*
G01X203046D01*
G02Y692214I0J-1502D01*
G02X201544Y693687I0J1502D01*
G37*
G36*
G01X73397Y823171D02*
Y823465D01*
G03X73332Y823612I-200J-1D01*
G02X72847Y824718I1019J1106D01*
G02X75851I1502J0D01*
G02X75366Y823612I-1504J0D01*
G03X75301Y823465I135J-148D01*
G01Y823171D01*
G03X75366Y823024I200J1D01*
G02X75851Y821918I-1019J-1106D01*
G02X72847I-1502J0D01*
G02X73332Y823024I1504J0D01*
G03X73397Y823171I-135J148D01*
G37*
G36*
G01X26275Y814415D02*
X40423Y828563D01*
G02X41768Y829120I1345J-1345D01*
G01X56049D01*
G02Y825316I0J-1902D01*
G01X42639D01*
G03X42497Y825257I0J-200D01*
G01X29581Y812341D01*
G03X29522Y812199I141J-142D01*
G01Y706898D01*
G03X29581Y706756I200J0D01*
G01X35910Y700427D01*
G02X35968Y700365I-1359J-1330D01*
G03X35970Y700363I142J140D01*
G01X35994Y700337D01*
X36059Y700304D01*
X36359Y700271D01*
G03X36496Y700307I21J199D01*
G02X37365Y700584I869J-1225D01*
G02X38471Y700099I0J-1504D01*
G03X38618Y700034I148J135D01*
G01X38912D01*
G03X39059Y700099I-1J200D01*
G02X40165Y700584I1106J-1019D01*
G02Y697580I0J-1502D01*
G02X39059Y698065I0J1504D01*
G03X38912Y698130I-148J-135D01*
G01X38618D01*
G03X38471Y698065I1J-200D01*
G02X37365Y697580I-1106J1019D01*
G02X36496Y697857I0J1502D01*
G03X36359Y697893I-116J-163D01*
G01X36095Y697864D01*
G03X35969Y697800I22J-199D01*
G02X34565Y697180I-1405J1282D01*
G02X33220Y697737I0J1902D01*
G01X26275Y704682D01*
G02X25718Y706027I1345J1345D01*
G01Y813070D01*
G02X26275Y814415I1902J0D01*
G37*
G36*
G01X42316Y1066197D02*
X42343Y1066171D01*
X42414Y1066143D01*
X42764D01*
X42835Y1066171D01*
X42862Y1066197D01*
G02X43889Y1066603I1027J-1096D01*
G02X45391Y1065101I0J-1502D01*
G02X45021Y1064114I-1501J0D01*
G01Y1064113D01*
X45020D01*
G03X44972Y1063983I152J-130D01*
G01Y1063719D01*
G03X45020Y1063589I200J0D01*
G01X45021Y1063588D01*
G02X45391Y1062601I-1131J-987D01*
G02X43889Y1061099I-1502J0D01*
G02X42862Y1061505I0J1502D01*
G01X42835Y1061531D01*
X42764Y1061559D01*
X42414D01*
X42343Y1061531D01*
X42316Y1061505D01*
G02X40262I-1027J1096D01*
G01X40235Y1061531D01*
X40164Y1061559D01*
X39814D01*
X39743Y1061531D01*
X39716Y1061505D01*
G02X37662I-1027J1096D01*
G01X37635Y1061531D01*
X37564Y1061559D01*
X37214D01*
X37143Y1061531D01*
X37116Y1061505D01*
G02X36089Y1061099I-1027J1096D01*
G02X34587Y1062601I0J1502D01*
G02X34957Y1063588I1501J0D01*
G01Y1063589D01*
X34958D01*
G03X35006Y1063719I-152J130D01*
G01Y1063983D01*
G03X34958Y1064113I-200J0D01*
G01X34957Y1064114D01*
G02X34587Y1065101I1131J987D01*
G02X36089Y1066603I1502J0D01*
G02X37116Y1066197I0J-1502D01*
G01X37143Y1066171D01*
X37214Y1066143D01*
X37564D01*
X37635Y1066171D01*
X37662Y1066197D01*
G02X39716I1027J-1096D01*
G01X39743Y1066171D01*
X39814Y1066143D01*
X40164D01*
X40235Y1066171D01*
X40262Y1066197D01*
G02X42316I1027J-1096D01*
G37*
G36*
G01X27423Y1066625D02*
X27450Y1066599D01*
X27521Y1066571D01*
X27871D01*
X27942Y1066599D01*
X27969Y1066625D01*
G02X28996Y1067031I1027J-1096D01*
G02X30498Y1065529I0J-1502D01*
G02X30128Y1064542I-1501J0D01*
G01Y1064541D01*
X30127D01*
G03X30079Y1064411I152J-130D01*
G01Y1064147D01*
G03X30127Y1064017I200J0D01*
G01X30128Y1064016D01*
G02X30498Y1063029I-1131J-987D01*
G02X28996Y1061527I-1502J0D01*
G02X27969Y1061933I0J1502D01*
G01X27942Y1061959D01*
X27871Y1061987D01*
X27521D01*
X27450Y1061959D01*
X27423Y1061933D01*
G02X25369I-1027J1096D01*
G01X25342Y1061959D01*
X25271Y1061987D01*
X24921D01*
X24850Y1061959D01*
X24823Y1061933D01*
G02X22769I-1027J1096D01*
G01X22742Y1061959D01*
X22671Y1061987D01*
X22321D01*
X22250Y1061959D01*
X22223Y1061933D01*
G02X21196Y1061527I-1027J1096D01*
G02X19694Y1063029I0J1502D01*
G02X20064Y1064016I1501J0D01*
G01Y1064017D01*
X20065D01*
G03X20113Y1064147I-152J130D01*
G01Y1064411D01*
G03X20065Y1064541I-200J0D01*
G01X20064Y1064542D01*
G02X19694Y1065529I1131J987D01*
G02X21196Y1067031I1502J0D01*
G02X22223Y1066625I0J-1502D01*
G01X22250Y1066599D01*
X22321Y1066571D01*
X22671D01*
X22742Y1066599D01*
X22769Y1066625D01*
G02X24823I1027J-1096D01*
G01X24850Y1066599D01*
X24921Y1066571D01*
X25271D01*
X25342Y1066599D01*
X25369Y1066625D01*
G02X27423I1027J-1096D01*
G37*
G36*
G01X33425Y1074161D02*
G02Y1077165I0J1502D01*
G02X34412Y1076795I0J-1501D01*
G01X34413D01*
Y1076794D01*
G03X34543Y1076746I130J152D01*
G01X34807D01*
G03X34937Y1076794I0J200D01*
G01X34938Y1076795D01*
G02X35925Y1077165I987J-1131D01*
G02Y1074161I0J-1502D01*
G02X34938Y1074531I0J1501D01*
G01X34937D01*
Y1074532D01*
G03X34807Y1074580I-130J-152D01*
G01X34543D01*
G03X34413Y1074532I0J-200D01*
G01X34412Y1074531D01*
G02X33425Y1074161I-987J1131D01*
G37*
G36*
G01X27033Y1083774D02*
X27060Y1083748D01*
X27131Y1083720D01*
X27481D01*
X27552Y1083748D01*
X27579Y1083774D01*
G02X28606Y1084180I1027J-1096D01*
G02X30108Y1082678I0J-1502D01*
G02X29738Y1081691I-1501J0D01*
G01Y1081690D01*
X29737D01*
G03X29689Y1081560I152J-130D01*
G01Y1081296D01*
G03X29737Y1081166I200J0D01*
G01X29738Y1081165D01*
G02X30108Y1080178I-1131J-987D01*
G02X28606Y1078676I-1502J0D01*
G02X27579Y1079082I0J1502D01*
G01X27552Y1079108D01*
X27481Y1079136D01*
X27131D01*
X27060Y1079108D01*
X27033Y1079082D01*
G02X24979I-1027J1096D01*
G01X24952Y1079108D01*
X24881Y1079136D01*
X24531D01*
X24460Y1079108D01*
X24433Y1079082D01*
G02X22379I-1027J1096D01*
G01X22352Y1079108D01*
X22281Y1079136D01*
X21931D01*
X21860Y1079108D01*
X21833Y1079082D01*
G02X20806Y1078676I-1027J1096D01*
G02X19304Y1080178I0J1502D01*
G02X19674Y1081165I1501J0D01*
G01Y1081166D01*
X19675D01*
G03X19723Y1081296I-152J130D01*
G01Y1081560D01*
G03X19675Y1081690I-200J0D01*
G01X19674Y1081691D01*
G02X19304Y1082678I1131J987D01*
G02X20806Y1084180I1502J0D01*
G02X21833Y1083774I0J-1502D01*
G01X21860Y1083748D01*
X21931Y1083720D01*
X22281D01*
X22352Y1083748D01*
X22379Y1083774D01*
G02X24433I1027J-1096D01*
G01X24460Y1083748D01*
X24531Y1083720D01*
X24881D01*
X24952Y1083748D01*
X24979Y1083774D01*
G02X27033I1027J-1096D01*
G37*
G36*
G01X27548Y1102431D02*
X27575Y1102405D01*
X27646Y1102377D01*
X27996D01*
X28067Y1102405D01*
X28094Y1102431D01*
G02X29121Y1102837I1027J-1096D01*
G02X30623Y1101335I0J-1502D01*
G02X30230Y1100322I-1502J0D01*
G01X30204Y1100294D01*
X30177Y1100225D01*
Y1099879D01*
X30204Y1099810D01*
X30230Y1099782D01*
G02X30623Y1098769I-1109J-1013D01*
G02X29121Y1097267I-1502J0D01*
G02X28094Y1097673I0J1502D01*
G01X28067Y1097699D01*
X27996Y1097727D01*
X27646D01*
X27575Y1097699D01*
X27548Y1097673D01*
G02X25494I-1027J1096D01*
G01X25467Y1097699D01*
X25396Y1097727D01*
X25046D01*
X24975Y1097699D01*
X24948Y1097673D01*
G02X22894I-1027J1096D01*
G01X22867Y1097699D01*
X22796Y1097727D01*
X22446D01*
X22375Y1097699D01*
X22348Y1097673D01*
G02X21321Y1097267I-1027J1096D01*
G02X19819Y1098769I0J1502D01*
G02X20212Y1099782I1502J0D01*
G01X20238Y1099810D01*
X20265Y1099879D01*
Y1100225D01*
X20238Y1100294D01*
X20212Y1100322D01*
G02X19819Y1101335I1109J1013D01*
G02X21321Y1102837I1502J0D01*
G02X22348Y1102431I0J-1502D01*
G01X22375Y1102405D01*
X22446Y1102377D01*
X22796D01*
X22867Y1102405D01*
X22894Y1102431D01*
G02X24948I1027J-1096D01*
G01X24975Y1102405D01*
X25046Y1102377D01*
X25396D01*
X25467Y1102405D01*
X25494Y1102431D01*
G02X27548I1027J-1096D01*
G37*
G36*
G01X44859Y1106602D02*
G02X45925Y1106158I0J-1502D01*
G03X46067Y1106099I142J141D01*
G01X46351D01*
G03X46493Y1106158I0J200D01*
G02X47559Y1106602I1066J-1058D01*
G02Y1103598I0J-1502D01*
G02X46493Y1104042I0J1502D01*
G03X46351Y1104101I-142J-141D01*
G01X46067D01*
G03X45925Y1104042I0J-200D01*
G02X44859Y1103598I-1066J1058D01*
G02X43832Y1104004I0J1502D01*
G01X43805Y1104030D01*
X43734Y1104058D01*
X43384D01*
X43313Y1104030D01*
X43286Y1104004D01*
G02X41232I-1027J1096D01*
G01X41205Y1104030D01*
X41134Y1104058D01*
X40784D01*
X40713Y1104030D01*
X40686Y1104004D01*
G02X39659Y1103598I-1027J1096D01*
G02Y1106602I0J1502D01*
G02X40686Y1106196I0J-1502D01*
G01X40713Y1106170D01*
X40784Y1106142D01*
X41134D01*
X41205Y1106170D01*
X41232Y1106196D01*
G02X43286I1027J-1096D01*
G01X43313Y1106170D01*
X43384Y1106142D01*
X43734D01*
X43805Y1106170D01*
X43832Y1106196D01*
G02X44859Y1106602I1027J-1096D01*
G37*
G36*
G01X29874Y1113135D02*
G02X30940Y1112691I0J-1502D01*
G03X31082Y1112632I142J141D01*
G01X31366D01*
G03X31508Y1112691I0J200D01*
G02X32574Y1113135I1066J-1058D01*
G02Y1110131I0J-1502D01*
G02X31508Y1110575I0J1502D01*
G03X31366Y1110634I-142J-141D01*
G01X31082D01*
G03X30940Y1110575I0J-200D01*
G02X29874Y1110131I-1066J1058D01*
G02X28847Y1110537I0J1502D01*
G01X28820Y1110563D01*
X28749Y1110591D01*
X28399D01*
X28328Y1110563D01*
X28301Y1110537D01*
G02X26247I-1027J1096D01*
G01X26220Y1110563D01*
X26149Y1110591D01*
X25799D01*
X25728Y1110563D01*
X25701Y1110537D01*
G02X24674Y1110131I-1027J1096D01*
G02Y1113135I0J1502D01*
G02X25701Y1112729I0J-1502D01*
G01X25728Y1112703D01*
X25799Y1112675D01*
X26149D01*
X26220Y1112703D01*
X26247Y1112729D01*
G02X28301I1027J-1096D01*
G01X28328Y1112703D01*
X28399Y1112675D01*
X28749D01*
X28820Y1112703D01*
X28847Y1112729D01*
G02X29874Y1113135I1027J-1096D01*
G37*
G36*
G01X44859Y1116302D02*
G02X45925Y1115858I0J-1502D01*
G03X46067Y1115799I142J141D01*
G01X46351D01*
G03X46493Y1115858I0J200D01*
G02X47559Y1116302I1066J-1058D01*
G02Y1113298I0J-1502D01*
G02X46493Y1113742I0J1502D01*
G03X46351Y1113801I-142J-141D01*
G01X46067D01*
G03X45925Y1113742I0J-200D01*
G02X44859Y1113298I-1066J1058D01*
G02X43832Y1113704I0J1502D01*
G01X43805Y1113730D01*
X43734Y1113758D01*
X43384D01*
X43313Y1113730D01*
X43286Y1113704D01*
G02X41232I-1027J1096D01*
G01X41205Y1113730D01*
X41134Y1113758D01*
X40784D01*
X40713Y1113730D01*
X40686Y1113704D01*
G02X39659Y1113298I-1027J1096D01*
G02Y1116302I0J1502D01*
G02X40686Y1115896I0J-1502D01*
G01X40713Y1115870D01*
X40784Y1115842D01*
X41134D01*
X41205Y1115870D01*
X41232Y1115896D01*
G02X43286I1027J-1096D01*
G01X43313Y1115870D01*
X43384Y1115842D01*
X43734D01*
X43805Y1115870D01*
X43832Y1115896D01*
G02X44859Y1116302I1027J-1096D01*
G37*
G36*
G01X29874Y1122835D02*
G02X30940Y1122391I0J-1502D01*
G03X31082Y1122332I142J141D01*
G01X31366D01*
G03X31508Y1122391I0J200D01*
G02X32574Y1122835I1066J-1058D01*
G02Y1119831I0J-1502D01*
G02X31508Y1120275I0J1502D01*
G03X31366Y1120334I-142J-141D01*
G01X31082D01*
G03X30940Y1120275I0J-200D01*
G02X29874Y1119831I-1066J1058D01*
G02X28847Y1120237I0J1502D01*
G01X28820Y1120263D01*
X28749Y1120291D01*
X28399D01*
X28328Y1120263D01*
X28301Y1120237D01*
G02X26247I-1027J1096D01*
G01X26220Y1120263D01*
X26149Y1120291D01*
X25799D01*
X25728Y1120263D01*
X25701Y1120237D01*
G02X24674Y1119831I-1027J1096D01*
G02Y1122835I0J1502D01*
G02X25701Y1122429I0J-1502D01*
G01X25728Y1122403D01*
X25799Y1122375D01*
X26149D01*
X26220Y1122403D01*
X26247Y1122429D01*
G02X28301I1027J-1096D01*
G01X28328Y1122403D01*
X28399Y1122375D01*
X28749D01*
X28820Y1122403D01*
X28847Y1122429D01*
G02X29874Y1122835I1027J-1096D01*
G37*
G36*
G01X21974Y1128831D02*
G02Y1131835I0J1502D01*
G02X23040Y1131391I0J-1502D01*
G03X23182Y1131332I142J141D01*
G01X23466D01*
G03X23608Y1131391I0J200D01*
G02X24674Y1131835I1066J-1058D01*
G02Y1128831I0J-1502D01*
G02X23608Y1129275I0J1502D01*
G03X23466Y1129334I-142J-141D01*
G01X23182D01*
G03X23040Y1129275I0J-200D01*
G02X21974Y1128831I-1066J1058D01*
G37*
G36*
G01X48547Y1132186D02*
G02Y1135190I0J1502D01*
G02X49534Y1134820I0J-1501D01*
G01X49535D01*
Y1134819D01*
G03X49665Y1134771I130J152D01*
G01X49929D01*
G03X50059Y1134819I0J200D01*
G01X50060Y1134820D01*
G02X51047Y1135190I987J-1131D01*
G02Y1132186I0J-1502D01*
G02X50060Y1132556I0J1501D01*
G01X50059D01*
Y1132557D01*
G03X49929Y1132605I-130J-152D01*
G01X49665D01*
G03X49535Y1132557I0J-200D01*
G01X49534Y1132556D01*
G02X48547Y1132186I-987J1131D01*
G37*
G36*
G01X21209Y1137203D02*
G02Y1140207I0J1502D01*
G02X22196Y1139837I0J-1501D01*
G01X22197D01*
Y1139836D01*
G03X22327Y1139788I130J152D01*
G01X22591D01*
G03X22721Y1139836I0J200D01*
G01X22722Y1139837D01*
G02X23709Y1140207I987J-1131D01*
G02Y1137203I0J-1502D01*
G02X22722Y1137573I0J1501D01*
G01X22721D01*
Y1137574D01*
G03X22591Y1137622I-130J-152D01*
G01X22327D01*
G03X22197Y1137574I0J-200D01*
G01X22196Y1137573D01*
G02X21209Y1137203I-987J1131D01*
G37*
G36*
G01X46685Y1255187D02*
X46686Y1255186D01*
G03X46816Y1255138I130J152D01*
G01X47080D01*
G03X47210Y1255186I0J200D01*
G01X47211Y1255187D01*
G02X48198Y1255557I987J-1131D01*
G02X49700Y1254055I0J-1502D01*
G02X49330Y1253068I-1501J0D01*
G01Y1253067D01*
X49329D01*
G03X49281Y1252937I152J-130D01*
G01Y1252673D01*
G03X49329Y1252543I200J0D01*
G01X49330Y1252542D01*
G02X49700Y1251555I-1131J-987D01*
G02X48198Y1250053I-1502J0D01*
G02X47211Y1250423I0J1501D01*
G01X47210D01*
Y1250424D01*
G03X47080Y1250472I-130J-152D01*
G01X46816D01*
G03X46686Y1250424I0J-200D01*
G01X46685Y1250423D01*
G02X44711I-987J1131D01*
G01X44710D01*
Y1250424D01*
G03X44580Y1250472I-130J-152D01*
G01X44316D01*
G03X44186Y1250424I0J-200D01*
G01X44185Y1250423D01*
G02X43198Y1250053I-987J1131D01*
G02X41696Y1251555I0J1502D01*
G02X42066Y1252542I1501J0D01*
G01Y1252543D01*
X42067D01*
G03X42115Y1252673I-152J130D01*
G01Y1252937D01*
G03X42067Y1253067I-200J0D01*
G01X42066Y1253068D01*
G02X41696Y1254055I1131J987D01*
G02X43198Y1255557I1502J0D01*
G02X44185Y1255187I0J-1501D01*
G01X44186D01*
Y1255186D01*
G03X44316Y1255138I130J152D01*
G01X44580D01*
G03X44710Y1255186I0J200D01*
G01X44711Y1255187D01*
G02X46685I987J-1131D01*
G37*
G36*
G01X108270Y1464825D02*
Y1465951D01*
G02X108472Y1466154I202J1D01*
G01X111292D01*
G02X111494Y1465951I-1J-203D01*
G01Y1464825D01*
G03X111522Y1464722I200J-1D01*
G02X111794Y1463741I-1640J-983D01*
G02X111522Y1462760I-1912J2D01*
G03X111494Y1462657I172J-102D01*
G01Y1459706D01*
G03X111522Y1459603I200J-1D01*
G02X111794Y1458622I-1640J-983D01*
G02X111522Y1457641I-1912J2D01*
G03X111494Y1457538I172J-102D01*
G01Y1456413D01*
G02X111292Y1456210I-202J-1D01*
G01X108472D01*
G02X108270Y1456413I1J203D01*
G01Y1457538D01*
G03X108242Y1457641I-200J1D01*
G02X107970Y1458622I1640J983D01*
G02X108242Y1459603I1912J-2D01*
G03X108270Y1459706I-172J102D01*
G01Y1462657D01*
G03X108242Y1462760I-200J1D01*
G02X107970Y1463741I1640J983D01*
G02X108242Y1464722I1912J-2D01*
G03X108270Y1464825I-172J102D01*
G37*
G36*
G01X125592D02*
Y1465951D01*
G02X125795Y1466154I203J0D01*
G01X128615D01*
G02X128818Y1465951I0J-203D01*
G01Y1464825D01*
G03X128846Y1464722I200J-1D01*
G02Y1462760I-1642J-981D01*
G03X128818Y1462657I172J-102D01*
G01Y1459706D01*
G03X128846Y1459603I200J-1D01*
G02Y1457641I-1642J-981D01*
G03X128818Y1457538I172J-102D01*
G01Y1456413D01*
G02X128615Y1456210I-203J0D01*
G01X125795D01*
G02X125592Y1456413I0J203D01*
G01Y1457538D01*
G03X125564Y1457641I-200J1D01*
G02Y1459603I1642J981D01*
G03X125592Y1459706I-172J102D01*
G01Y1462657D01*
G03X125564Y1462760I-200J1D01*
G02Y1464722I1642J981D01*
G03X125592Y1464825I-172J102D01*
G37*
G36*
G01X142916D02*
Y1465951D01*
G02X143118Y1466154I202J1D01*
G01X145938D01*
G02X146140Y1465951I-1J-203D01*
G01Y1464825D01*
G03X146168Y1464722I200J-1D01*
G02X146440Y1463741I-1640J-983D01*
G02X146168Y1462760I-1912J2D01*
G03X146140Y1462657I172J-102D01*
G01Y1459706D01*
G03X146168Y1459603I200J-1D01*
G02X146440Y1458622I-1640J-983D01*
G02X146168Y1457641I-1912J2D01*
G03X146140Y1457538I172J-102D01*
G01Y1456413D01*
G02X145938Y1456210I-202J-1D01*
G01X143118D01*
G02X142916Y1456413I1J203D01*
G01Y1457538D01*
G03X142888Y1457641I-200J1D01*
G02X142616Y1458622I1640J983D01*
G02X142888Y1459603I1912J-2D01*
G03X142916Y1459706I-172J102D01*
G01Y1462657D01*
G03X142888Y1462760I-200J1D01*
G02X142616Y1463741I1640J983D01*
G02X142888Y1464722I1912J-2D01*
G03X142916Y1464825I-172J102D01*
G37*
G36*
G01X160238D02*
Y1465951D01*
G02X160440Y1466154I202J1D01*
G01X163260D01*
G02X163462Y1465951I-1J-203D01*
G01Y1464825D01*
G03X163490Y1464722I200J-1D01*
G02X163762Y1463741I-1640J-983D01*
G02X163490Y1462760I-1912J2D01*
G03X163462Y1462657I172J-102D01*
G01Y1459706D01*
G03X163490Y1459603I200J-1D01*
G02X163762Y1458622I-1640J-983D01*
G02X163490Y1457641I-1912J2D01*
G03X163462Y1457538I172J-102D01*
G01Y1456413D01*
G02X163260Y1456210I-202J-1D01*
G01X160440D01*
G02X160238Y1456413I1J203D01*
G01Y1457538D01*
G03X160210Y1457641I-200J1D01*
G02X159938Y1458622I1640J983D01*
G02X160210Y1459603I1912J-2D01*
G03X160238Y1459706I-172J102D01*
G01Y1462657D01*
G03X160210Y1462760I-200J1D01*
G02X159938Y1463741I1640J983D01*
G02X160210Y1464722I1912J-2D01*
G03X160238Y1464825I-172J102D01*
G37*
G36*
G01X116930Y1469155D02*
Y1470281D01*
G02X117133Y1470484I203J0D01*
G01X119953D01*
G02X120156Y1470281I0J-203D01*
G01Y1469155D01*
G03X120184Y1469052I200J-1D01*
G02Y1467090I-1642J-981D01*
G03X120156Y1466987I172J-102D01*
G01Y1464037D01*
G03X120184Y1463934I200J-1D01*
G02Y1461972I-1642J-981D01*
G03X120156Y1461869I172J-102D01*
G01Y1460743D01*
G02X119953Y1460540I-203J0D01*
G01X117133D01*
G02X116930Y1460743I0J203D01*
G01Y1461869D01*
G03X116902Y1461972I-200J1D01*
G02Y1463934I1642J981D01*
G03X116930Y1464037I-172J102D01*
G01Y1466987D01*
G03X116902Y1467090I-200J1D01*
G02Y1469052I1642J981D01*
G03X116930Y1469155I-172J102D01*
G37*
G36*
G01X134254D02*
Y1470281D01*
G02X134456Y1470484I202J1D01*
G01X137276D01*
G02X137478Y1470281I-1J-203D01*
G01Y1469155D01*
G03X137506Y1469052I200J-1D01*
G02X137778Y1468071I-1640J-983D01*
G02X137506Y1467090I-1912J2D01*
G03X137478Y1466987I172J-102D01*
G01Y1464037D01*
G03X137506Y1463934I200J-1D01*
G02X137778Y1462953I-1640J-983D01*
G02X137506Y1461972I-1912J2D01*
G03X137478Y1461869I172J-102D01*
G01Y1460743D01*
G02X137276Y1460540I-202J-1D01*
G01X134456D01*
G02X134254Y1460743I1J203D01*
G01Y1461869D01*
G03X134226Y1461972I-200J1D01*
G02X133954Y1462953I1640J983D01*
G02X134226Y1463934I1912J-2D01*
G03X134254Y1464037I-172J102D01*
G01Y1466987D01*
G03X134226Y1467090I-200J1D01*
G02X133954Y1468071I1640J983D01*
G02X134226Y1469052I1912J-2D01*
G03X134254Y1469155I-172J102D01*
G37*
G36*
G01X151576D02*
Y1470281D01*
G02X151779Y1470484I203J0D01*
G01X154599D01*
G02X154802Y1470281I0J-203D01*
G01Y1469155D01*
G03X154830Y1469052I200J-1D01*
G02Y1467090I-1642J-981D01*
G03X154802Y1466987I172J-102D01*
G01Y1464037D01*
G03X154830Y1463934I200J-1D01*
G02Y1461972I-1642J-981D01*
G03X154802Y1461869I172J-102D01*
G01Y1460743D01*
G02X154599Y1460540I-203J0D01*
G01X151779D01*
G02X151576Y1460743I0J203D01*
G01Y1461869D01*
G03X151548Y1461972I-200J1D01*
G02Y1463934I1642J981D01*
G03X151576Y1464037I-172J102D01*
G01Y1466987D01*
G03X151548Y1467090I-200J1D01*
G02Y1469052I1642J981D01*
G03X151576Y1469155I-172J102D01*
G37*
G36*
G01X168900D02*
Y1470281D01*
G02X169102Y1470484I202J1D01*
G01X171922D01*
G02X172124Y1470281I-1J-203D01*
G01Y1469155D01*
G03X172152Y1469052I200J-1D01*
G02X172424Y1468071I-1640J-983D01*
G02X172152Y1467090I-1912J2D01*
G03X172124Y1466987I172J-102D01*
G01Y1464037D01*
G03X172152Y1463934I200J-1D01*
G02X172424Y1462953I-1640J-983D01*
G02X172152Y1461972I-1912J2D01*
G03X172124Y1461869I172J-102D01*
G01Y1460743D01*
G02X171922Y1460540I-202J-1D01*
G01X169102D01*
G02X168900Y1460743I1J203D01*
G01Y1461869D01*
G03X168872Y1461972I-200J1D01*
G02X168600Y1462953I1640J983D01*
G02X168872Y1463934I1912J-2D01*
G03X168900Y1464037I-172J102D01*
G01Y1466987D01*
G03X168872Y1467090I-200J1D01*
G02X168600Y1468071I1640J983D01*
G02X168872Y1469052I1912J-2D01*
G03X168900Y1469155I-172J102D01*
G37*
G36*
G01X108270Y1480179D02*
Y1481305D01*
G02X108472Y1481508I202J1D01*
G01X111292D01*
G02X111494Y1481305I-1J-203D01*
G01Y1480179D01*
G03X111522Y1480076I200J-1D01*
G02X111794Y1479095I-1640J-983D01*
G02X111522Y1478114I-1912J2D01*
G03X111494Y1478011I172J-102D01*
G01Y1475061D01*
G03X111522Y1474958I200J-1D01*
G02X111794Y1473977I-1640J-983D01*
G02X111522Y1472996I-1912J2D01*
G03X111494Y1472893I172J-102D01*
G01Y1471767D01*
G02X111292Y1471564I-202J-1D01*
G01X108472D01*
G02X108270Y1471767I1J203D01*
G01Y1472893D01*
G03X108242Y1472996I-200J1D01*
G02X107970Y1473977I1640J983D01*
G02X108242Y1474958I1912J-2D01*
G03X108270Y1475061I-172J102D01*
G01Y1478011D01*
G03X108242Y1478114I-200J1D01*
G02X107970Y1479095I1640J983D01*
G02X108242Y1480076I1912J-2D01*
G03X108270Y1480179I-172J102D01*
G37*
G36*
G01X125592D02*
Y1481305D01*
G02X125795Y1481508I203J0D01*
G01X128615D01*
G02X128818Y1481305I0J-203D01*
G01Y1480179D01*
G03X128846Y1480076I200J-1D01*
G02Y1478114I-1642J-981D01*
G03X128818Y1478011I172J-102D01*
G01Y1475061D01*
G03X128846Y1474958I200J-1D01*
G02Y1472996I-1642J-981D01*
G03X128818Y1472893I172J-102D01*
G01Y1471767D01*
G02X128615Y1471564I-203J0D01*
G01X125795D01*
G02X125592Y1471767I0J203D01*
G01Y1472893D01*
G03X125564Y1472996I-200J1D01*
G02Y1474958I1642J981D01*
G03X125592Y1475061I-172J102D01*
G01Y1478011D01*
G03X125564Y1478114I-200J1D01*
G02Y1480076I1642J981D01*
G03X125592Y1480179I-172J102D01*
G37*
G36*
G01X142916D02*
Y1481305D01*
G02X143118Y1481508I202J1D01*
G01X145938D01*
G02X146140Y1481305I-1J-203D01*
G01Y1480179D01*
G03X146168Y1480076I200J-1D01*
G02X146440Y1479095I-1640J-983D01*
G02X146168Y1478114I-1912J2D01*
G03X146140Y1478011I172J-102D01*
G01Y1475061D01*
G03X146168Y1474958I200J-1D01*
G02X146440Y1473977I-1640J-983D01*
G02X146168Y1472996I-1912J2D01*
G03X146140Y1472893I172J-102D01*
G01Y1471767D01*
G02X145938Y1471564I-202J-1D01*
G01X143118D01*
G02X142916Y1471767I1J203D01*
G01Y1472893D01*
G03X142888Y1472996I-200J1D01*
G02X142616Y1473977I1640J983D01*
G02X142888Y1474958I1912J-2D01*
G03X142916Y1475061I-172J102D01*
G01Y1478011D01*
G03X142888Y1478114I-200J1D01*
G02X142616Y1479095I1640J983D01*
G02X142888Y1480076I1912J-2D01*
G03X142916Y1480179I-172J102D01*
G37*
G36*
G01X160238D02*
Y1481305D01*
G02X160440Y1481508I202J1D01*
G01X163260D01*
G02X163462Y1481305I-1J-203D01*
G01Y1480179D01*
G03X163490Y1480076I200J-1D01*
G02X163762Y1479095I-1640J-983D01*
G02X163490Y1478114I-1912J2D01*
G03X163462Y1478011I172J-102D01*
G01Y1475061D01*
G03X163490Y1474958I200J-1D01*
G02X163762Y1473977I-1640J-983D01*
G02X163490Y1472996I-1912J2D01*
G03X163462Y1472893I172J-102D01*
G01Y1471767D01*
G02X163260Y1471564I-202J-1D01*
G01X160440D01*
G02X160238Y1471767I1J203D01*
G01Y1472893D01*
G03X160210Y1472996I-200J1D01*
G02X159938Y1473977I1640J983D01*
G02X160210Y1474958I1912J-2D01*
G03X160238Y1475061I-172J102D01*
G01Y1478011D01*
G03X160210Y1478114I-200J1D01*
G02X159938Y1479095I1640J983D01*
G02X160210Y1480076I1912J-2D01*
G03X160238Y1480179I-172J102D01*
G37*
G36*
G01X116930Y1484510D02*
Y1485635D01*
G02X117133Y1485838I203J0D01*
G01X119953D01*
G02X120156Y1485635I0J-203D01*
G01Y1484510D01*
G03X120184Y1484407I200J-1D01*
G02Y1482445I-1642J-981D01*
G03X120156Y1482342I172J-102D01*
G01Y1479392D01*
G03X120184Y1479289I200J-1D01*
G02Y1477327I-1642J-981D01*
G03X120156Y1477224I172J-102D01*
G01Y1476097D01*
G02X119953Y1475894I-203J0D01*
G01X117133D01*
G02X116930Y1476097I0J203D01*
G01Y1477224D01*
G03X116902Y1477327I-200J1D01*
G02Y1479289I1642J981D01*
G03X116930Y1479392I-172J102D01*
G01Y1482342D01*
G03X116902Y1482445I-200J1D01*
G02Y1484407I1642J981D01*
G03X116930Y1484510I-172J102D01*
G37*
G36*
G01X134254D02*
Y1485635D01*
G02X134456Y1485838I202J1D01*
G01X137276D01*
G02X137478Y1485635I-1J-203D01*
G01Y1484510D01*
G03X137506Y1484407I200J-1D01*
G02X137778Y1483426I-1640J-983D01*
G02X137506Y1482445I-1912J2D01*
G03X137478Y1482342I172J-102D01*
G01Y1479392D01*
G03X137506Y1479289I200J-1D01*
G02X137778Y1478308I-1640J-983D01*
G02X137506Y1477327I-1912J2D01*
G03X137478Y1477224I172J-102D01*
G01Y1476097D01*
G02X137276Y1475894I-202J-1D01*
G01X134456D01*
G02X134254Y1476097I1J203D01*
G01Y1477224D01*
G03X134226Y1477327I-200J1D01*
G02X133954Y1478308I1640J983D01*
G02X134226Y1479289I1912J-2D01*
G03X134254Y1479392I-172J102D01*
G01Y1482342D01*
G03X134226Y1482445I-200J1D01*
G02X133954Y1483426I1640J983D01*
G02X134226Y1484407I1912J-2D01*
G03X134254Y1484510I-172J102D01*
G37*
G36*
G01X151576D02*
Y1485635D01*
G02X151779Y1485838I203J0D01*
G01X154599D01*
G02X154802Y1485635I0J-203D01*
G01Y1484510D01*
G03X154830Y1484407I200J-1D01*
G02Y1482445I-1642J-981D01*
G03X154802Y1482342I172J-102D01*
G01Y1479392D01*
G03X154830Y1479289I200J-1D01*
G02Y1477327I-1642J-981D01*
G03X154802Y1477224I172J-102D01*
G01Y1476097D01*
G02X154599Y1475894I-203J0D01*
G01X151779D01*
G02X151576Y1476097I0J203D01*
G01Y1477224D01*
G03X151548Y1477327I-200J1D01*
G02Y1479289I1642J981D01*
G03X151576Y1479392I-172J102D01*
G01Y1482342D01*
G03X151548Y1482445I-200J1D01*
G02Y1484407I1642J981D01*
G03X151576Y1484510I-172J102D01*
G37*
G36*
G01X168900D02*
Y1485635D01*
G02X169102Y1485838I202J1D01*
G01X171922D01*
G02X172124Y1485635I-1J-203D01*
G01Y1484510D01*
G03X172152Y1484407I200J-1D01*
G02X172424Y1483426I-1640J-983D01*
G02X172152Y1482445I-1912J2D01*
G03X172124Y1482342I172J-102D01*
G01Y1479392D01*
G03X172152Y1479289I200J-1D01*
G02X172424Y1478308I-1640J-983D01*
G02X172152Y1477327I-1912J2D01*
G03X172124Y1477224I172J-102D01*
G01Y1476097D01*
G02X171922Y1475894I-202J-1D01*
G01X169102D01*
G02X168900Y1476097I1J203D01*
G01Y1477224D01*
G03X168872Y1477327I-200J1D01*
G02X168600Y1478308I1640J983D01*
G02X168872Y1479289I1912J-2D01*
G03X168900Y1479392I-172J102D01*
G01Y1482342D01*
G03X168872Y1482445I-200J1D01*
G02X168600Y1483426I1640J983D01*
G02X168872Y1484407I1912J-2D01*
G03X168900Y1484510I-172J102D01*
G37*
G36*
G01X108270Y1495533D02*
Y1496659D01*
G02X108472Y1496862I202J1D01*
G01X111292D01*
G02X111494Y1496659I-1J-203D01*
G01Y1495533D01*
G03X111522Y1495430I200J-1D01*
G02X111794Y1494449I-1640J-983D01*
G02X111522Y1493468I-1912J2D01*
G03X111494Y1493365I172J-102D01*
G01Y1490415D01*
G03X111522Y1490312I200J-1D01*
G02X111794Y1489331I-1640J-983D01*
G02X111522Y1488350I-1912J2D01*
G03X111494Y1488247I172J-102D01*
G01Y1487121D01*
G02X111292Y1486918I-202J-1D01*
G01X108472D01*
G02X108270Y1487121I1J203D01*
G01Y1488247D01*
G03X108242Y1488350I-200J1D01*
G02X107970Y1489331I1640J983D01*
G02X108242Y1490312I1912J-2D01*
G03X108270Y1490415I-172J102D01*
G01Y1493365D01*
G03X108242Y1493468I-200J1D01*
G02X107970Y1494449I1640J983D01*
G02X108242Y1495430I1912J-2D01*
G03X108270Y1495533I-172J102D01*
G37*
G36*
G01X125592D02*
Y1496659D01*
G02X125795Y1496862I203J0D01*
G01X128615D01*
G02X128818Y1496659I0J-203D01*
G01Y1495533D01*
G03X128846Y1495430I200J-1D01*
G02Y1493468I-1642J-981D01*
G03X128818Y1493365I172J-102D01*
G01Y1490415D01*
G03X128846Y1490312I200J-1D01*
G02Y1488350I-1642J-981D01*
G03X128818Y1488247I172J-102D01*
G01Y1487121D01*
G02X128615Y1486918I-203J0D01*
G01X125795D01*
G02X125592Y1487121I0J203D01*
G01Y1488247D01*
G03X125564Y1488350I-200J1D01*
G02Y1490312I1642J981D01*
G03X125592Y1490415I-172J102D01*
G01Y1493365D01*
G03X125564Y1493468I-200J1D01*
G02Y1495430I1642J981D01*
G03X125592Y1495533I-172J102D01*
G37*
G36*
G01X142916D02*
Y1496659D01*
G02X143118Y1496862I202J1D01*
G01X145938D01*
G02X146140Y1496659I-1J-203D01*
G01Y1495533D01*
G03X146168Y1495430I200J-1D01*
G02X146440Y1494449I-1640J-983D01*
G02X146168Y1493468I-1912J2D01*
G03X146140Y1493365I172J-102D01*
G01Y1490415D01*
G03X146168Y1490312I200J-1D01*
G02X146440Y1489331I-1640J-983D01*
G02X146168Y1488350I-1912J2D01*
G03X146140Y1488247I172J-102D01*
G01Y1487121D01*
G02X145938Y1486918I-202J-1D01*
G01X143118D01*
G02X142916Y1487121I1J203D01*
G01Y1488247D01*
G03X142888Y1488350I-200J1D01*
G02X142616Y1489331I1640J983D01*
G02X142888Y1490312I1912J-2D01*
G03X142916Y1490415I-172J102D01*
G01Y1493365D01*
G03X142888Y1493468I-200J1D01*
G02X142616Y1494449I1640J983D01*
G02X142888Y1495430I1912J-2D01*
G03X142916Y1495533I-172J102D01*
G37*
G36*
G01X160238D02*
Y1496659D01*
G02X160440Y1496862I202J1D01*
G01X163260D01*
G02X163462Y1496659I-1J-203D01*
G01Y1495533D01*
G03X163490Y1495430I200J-1D01*
G02X163762Y1494449I-1640J-983D01*
G02X163490Y1493468I-1912J2D01*
G03X163462Y1493365I172J-102D01*
G01Y1490415D01*
G03X163490Y1490312I200J-1D01*
G02X163762Y1489331I-1640J-983D01*
G02X163490Y1488350I-1912J2D01*
G03X163462Y1488247I172J-102D01*
G01Y1487121D01*
G02X163260Y1486918I-202J-1D01*
G01X160440D01*
G02X160238Y1487121I1J203D01*
G01Y1488247D01*
G03X160210Y1488350I-200J1D01*
G02X159938Y1489331I1640J983D01*
G02X160210Y1490312I1912J-2D01*
G03X160238Y1490415I-172J102D01*
G01Y1493365D01*
G03X160210Y1493468I-200J1D01*
G02X159938Y1494449I1640J983D01*
G02X160210Y1495430I1912J-2D01*
G03X160238Y1495533I-172J102D01*
G37*
G36*
G01X116930Y1499864D02*
Y1500989D01*
G02X117133Y1501192I203J0D01*
G01X119953D01*
G02X120156Y1500989I0J-203D01*
G01Y1499864D01*
G03X120184Y1499761I200J-1D01*
G02Y1497799I-1642J-981D01*
G03X120156Y1497696I172J-102D01*
G01Y1494746D01*
G03X120184Y1494643I200J-1D01*
G02Y1492681I-1642J-981D01*
G03X120156Y1492578I172J-102D01*
G01Y1491451D01*
G02X119953Y1491248I-203J0D01*
G01X117133D01*
G02X116930Y1491451I0J203D01*
G01Y1492578D01*
G03X116902Y1492681I-200J1D01*
G02Y1494643I1642J981D01*
G03X116930Y1494746I-172J102D01*
G01Y1497696D01*
G03X116902Y1497799I-200J1D01*
G02Y1499761I1642J981D01*
G03X116930Y1499864I-172J102D01*
G37*
G36*
G01X134254D02*
Y1500989D01*
G02X134456Y1501192I202J1D01*
G01X137276D01*
G02X137478Y1500989I-1J-203D01*
G01Y1499864D01*
G03X137506Y1499761I200J-1D01*
G02X137778Y1498780I-1640J-983D01*
G02X137506Y1497799I-1912J2D01*
G03X137478Y1497696I172J-102D01*
G01Y1494746D01*
G03X137506Y1494643I200J-1D01*
G02X137778Y1493662I-1640J-983D01*
G02X137506Y1492681I-1912J2D01*
G03X137478Y1492578I172J-102D01*
G01Y1491451D01*
G02X137276Y1491248I-202J-1D01*
G01X134456D01*
G02X134254Y1491451I1J203D01*
G01Y1492578D01*
G03X134226Y1492681I-200J1D01*
G02X133954Y1493662I1640J983D01*
G02X134226Y1494643I1912J-2D01*
G03X134254Y1494746I-172J102D01*
G01Y1497696D01*
G03X134226Y1497799I-200J1D01*
G02X133954Y1498780I1640J983D01*
G02X134226Y1499761I1912J-2D01*
G03X134254Y1499864I-172J102D01*
G37*
G36*
G01X151576D02*
Y1500989D01*
G02X151779Y1501192I203J0D01*
G01X154599D01*
G02X154802Y1500989I0J-203D01*
G01Y1499864D01*
G03X154830Y1499761I200J-1D01*
G02Y1497799I-1642J-981D01*
G03X154802Y1497696I172J-102D01*
G01Y1494746D01*
G03X154830Y1494643I200J-1D01*
G02Y1492681I-1642J-981D01*
G03X154802Y1492578I172J-102D01*
G01Y1491451D01*
G02X154599Y1491248I-203J0D01*
G01X151779D01*
G02X151576Y1491451I0J203D01*
G01Y1492578D01*
G03X151548Y1492681I-200J1D01*
G02Y1494643I1642J981D01*
G03X151576Y1494746I-172J102D01*
G01Y1497696D01*
G03X151548Y1497799I-200J1D01*
G02Y1499761I1642J981D01*
G03X151576Y1499864I-172J102D01*
G37*
G36*
G01X168900D02*
Y1500989D01*
G02X169102Y1501192I202J1D01*
G01X171922D01*
G02X172124Y1500989I-1J-203D01*
G01Y1499864D01*
G03X172152Y1499761I200J-1D01*
G02X172424Y1498780I-1640J-983D01*
G02X172152Y1497799I-1912J2D01*
G03X172124Y1497696I172J-102D01*
G01Y1494746D01*
G03X172152Y1494643I200J-1D01*
G02X172424Y1493662I-1640J-983D01*
G02X172152Y1492681I-1912J2D01*
G03X172124Y1492578I172J-102D01*
G01Y1491451D01*
G02X171922Y1491248I-202J-1D01*
G01X169102D01*
G02X168900Y1491451I1J203D01*
G01Y1492578D01*
G03X168872Y1492681I-200J1D01*
G02X168600Y1493662I1640J983D01*
G02X168872Y1494643I1912J-2D01*
G03X168900Y1494746I-172J102D01*
G01Y1497696D01*
G03X168872Y1497799I-200J1D01*
G02X168600Y1498780I1640J983D01*
G02X168872Y1499761I1912J-2D01*
G03X168900Y1499864I-172J102D01*
G37*
G36*
G01X108270Y1510888D02*
Y1512014D01*
G02X108472Y1512216I202J0D01*
G01X111292D01*
G02X111494Y1512014I0J-202D01*
G01Y1510888D01*
G03X111522Y1510785I200J-1D01*
G02X111794Y1509804I-1640J-983D01*
G02X111522Y1508823I-1912J2D01*
G03X111494Y1508720I172J-102D01*
G01Y1505769D01*
G03X111522Y1505666I200J-1D01*
G02X111794Y1504685I-1640J-983D01*
G02X111522Y1503704I-1912J2D01*
G03X111494Y1503601I172J-102D01*
G01Y1502476D01*
G02X111292Y1502274I-202J0D01*
G01X108472D01*
G02X108270Y1502476I0J202D01*
G01Y1503601D01*
G03X108242Y1503704I-200J1D01*
G02X107970Y1504685I1640J983D01*
G02X108242Y1505666I1912J-2D01*
G03X108270Y1505769I-172J102D01*
G01Y1508720D01*
G03X108242Y1508823I-200J1D01*
G02X107970Y1509804I1640J983D01*
G02X108242Y1510785I1912J-2D01*
G03X108270Y1510888I-172J102D01*
G37*
G36*
G01X125592D02*
Y1512014D01*
G02X125795Y1512216I203J-1D01*
G01X128615D01*
G02X128818Y1512014I1J-202D01*
G01Y1510888D01*
G03X128846Y1510785I200J-1D01*
G02Y1508823I-1642J-981D01*
G03X128818Y1508720I172J-102D01*
G01Y1505769D01*
G03X128846Y1505666I200J-1D01*
G02Y1503704I-1642J-981D01*
G03X128818Y1503601I172J-102D01*
G01Y1502476D01*
G02X128615Y1502274I-203J1D01*
G01X125795D01*
G02X125592Y1502476I-1J202D01*
G01Y1503601D01*
G03X125564Y1503704I-200J1D01*
G02Y1505666I1642J981D01*
G03X125592Y1505769I-172J102D01*
G01Y1508720D01*
G03X125564Y1508823I-200J1D01*
G02Y1510785I1642J981D01*
G03X125592Y1510888I-172J102D01*
G37*
G36*
G01X142916D02*
Y1512014D01*
G02X143118Y1512216I202J0D01*
G01X145938D01*
G02X146140Y1512014I0J-202D01*
G01Y1510888D01*
G03X146168Y1510785I200J-1D01*
G02X146440Y1509804I-1640J-983D01*
G02X146168Y1508823I-1912J2D01*
G03X146140Y1508720I172J-102D01*
G01Y1505769D01*
G03X146168Y1505666I200J-1D01*
G02X146440Y1504685I-1640J-983D01*
G02X146168Y1503704I-1912J2D01*
G03X146140Y1503601I172J-102D01*
G01Y1502476D01*
G02X145938Y1502274I-202J0D01*
G01X143118D01*
G02X142916Y1502476I0J202D01*
G01Y1503601D01*
G03X142888Y1503704I-200J1D01*
G02X142616Y1504685I1640J983D01*
G02X142888Y1505666I1912J-2D01*
G03X142916Y1505769I-172J102D01*
G01Y1508720D01*
G03X142888Y1508823I-200J1D01*
G02X142616Y1509804I1640J983D01*
G02X142888Y1510785I1912J-2D01*
G03X142916Y1510888I-172J102D01*
G37*
G36*
G01X160238D02*
Y1512014D01*
G02X160440Y1512216I202J0D01*
G01X163260D01*
G02X163462Y1512014I0J-202D01*
G01Y1510888D01*
G03X163490Y1510785I200J-1D01*
G02X163762Y1509804I-1640J-983D01*
G02X163490Y1508823I-1912J2D01*
G03X163462Y1508720I172J-102D01*
G01Y1505769D01*
G03X163490Y1505666I200J-1D01*
G02X163762Y1504685I-1640J-983D01*
G02X163490Y1503704I-1912J2D01*
G03X163462Y1503601I172J-102D01*
G01Y1502476D01*
G02X163260Y1502274I-202J0D01*
G01X160440D01*
G02X160238Y1502476I0J202D01*
G01Y1503601D01*
G03X160210Y1503704I-200J1D01*
G02X159938Y1504685I1640J983D01*
G02X160210Y1505666I1912J-2D01*
G03X160238Y1505769I-172J102D01*
G01Y1508720D01*
G03X160210Y1508823I-200J1D01*
G02X159938Y1509804I1640J983D01*
G02X160210Y1510785I1912J-2D01*
G03X160238Y1510888I-172J102D01*
G37*
G36*
G01X177560D02*
Y1512014D01*
G02X177763Y1512216I203J-1D01*
G01X180583D01*
G02X180786Y1512014I1J-202D01*
G01Y1510888D01*
G03X180814Y1510785I200J-1D01*
G02Y1508823I-1642J-981D01*
G03X180786Y1508720I172J-102D01*
G01Y1505769D01*
G03X180814Y1505666I200J-1D01*
G02Y1503704I-1642J-981D01*
G03X180786Y1503601I172J-102D01*
G01Y1502476D01*
G02X180583Y1502274I-203J1D01*
G01X177763D01*
G02X177560Y1502476I-1J202D01*
G01Y1503601D01*
G03X177532Y1503704I-200J1D01*
G02Y1505666I1642J981D01*
G03X177560Y1505769I-172J102D01*
G01Y1508720D01*
G03X177532Y1508823I-200J1D01*
G02Y1510785I1642J981D01*
G03X177560Y1510888I-172J102D01*
G37*
G36*
G01X116930Y1515218D02*
Y1516344D01*
G02X117133Y1516546I203J-1D01*
G01X119953D01*
G02X120156Y1516344I1J-202D01*
G01Y1515218D01*
G03X120184Y1515115I200J-1D01*
G02Y1513153I-1642J-981D01*
G03X120156Y1513050I172J-102D01*
G01Y1510100D01*
G03X120184Y1509997I200J-1D01*
G02Y1508035I-1642J-981D01*
G03X120156Y1507932I172J-102D01*
G01Y1506806D01*
G02X119953Y1506604I-203J1D01*
G01X117133D01*
G02X116930Y1506806I-1J202D01*
G01Y1507932D01*
G03X116902Y1508035I-200J1D01*
G02Y1509997I1642J981D01*
G03X116930Y1510100I-172J102D01*
G01Y1513050D01*
G03X116902Y1513153I-200J1D01*
G02Y1515115I1642J981D01*
G03X116930Y1515218I-172J102D01*
G37*
G36*
G01X134254D02*
Y1516344D01*
G02X134456Y1516546I202J0D01*
G01X137276D01*
G02X137478Y1516344I0J-202D01*
G01Y1515218D01*
G03X137506Y1515115I200J-1D01*
G02X137778Y1514134I-1640J-983D01*
G02X137506Y1513153I-1912J2D01*
G03X137478Y1513050I172J-102D01*
G01Y1510100D01*
G03X137506Y1509997I200J-1D01*
G02X137778Y1509016I-1640J-983D01*
G02X137506Y1508035I-1912J2D01*
G03X137478Y1507932I172J-102D01*
G01Y1506806D01*
G02X137276Y1506604I-202J0D01*
G01X134456D01*
G02X134254Y1506806I0J202D01*
G01Y1507932D01*
G03X134226Y1508035I-200J1D01*
G02X133954Y1509016I1640J983D01*
G02X134226Y1509997I1912J-2D01*
G03X134254Y1510100I-172J102D01*
G01Y1513050D01*
G03X134226Y1513153I-200J1D01*
G02X133954Y1514134I1640J983D01*
G02X134226Y1515115I1912J-2D01*
G03X134254Y1515218I-172J102D01*
G37*
G36*
G01X151576D02*
Y1516344D01*
G02X151779Y1516546I203J-1D01*
G01X154599D01*
G02X154802Y1516344I1J-202D01*
G01Y1515218D01*
G03X154830Y1515115I200J-1D01*
G02Y1513153I-1642J-981D01*
G03X154802Y1513050I172J-102D01*
G01Y1510100D01*
G03X154830Y1509997I200J-1D01*
G02Y1508035I-1642J-981D01*
G03X154802Y1507932I172J-102D01*
G01Y1506806D01*
G02X154599Y1506604I-203J1D01*
G01X151779D01*
G02X151576Y1506806I-1J202D01*
G01Y1507932D01*
G03X151548Y1508035I-200J1D01*
G02Y1509997I1642J981D01*
G03X151576Y1510100I-172J102D01*
G01Y1513050D01*
G03X151548Y1513153I-200J1D01*
G02Y1515115I1642J981D01*
G03X151576Y1515218I-172J102D01*
G37*
G36*
G01X168900D02*
Y1516344D01*
G02X169102Y1516546I202J0D01*
G01X171922D01*
G02X172124Y1516344I0J-202D01*
G01Y1515218D01*
G03X172152Y1515115I200J-1D01*
G02X172424Y1514134I-1640J-983D01*
G02X172152Y1513153I-1912J2D01*
G03X172124Y1513050I172J-102D01*
G01Y1510100D01*
G03X172152Y1509997I200J-1D01*
G02X172424Y1509016I-1640J-983D01*
G02X172152Y1508035I-1912J2D01*
G03X172124Y1507932I172J-102D01*
G01Y1506806D01*
G02X171922Y1506604I-202J0D01*
G01X169102D01*
G02X168900Y1506806I0J202D01*
G01Y1507932D01*
G03X168872Y1508035I-200J1D01*
G02X168600Y1509016I1640J983D01*
G02X168872Y1509997I1912J-2D01*
G03X168900Y1510100I-172J102D01*
G01Y1513050D01*
G03X168872Y1513153I-200J1D01*
G02X168600Y1514134I1640J983D01*
G02X168872Y1515115I1912J-2D01*
G03X168900Y1515218I-172J102D01*
G37*
G36*
G01X186222D02*
Y1516344D01*
G02X186425Y1516546I203J-1D01*
G01X189245D01*
G02X189448Y1516344I1J-202D01*
G01Y1515218D01*
G03X189476Y1515115I200J-1D01*
G02Y1513153I-1642J-981D01*
G03X189448Y1513050I172J-102D01*
G01Y1510100D01*
G03X189476Y1509997I200J-1D01*
G02Y1508035I-1642J-981D01*
G03X189448Y1507932I172J-102D01*
G01Y1506806D01*
G02X189245Y1506604I-203J1D01*
G01X186425D01*
G02X186222Y1506806I-1J202D01*
G01Y1507932D01*
G03X186194Y1508035I-200J1D01*
G02Y1509997I1642J981D01*
G03X186222Y1510100I-172J102D01*
G01Y1513050D01*
G03X186194Y1513153I-200J1D01*
G02Y1515115I1642J981D01*
G03X186222Y1515218I-172J102D01*
G37*
G36*
G01X108270Y1567187D02*
Y1568313D01*
G02X108472Y1568516I202J1D01*
G01X111292D01*
G02X111494Y1568313I-1J-203D01*
G01Y1567187D01*
G03X111522Y1567084I200J-1D01*
G02X111794Y1566103I-1640J-983D01*
G02X111522Y1565122I-1912J2D01*
G03X111494Y1565019I172J-102D01*
G01Y1562069D01*
G03X111522Y1561966I200J-1D01*
G02X111794Y1560985I-1640J-983D01*
G02X111522Y1560004I-1912J2D01*
G03X111494Y1559901I172J-102D01*
G01Y1558775D01*
G02X111292Y1558572I-202J-1D01*
G01X108472D01*
G02X108270Y1558775I1J203D01*
G01Y1559901D01*
G03X108242Y1560004I-200J1D01*
G02X107970Y1560985I1640J983D01*
G02X108242Y1561966I1912J-2D01*
G03X108270Y1562069I-172J102D01*
G01Y1565019D01*
G03X108242Y1565122I-200J1D01*
G02X107970Y1566103I1640J983D01*
G02X108242Y1567084I1912J-2D01*
G03X108270Y1567187I-172J102D01*
G37*
G36*
G01X125592D02*
Y1568313D01*
G02X125795Y1568516I203J0D01*
G01X128615D01*
G02X128818Y1568313I0J-203D01*
G01Y1567187D01*
G03X128846Y1567084I200J-1D01*
G02Y1565122I-1642J-981D01*
G03X128818Y1565019I172J-102D01*
G01Y1562069D01*
G03X128846Y1561966I200J-1D01*
G02Y1560004I-1642J-981D01*
G03X128818Y1559901I172J-102D01*
G01Y1558775D01*
G02X128615Y1558572I-203J0D01*
G01X125795D01*
G02X125592Y1558775I0J203D01*
G01Y1559901D01*
G03X125564Y1560004I-200J1D01*
G02Y1561966I1642J981D01*
G03X125592Y1562069I-172J102D01*
G01Y1565019D01*
G03X125564Y1565122I-200J1D01*
G02Y1567084I1642J981D01*
G03X125592Y1567187I-172J102D01*
G37*
G36*
G01X142916D02*
Y1568313D01*
G02X143118Y1568516I202J1D01*
G01X145938D01*
G02X146140Y1568313I-1J-203D01*
G01Y1567187D01*
G03X146168Y1567084I200J-1D01*
G02X146440Y1566103I-1640J-983D01*
G02X146168Y1565122I-1912J2D01*
G03X146140Y1565019I172J-102D01*
G01Y1562069D01*
G03X146168Y1561966I200J-1D01*
G02X146440Y1560985I-1640J-983D01*
G02X146168Y1560004I-1912J2D01*
G03X146140Y1559901I172J-102D01*
G01Y1558775D01*
G02X145938Y1558572I-202J-1D01*
G01X143118D01*
G02X142916Y1558775I1J203D01*
G01Y1559901D01*
G03X142888Y1560004I-200J1D01*
G02X142616Y1560985I1640J983D01*
G02X142888Y1561966I1912J-2D01*
G03X142916Y1562069I-172J102D01*
G01Y1565019D01*
G03X142888Y1565122I-200J1D01*
G02X142616Y1566103I1640J983D01*
G02X142888Y1567084I1912J-2D01*
G03X142916Y1567187I-172J102D01*
G37*
G36*
G01X160238D02*
Y1568313D01*
G02X160440Y1568516I202J1D01*
G01X163260D01*
G02X163462Y1568313I-1J-203D01*
G01Y1567187D01*
G03X163490Y1567084I200J-1D01*
G02X163762Y1566103I-1640J-983D01*
G02X163490Y1565122I-1912J2D01*
G03X163462Y1565019I172J-102D01*
G01Y1562069D01*
G03X163490Y1561966I200J-1D01*
G02X163762Y1560985I-1640J-983D01*
G02X163490Y1560004I-1912J2D01*
G03X163462Y1559901I172J-102D01*
G01Y1558775D01*
G02X163260Y1558572I-202J-1D01*
G01X160440D01*
G02X160238Y1558775I1J203D01*
G01Y1559901D01*
G03X160210Y1560004I-200J1D01*
G02X159938Y1560985I1640J983D01*
G02X160210Y1561966I1912J-2D01*
G03X160238Y1562069I-172J102D01*
G01Y1565019D01*
G03X160210Y1565122I-200J1D01*
G02X159938Y1566103I1640J983D01*
G02X160210Y1567084I1912J-2D01*
G03X160238Y1567187I-172J102D01*
G37*
G36*
G01X177560D02*
Y1568313D01*
G02X177763Y1568516I203J0D01*
G01X180583D01*
G02X180786Y1568313I0J-203D01*
G01Y1567187D01*
G03X180814Y1567084I200J-1D01*
G02Y1565122I-1642J-981D01*
G03X180786Y1565019I172J-102D01*
G01Y1562069D01*
G03X180814Y1561966I200J-1D01*
G02Y1560004I-1642J-981D01*
G03X180786Y1559901I172J-102D01*
G01Y1558775D01*
G02X180583Y1558572I-203J0D01*
G01X177763D01*
G02X177560Y1558775I0J203D01*
G01Y1559901D01*
G03X177532Y1560004I-200J1D01*
G02Y1561966I1642J981D01*
G03X177560Y1562069I-172J102D01*
G01Y1565019D01*
G03X177532Y1565122I-200J1D01*
G02Y1567084I1642J981D01*
G03X177560Y1567187I-172J102D01*
G37*
G36*
G01X116930Y1571518D02*
Y1572644D01*
G02X117133Y1572846I203J-1D01*
G01X119953D01*
G02X120156Y1572644I1J-202D01*
G01Y1571518D01*
G03X120184Y1571415I200J-1D01*
G02Y1569453I-1642J-981D01*
G03X120156Y1569350I172J-102D01*
G01Y1566399D01*
G03X120184Y1566296I200J-1D01*
G02Y1564334I-1642J-981D01*
G03X120156Y1564231I172J-102D01*
G01Y1563106D01*
G02X119953Y1562904I-203J1D01*
G01X117133D01*
G02X116930Y1563106I-1J202D01*
G01Y1564231D01*
G03X116902Y1564334I-200J1D01*
G02Y1566296I1642J981D01*
G03X116930Y1566399I-172J102D01*
G01Y1569350D01*
G03X116902Y1569453I-200J1D01*
G02Y1571415I1642J981D01*
G03X116930Y1571518I-172J102D01*
G37*
G36*
G01X134254D02*
Y1572644D01*
G02X134456Y1572846I202J0D01*
G01X137276D01*
G02X137478Y1572644I0J-202D01*
G01Y1571518D01*
G03X137506Y1571415I200J-1D01*
G02X137778Y1570434I-1640J-983D01*
G02X137506Y1569453I-1912J2D01*
G03X137478Y1569350I172J-102D01*
G01Y1566399D01*
G03X137506Y1566296I200J-1D01*
G02X137778Y1565315I-1640J-983D01*
G02X137506Y1564334I-1912J2D01*
G03X137478Y1564231I172J-102D01*
G01Y1563106D01*
G02X137276Y1562904I-202J0D01*
G01X134456D01*
G02X134254Y1563106I0J202D01*
G01Y1564231D01*
G03X134226Y1564334I-200J1D01*
G02X133954Y1565315I1640J983D01*
G02X134226Y1566296I1912J-2D01*
G03X134254Y1566399I-172J102D01*
G01Y1569350D01*
G03X134226Y1569453I-200J1D01*
G02X133954Y1570434I1640J983D01*
G02X134226Y1571415I1912J-2D01*
G03X134254Y1571518I-172J102D01*
G37*
G36*
G01X151576D02*
Y1572644D01*
G02X151779Y1572846I203J-1D01*
G01X154599D01*
G02X154802Y1572644I1J-202D01*
G01Y1571518D01*
G03X154830Y1571415I200J-1D01*
G02Y1569453I-1642J-981D01*
G03X154802Y1569350I172J-102D01*
G01Y1566399D01*
G03X154830Y1566296I200J-1D01*
G02Y1564334I-1642J-981D01*
G03X154802Y1564231I172J-102D01*
G01Y1563106D01*
G02X154599Y1562904I-203J1D01*
G01X151779D01*
G02X151576Y1563106I-1J202D01*
G01Y1564231D01*
G03X151548Y1564334I-200J1D01*
G02Y1566296I1642J981D01*
G03X151576Y1566399I-172J102D01*
G01Y1569350D01*
G03X151548Y1569453I-200J1D01*
G02Y1571415I1642J981D01*
G03X151576Y1571518I-172J102D01*
G37*
G36*
G01X168900D02*
Y1572644D01*
G02X169102Y1572846I202J0D01*
G01X171922D01*
G02X172124Y1572644I0J-202D01*
G01Y1571518D01*
G03X172152Y1571415I200J-1D01*
G02X172424Y1570434I-1640J-983D01*
G02X172152Y1569453I-1912J2D01*
G03X172124Y1569350I172J-102D01*
G01Y1566399D01*
G03X172152Y1566296I200J-1D01*
G02X172424Y1565315I-1640J-983D01*
G02X172152Y1564334I-1912J2D01*
G03X172124Y1564231I172J-102D01*
G01Y1563106D01*
G02X171922Y1562904I-202J0D01*
G01X169102D01*
G02X168900Y1563106I0J202D01*
G01Y1564231D01*
G03X168872Y1564334I-200J1D01*
G02X168600Y1565315I1640J983D01*
G02X168872Y1566296I1912J-2D01*
G03X168900Y1566399I-172J102D01*
G01Y1569350D01*
G03X168872Y1569453I-200J1D01*
G02X168600Y1570434I1640J983D01*
G02X168872Y1571415I1912J-2D01*
G03X168900Y1571518I-172J102D01*
G37*
G36*
G01X186222D02*
Y1572644D01*
G02X186425Y1572846I203J-1D01*
G01X189245D01*
G02X189448Y1572644I1J-202D01*
G01Y1571518D01*
G03X189476Y1571415I200J-1D01*
G02Y1569453I-1642J-981D01*
G03X189448Y1569350I172J-102D01*
G01Y1566399D01*
G03X189476Y1566296I200J-1D01*
G02Y1564334I-1642J-981D01*
G03X189448Y1564231I172J-102D01*
G01Y1563106D01*
G02X189245Y1562904I-203J1D01*
G01X186425D01*
G02X186222Y1563106I-1J202D01*
G01Y1564231D01*
G03X186194Y1564334I-200J1D01*
G02Y1566296I1642J981D01*
G03X186222Y1566399I-172J102D01*
G01Y1569350D01*
G03X186194Y1569453I-200J1D01*
G02Y1571415I1642J981D01*
G03X186222Y1571518I-172J102D01*
G37*
G36*
G01X108270Y1582541D02*
Y1583667D01*
G02X108472Y1583870I202J1D01*
G01X111292D01*
G02X111494Y1583667I-1J-203D01*
G01Y1582541D01*
G03X111522Y1582438I200J-1D01*
G02X111794Y1581457I-1640J-983D01*
G02X111522Y1580476I-1912J2D01*
G03X111494Y1580373I172J-102D01*
G01Y1577423D01*
G03X111522Y1577320I200J-1D01*
G02X111794Y1576339I-1640J-983D01*
G02X111522Y1575358I-1912J2D01*
G03X111494Y1575255I172J-102D01*
G01Y1574129D01*
G02X111292Y1573926I-202J-1D01*
G01X108472D01*
G02X108270Y1574129I1J203D01*
G01Y1575255D01*
G03X108242Y1575358I-200J1D01*
G02X107970Y1576339I1640J983D01*
G02X108242Y1577320I1912J-2D01*
G03X108270Y1577423I-172J102D01*
G01Y1580373D01*
G03X108242Y1580476I-200J1D01*
G02X107970Y1581457I1640J983D01*
G02X108242Y1582438I1912J-2D01*
G03X108270Y1582541I-172J102D01*
G37*
G36*
G01X125592D02*
Y1583667D01*
G02X125795Y1583870I203J0D01*
G01X128615D01*
G02X128818Y1583667I0J-203D01*
G01Y1582541D01*
G03X128846Y1582438I200J-1D01*
G02Y1580476I-1642J-981D01*
G03X128818Y1580373I172J-102D01*
G01Y1577423D01*
G03X128846Y1577320I200J-1D01*
G02Y1575358I-1642J-981D01*
G03X128818Y1575255I172J-102D01*
G01Y1574129D01*
G02X128615Y1573926I-203J0D01*
G01X125795D01*
G02X125592Y1574129I0J203D01*
G01Y1575255D01*
G03X125564Y1575358I-200J1D01*
G02Y1577320I1642J981D01*
G03X125592Y1577423I-172J102D01*
G01Y1580373D01*
G03X125564Y1580476I-200J1D01*
G02Y1582438I1642J981D01*
G03X125592Y1582541I-172J102D01*
G37*
G36*
G01X142916D02*
Y1583667D01*
G02X143118Y1583870I202J1D01*
G01X145938D01*
G02X146140Y1583667I-1J-203D01*
G01Y1582541D01*
G03X146168Y1582438I200J-1D01*
G02X146440Y1581457I-1640J-983D01*
G02X146168Y1580476I-1912J2D01*
G03X146140Y1580373I172J-102D01*
G01Y1577423D01*
G03X146168Y1577320I200J-1D01*
G02X146440Y1576339I-1640J-983D01*
G02X146168Y1575358I-1912J2D01*
G03X146140Y1575255I172J-102D01*
G01Y1574129D01*
G02X145938Y1573926I-202J-1D01*
G01X143118D01*
G02X142916Y1574129I1J203D01*
G01Y1575255D01*
G03X142888Y1575358I-200J1D01*
G02X142616Y1576339I1640J983D01*
G02X142888Y1577320I1912J-2D01*
G03X142916Y1577423I-172J102D01*
G01Y1580373D01*
G03X142888Y1580476I-200J1D01*
G02X142616Y1581457I1640J983D01*
G02X142888Y1582438I1912J-2D01*
G03X142916Y1582541I-172J102D01*
G37*
G36*
G01X160238D02*
Y1583667D01*
G02X160440Y1583870I202J1D01*
G01X163260D01*
G02X163462Y1583667I-1J-203D01*
G01Y1582541D01*
G03X163490Y1582438I200J-1D01*
G02X163762Y1581457I-1640J-983D01*
G02X163490Y1580476I-1912J2D01*
G03X163462Y1580373I172J-102D01*
G01Y1577423D01*
G03X163490Y1577320I200J-1D01*
G02X163762Y1576339I-1640J-983D01*
G02X163490Y1575358I-1912J2D01*
G03X163462Y1575255I172J-102D01*
G01Y1574129D01*
G02X163260Y1573926I-202J-1D01*
G01X160440D01*
G02X160238Y1574129I1J203D01*
G01Y1575255D01*
G03X160210Y1575358I-200J1D01*
G02X159938Y1576339I1640J983D01*
G02X160210Y1577320I1912J-2D01*
G03X160238Y1577423I-172J102D01*
G01Y1580373D01*
G03X160210Y1580476I-200J1D01*
G02X159938Y1581457I1640J983D01*
G02X160210Y1582438I1912J-2D01*
G03X160238Y1582541I-172J102D01*
G37*
G36*
G01X177560D02*
Y1583667D01*
G02X177763Y1583870I203J0D01*
G01X180583D01*
G02X180786Y1583667I0J-203D01*
G01Y1582541D01*
G03X180814Y1582438I200J-1D01*
G02Y1580476I-1642J-981D01*
G03X180786Y1580373I172J-102D01*
G01Y1577423D01*
G03X180814Y1577320I200J-1D01*
G02Y1575358I-1642J-981D01*
G03X180786Y1575255I172J-102D01*
G01Y1574129D01*
G02X180583Y1573926I-203J0D01*
G01X177763D01*
G02X177560Y1574129I0J203D01*
G01Y1575255D01*
G03X177532Y1575358I-200J1D01*
G02Y1577320I1642J981D01*
G03X177560Y1577423I-172J102D01*
G01Y1580373D01*
G03X177532Y1580476I-200J1D01*
G02Y1582438I1642J981D01*
G03X177560Y1582541I-172J102D01*
G37*
G36*
G01X56517Y1584436D02*
X56811D01*
G03X56958Y1584501I-1J200D01*
G02X59170I1106J-1017D01*
G03X59317Y1584436I148J135D01*
G01X59611D01*
G03X59758Y1584501I-1J200D01*
G02X60864Y1584986I1106J-1019D01*
G02Y1581982I0J-1502D01*
G02X59758Y1582467I0J1504D01*
G03X59611Y1582532I-148J-135D01*
G01X59317D01*
G03X59170Y1582467I1J-200D01*
G02X56958I-1106J1017D01*
G03X56811Y1582532I-148J-135D01*
G01X56517D01*
G03X56370Y1582467I1J-200D01*
G02X55264Y1581982I-1106J1019D01*
G02Y1584986I0J1502D01*
G02X56370Y1584501I0J-1504D01*
G03X56517Y1584436I148J135D01*
G37*
G36*
G01X116930Y1586872D02*
Y1587998D01*
G02X117133Y1588200I203J-1D01*
G01X119953D01*
G02X120156Y1587998I1J-202D01*
G01Y1586872D01*
G03X120184Y1586769I200J-1D01*
G02Y1584807I-1642J-981D01*
G03X120156Y1584704I172J-102D01*
G01Y1581754D01*
G03X120184Y1581651I200J-1D01*
G02Y1579689I-1642J-981D01*
G03X120156Y1579586I172J-102D01*
G01Y1578460D01*
G02X119953Y1578258I-203J1D01*
G01X117133D01*
G02X116930Y1578460I-1J202D01*
G01Y1579586D01*
G03X116902Y1579689I-200J1D01*
G02Y1581651I1642J981D01*
G03X116930Y1581754I-172J102D01*
G01Y1584704D01*
G03X116902Y1584807I-200J1D01*
G02Y1586769I1642J981D01*
G03X116930Y1586872I-172J102D01*
G37*
G36*
G01X134254D02*
Y1587998D01*
G02X134456Y1588200I202J0D01*
G01X137276D01*
G02X137478Y1587998I0J-202D01*
G01Y1586872D01*
G03X137506Y1586769I200J-1D01*
G02X137778Y1585788I-1640J-983D01*
G02X137506Y1584807I-1912J2D01*
G03X137478Y1584704I172J-102D01*
G01Y1581754D01*
G03X137506Y1581651I200J-1D01*
G02X137778Y1580670I-1640J-983D01*
G02X137506Y1579689I-1912J2D01*
G03X137478Y1579586I172J-102D01*
G01Y1578460D01*
G02X137276Y1578258I-202J0D01*
G01X134456D01*
G02X134254Y1578460I0J202D01*
G01Y1579586D01*
G03X134226Y1579689I-200J1D01*
G02X133954Y1580670I1640J983D01*
G02X134226Y1581651I1912J-2D01*
G03X134254Y1581754I-172J102D01*
G01Y1584704D01*
G03X134226Y1584807I-200J1D01*
G02X133954Y1585788I1640J983D01*
G02X134226Y1586769I1912J-2D01*
G03X134254Y1586872I-172J102D01*
G37*
G36*
G01X151576D02*
Y1587998D01*
G02X151779Y1588200I203J-1D01*
G01X154599D01*
G02X154802Y1587998I1J-202D01*
G01Y1586872D01*
G03X154830Y1586769I200J-1D01*
G02Y1584807I-1642J-981D01*
G03X154802Y1584704I172J-102D01*
G01Y1581754D01*
G03X154830Y1581651I200J-1D01*
G02Y1579689I-1642J-981D01*
G03X154802Y1579586I172J-102D01*
G01Y1578460D01*
G02X154599Y1578258I-203J1D01*
G01X151779D01*
G02X151576Y1578460I-1J202D01*
G01Y1579586D01*
G03X151548Y1579689I-200J1D01*
G02Y1581651I1642J981D01*
G03X151576Y1581754I-172J102D01*
G01Y1584704D01*
G03X151548Y1584807I-200J1D01*
G02Y1586769I1642J981D01*
G03X151576Y1586872I-172J102D01*
G37*
G36*
G01X168900D02*
Y1587998D01*
G02X169102Y1588200I202J0D01*
G01X171922D01*
G02X172124Y1587998I0J-202D01*
G01Y1586872D01*
G03X172152Y1586769I200J-1D01*
G02X172424Y1585788I-1640J-983D01*
G02X172152Y1584807I-1912J2D01*
G03X172124Y1584704I172J-102D01*
G01Y1581754D01*
G03X172152Y1581651I200J-1D01*
G02X172424Y1580670I-1640J-983D01*
G02X172152Y1579689I-1912J2D01*
G03X172124Y1579586I172J-102D01*
G01Y1578460D01*
G02X171922Y1578258I-202J0D01*
G01X169102D01*
G02X168900Y1578460I0J202D01*
G01Y1579586D01*
G03X168872Y1579689I-200J1D01*
G02X168600Y1580670I1640J983D01*
G02X168872Y1581651I1912J-2D01*
G03X168900Y1581754I-172J102D01*
G01Y1584704D01*
G03X168872Y1584807I-200J1D01*
G02X168600Y1585788I1640J983D01*
G02X168872Y1586769I1912J-2D01*
G03X168900Y1586872I-172J102D01*
G37*
G36*
G01X108270Y1597895D02*
Y1599021D01*
G02X108472Y1599224I202J1D01*
G01X111292D01*
G02X111494Y1599021I-1J-203D01*
G01Y1597895D01*
G03X111522Y1597792I200J-1D01*
G02X111794Y1596811I-1640J-983D01*
G02X111522Y1595830I-1912J2D01*
G03X111494Y1595727I172J-102D01*
G01Y1592777D01*
G03X111522Y1592674I200J-1D01*
G02X111794Y1591693I-1640J-983D01*
G02X111522Y1590712I-1912J2D01*
G03X111494Y1590609I172J-102D01*
G01Y1589483D01*
G02X111292Y1589280I-202J-1D01*
G01X108472D01*
G02X108270Y1589483I1J203D01*
G01Y1590609D01*
G03X108242Y1590712I-200J1D01*
G02X107970Y1591693I1640J983D01*
G02X108242Y1592674I1912J-2D01*
G03X108270Y1592777I-172J102D01*
G01Y1595727D01*
G03X108242Y1595830I-200J1D01*
G02X107970Y1596811I1640J983D01*
G02X108242Y1597792I1912J-2D01*
G03X108270Y1597895I-172J102D01*
G37*
G36*
G01X125592D02*
Y1599021D01*
G02X125795Y1599224I203J0D01*
G01X128615D01*
G02X128818Y1599021I0J-203D01*
G01Y1597895D01*
G03X128846Y1597792I200J-1D01*
G02Y1595830I-1642J-981D01*
G03X128818Y1595727I172J-102D01*
G01Y1592777D01*
G03X128846Y1592674I200J-1D01*
G02Y1590712I-1642J-981D01*
G03X128818Y1590609I172J-102D01*
G01Y1589483D01*
G02X128615Y1589280I-203J0D01*
G01X125795D01*
G02X125592Y1589483I0J203D01*
G01Y1590609D01*
G03X125564Y1590712I-200J1D01*
G02Y1592674I1642J981D01*
G03X125592Y1592777I-172J102D01*
G01Y1595727D01*
G03X125564Y1595830I-200J1D01*
G02Y1597792I1642J981D01*
G03X125592Y1597895I-172J102D01*
G37*
G36*
G01X142916D02*
Y1599021D01*
G02X143118Y1599224I202J1D01*
G01X145938D01*
G02X146140Y1599021I-1J-203D01*
G01Y1597895D01*
G03X146168Y1597792I200J-1D01*
G02X146440Y1596811I-1640J-983D01*
G02X146168Y1595830I-1912J2D01*
G03X146140Y1595727I172J-102D01*
G01Y1592777D01*
G03X146168Y1592674I200J-1D01*
G02X146440Y1591693I-1640J-983D01*
G02X146168Y1590712I-1912J2D01*
G03X146140Y1590609I172J-102D01*
G01Y1589483D01*
G02X145938Y1589280I-202J-1D01*
G01X143118D01*
G02X142916Y1589483I1J203D01*
G01Y1590609D01*
G03X142888Y1590712I-200J1D01*
G02X142616Y1591693I1640J983D01*
G02X142888Y1592674I1912J-2D01*
G03X142916Y1592777I-172J102D01*
G01Y1595727D01*
G03X142888Y1595830I-200J1D01*
G02X142616Y1596811I1640J983D01*
G02X142888Y1597792I1912J-2D01*
G03X142916Y1597895I-172J102D01*
G37*
G36*
G01X160238D02*
Y1599021D01*
G02X160440Y1599224I202J1D01*
G01X163260D01*
G02X163462Y1599021I-1J-203D01*
G01Y1597895D01*
G03X163490Y1597792I200J-1D01*
G02X163762Y1596811I-1640J-983D01*
G02X163490Y1595830I-1912J2D01*
G03X163462Y1595727I172J-102D01*
G01Y1592777D01*
G03X163490Y1592674I200J-1D01*
G02X163762Y1591693I-1640J-983D01*
G02X163490Y1590712I-1912J2D01*
G03X163462Y1590609I172J-102D01*
G01Y1589483D01*
G02X163260Y1589280I-202J-1D01*
G01X160440D01*
G02X160238Y1589483I1J203D01*
G01Y1590609D01*
G03X160210Y1590712I-200J1D01*
G02X159938Y1591693I1640J983D01*
G02X160210Y1592674I1912J-2D01*
G03X160238Y1592777I-172J102D01*
G01Y1595727D01*
G03X160210Y1595830I-200J1D01*
G02X159938Y1596811I1640J983D01*
G02X160210Y1597792I1912J-2D01*
G03X160238Y1597895I-172J102D01*
G37*
G36*
G01X116930Y1602226D02*
Y1603352D01*
G02X117133Y1603554I203J-1D01*
G01X119953D01*
G02X120156Y1603352I1J-202D01*
G01Y1602226D01*
G03X120184Y1602123I200J-1D01*
G02Y1600161I-1642J-981D01*
G03X120156Y1600058I172J-102D01*
G01Y1597108D01*
G03X120184Y1597005I200J-1D01*
G02Y1595043I-1642J-981D01*
G03X120156Y1594940I172J-102D01*
G01Y1593814D01*
G02X119953Y1593612I-203J1D01*
G01X117133D01*
G02X116930Y1593814I-1J202D01*
G01Y1594940D01*
G03X116902Y1595043I-200J1D01*
G02Y1597005I1642J981D01*
G03X116930Y1597108I-172J102D01*
G01Y1600058D01*
G03X116902Y1600161I-200J1D01*
G02Y1602123I1642J981D01*
G03X116930Y1602226I-172J102D01*
G37*
G36*
G01X134254D02*
Y1603352D01*
G02X134456Y1603554I202J0D01*
G01X137276D01*
G02X137478Y1603352I0J-202D01*
G01Y1602226D01*
G03X137506Y1602123I200J-1D01*
G02X137778Y1601142I-1640J-983D01*
G02X137506Y1600161I-1912J2D01*
G03X137478Y1600058I172J-102D01*
G01Y1597108D01*
G03X137506Y1597005I200J-1D01*
G02X137778Y1596024I-1640J-983D01*
G02X137506Y1595043I-1912J2D01*
G03X137478Y1594940I172J-102D01*
G01Y1593814D01*
G02X137276Y1593612I-202J0D01*
G01X134456D01*
G02X134254Y1593814I0J202D01*
G01Y1594940D01*
G03X134226Y1595043I-200J1D01*
G02X133954Y1596024I1640J983D01*
G02X134226Y1597005I1912J-2D01*
G03X134254Y1597108I-172J102D01*
G01Y1600058D01*
G03X134226Y1600161I-200J1D01*
G02X133954Y1601142I1640J983D01*
G02X134226Y1602123I1912J-2D01*
G03X134254Y1602226I-172J102D01*
G37*
G36*
G01X151576D02*
Y1603352D01*
G02X151779Y1603554I203J-1D01*
G01X154599D01*
G02X154802Y1603352I1J-202D01*
G01Y1602226D01*
G03X154830Y1602123I200J-1D01*
G02Y1600161I-1642J-981D01*
G03X154802Y1600058I172J-102D01*
G01Y1597108D01*
G03X154830Y1597005I200J-1D01*
G02Y1595043I-1642J-981D01*
G03X154802Y1594940I172J-102D01*
G01Y1593814D01*
G02X154599Y1593612I-203J1D01*
G01X151779D01*
G02X151576Y1593814I-1J202D01*
G01Y1594940D01*
G03X151548Y1595043I-200J1D01*
G02Y1597005I1642J981D01*
G03X151576Y1597108I-172J102D01*
G01Y1600058D01*
G03X151548Y1600161I-200J1D01*
G02Y1602123I1642J981D01*
G03X151576Y1602226I-172J102D01*
G37*
G36*
G01X168900D02*
Y1603352D01*
G02X169102Y1603554I202J0D01*
G01X171922D01*
G02X172124Y1603352I0J-202D01*
G01Y1602226D01*
G03X172152Y1602123I200J-1D01*
G02X172424Y1601142I-1640J-983D01*
G02X172152Y1600161I-1912J2D01*
G03X172124Y1600058I172J-102D01*
G01Y1597108D01*
G03X172152Y1597005I200J-1D01*
G02X172424Y1596024I-1640J-983D01*
G02X172152Y1595043I-1912J2D01*
G03X172124Y1594940I172J-102D01*
G01Y1593814D01*
G02X171922Y1593612I-202J0D01*
G01X169102D01*
G02X168900Y1593814I0J202D01*
G01Y1594940D01*
G03X168872Y1595043I-200J1D01*
G02X168600Y1596024I1640J983D01*
G02X168872Y1597005I1912J-2D01*
G03X168900Y1597108I-172J102D01*
G01Y1600058D01*
G03X168872Y1600161I-200J1D01*
G02X168600Y1601142I1640J983D01*
G02X168872Y1602123I1912J-2D01*
G03X168900Y1602226I-172J102D01*
G37*
G36*
G01X186222D02*
Y1603352D01*
G02X186425Y1603554I203J-1D01*
G01X189245D01*
G02X189448Y1603352I1J-202D01*
G01Y1602226D01*
G03X189476Y1602123I200J-1D01*
G02Y1600161I-1642J-981D01*
G03X189448Y1600058I172J-102D01*
G01Y1597108D01*
G03X189476Y1597005I200J-1D01*
G02Y1595043I-1642J-981D01*
G03X189448Y1594940I172J-102D01*
G01Y1593814D01*
G02X189245Y1593612I-203J1D01*
G01X186425D01*
G02X186222Y1593814I-1J202D01*
G01Y1594940D01*
G03X186194Y1595043I-200J1D01*
G02Y1597005I1642J981D01*
G03X186222Y1597108I-172J102D01*
G01Y1600058D01*
G03X186194Y1600161I-200J1D01*
G02Y1602123I1642J981D01*
G03X186222Y1602226I-172J102D01*
G37*
G36*
G01X108270Y1613250D02*
Y1614376D01*
G02X108472Y1614578I202J0D01*
G01X111292D01*
G02X111494Y1614376I0J-202D01*
G01Y1613250D01*
G03X111522Y1613147I200J-1D01*
G02X111794Y1612166I-1640J-983D01*
G02X111522Y1611185I-1912J2D01*
G03X111494Y1611082I172J-102D01*
G01Y1608132D01*
G03X111522Y1608029I200J-1D01*
G02X111794Y1607048I-1640J-983D01*
G02X111522Y1606067I-1912J2D01*
G03X111494Y1605964I172J-102D01*
G01Y1604838D01*
G02X111292Y1604636I-202J0D01*
G01X108472D01*
G02X108270Y1604838I0J202D01*
G01Y1605964D01*
G03X108242Y1606067I-200J1D01*
G02X107970Y1607048I1640J983D01*
G02X108242Y1608029I1912J-2D01*
G03X108270Y1608132I-172J102D01*
G01Y1611082D01*
G03X108242Y1611185I-200J1D01*
G02X107970Y1612166I1640J983D01*
G02X108242Y1613147I1912J-2D01*
G03X108270Y1613250I-172J102D01*
G37*
G36*
G01X125592D02*
Y1614376D01*
G02X125795Y1614578I203J-1D01*
G01X128615D01*
G02X128818Y1614376I1J-202D01*
G01Y1613250D01*
G03X128846Y1613147I200J-1D01*
G02Y1611185I-1642J-981D01*
G03X128818Y1611082I172J-102D01*
G01Y1608132D01*
G03X128846Y1608029I200J-1D01*
G02Y1606067I-1642J-981D01*
G03X128818Y1605964I172J-102D01*
G01Y1604838D01*
G02X128615Y1604636I-203J1D01*
G01X125795D01*
G02X125592Y1604838I-1J202D01*
G01Y1605964D01*
G03X125564Y1606067I-200J1D01*
G02Y1608029I1642J981D01*
G03X125592Y1608132I-172J102D01*
G01Y1611082D01*
G03X125564Y1611185I-200J1D01*
G02Y1613147I1642J981D01*
G03X125592Y1613250I-172J102D01*
G37*
G36*
G01X142916D02*
Y1614376D01*
G02X143118Y1614578I202J0D01*
G01X145938D01*
G02X146140Y1614376I0J-202D01*
G01Y1613250D01*
G03X146168Y1613147I200J-1D01*
G02X146440Y1612166I-1640J-983D01*
G02X146168Y1611185I-1912J2D01*
G03X146140Y1611082I172J-102D01*
G01Y1608132D01*
G03X146168Y1608029I200J-1D01*
G02X146440Y1607048I-1640J-983D01*
G02X146168Y1606067I-1912J2D01*
G03X146140Y1605964I172J-102D01*
G01Y1604838D01*
G02X145938Y1604636I-202J0D01*
G01X143118D01*
G02X142916Y1604838I0J202D01*
G01Y1605964D01*
G03X142888Y1606067I-200J1D01*
G02X142616Y1607048I1640J983D01*
G02X142888Y1608029I1912J-2D01*
G03X142916Y1608132I-172J102D01*
G01Y1611082D01*
G03X142888Y1611185I-200J1D01*
G02X142616Y1612166I1640J983D01*
G02X142888Y1613147I1912J-2D01*
G03X142916Y1613250I-172J102D01*
G37*
G36*
G01X160238D02*
Y1614376D01*
G02X160440Y1614578I202J0D01*
G01X163260D01*
G02X163462Y1614376I0J-202D01*
G01Y1613250D01*
G03X163490Y1613147I200J-1D01*
G02X163762Y1612166I-1640J-983D01*
G02X163490Y1611185I-1912J2D01*
G03X163462Y1611082I172J-102D01*
G01Y1608132D01*
G03X163490Y1608029I200J-1D01*
G02X163762Y1607048I-1640J-983D01*
G02X163490Y1606067I-1912J2D01*
G03X163462Y1605964I172J-102D01*
G01Y1604838D01*
G02X163260Y1604636I-202J0D01*
G01X160440D01*
G02X160238Y1604838I0J202D01*
G01Y1605964D01*
G03X160210Y1606067I-200J1D01*
G02X159938Y1607048I1640J983D01*
G02X160210Y1608029I1912J-2D01*
G03X160238Y1608132I-172J102D01*
G01Y1611082D01*
G03X160210Y1611185I-200J1D01*
G02X159938Y1612166I1640J983D01*
G02X160210Y1613147I1912J-2D01*
G03X160238Y1613250I-172J102D01*
G37*
G36*
G01X116930Y1617580D02*
Y1618706D01*
G02X117133Y1618908I203J-1D01*
G01X119953D01*
G02X120156Y1618706I1J-202D01*
G01Y1617580D01*
G03X120184Y1617477I200J-1D01*
G02Y1615515I-1642J-981D01*
G03X120156Y1615412I172J-102D01*
G01Y1612462D01*
G03X120184Y1612359I200J-1D01*
G02Y1610397I-1642J-981D01*
G03X120156Y1610294I172J-102D01*
G01Y1609168D01*
G02X119953Y1608966I-203J1D01*
G01X117133D01*
G02X116930Y1609168I-1J202D01*
G01Y1610294D01*
G03X116902Y1610397I-200J1D01*
G02Y1612359I1642J981D01*
G03X116930Y1612462I-172J102D01*
G01Y1615412D01*
G03X116902Y1615515I-200J1D01*
G02Y1617477I1642J981D01*
G03X116930Y1617580I-172J102D01*
G37*
G36*
G01X134254D02*
Y1618706D01*
G02X134456Y1618908I202J0D01*
G01X137276D01*
G02X137478Y1618706I0J-202D01*
G01Y1617580D01*
G03X137506Y1617477I200J-1D01*
G02X137778Y1616496I-1640J-983D01*
G02X137506Y1615515I-1912J2D01*
G03X137478Y1615412I172J-102D01*
G01Y1612462D01*
G03X137506Y1612359I200J-1D01*
G02X137778Y1611378I-1640J-983D01*
G02X137506Y1610397I-1912J2D01*
G03X137478Y1610294I172J-102D01*
G01Y1609168D01*
G02X137276Y1608966I-202J0D01*
G01X134456D01*
G02X134254Y1609168I0J202D01*
G01Y1610294D01*
G03X134226Y1610397I-200J1D01*
G02X133954Y1611378I1640J983D01*
G02X134226Y1612359I1912J-2D01*
G03X134254Y1612462I-172J102D01*
G01Y1615412D01*
G03X134226Y1615515I-200J1D01*
G02X133954Y1616496I1640J983D01*
G02X134226Y1617477I1912J-2D01*
G03X134254Y1617580I-172J102D01*
G37*
G36*
G01X151576D02*
Y1618706D01*
G02X151779Y1618908I203J-1D01*
G01X154599D01*
G02X154802Y1618706I1J-202D01*
G01Y1617580D01*
G03X154830Y1617477I200J-1D01*
G02Y1615515I-1642J-981D01*
G03X154802Y1615412I172J-102D01*
G01Y1612462D01*
G03X154830Y1612359I200J-1D01*
G02Y1610397I-1642J-981D01*
G03X154802Y1610294I172J-102D01*
G01Y1609168D01*
G02X154599Y1608966I-203J1D01*
G01X151779D01*
G02X151576Y1609168I-1J202D01*
G01Y1610294D01*
G03X151548Y1610397I-200J1D01*
G02Y1612359I1642J981D01*
G03X151576Y1612462I-172J102D01*
G01Y1615412D01*
G03X151548Y1615515I-200J1D01*
G02Y1617477I1642J981D01*
G03X151576Y1617580I-172J102D01*
G37*
G36*
G01X168900D02*
Y1618706D01*
G02X169102Y1618908I202J0D01*
G01X171922D01*
G02X172124Y1618706I0J-202D01*
G01Y1617580D01*
G03X172152Y1617477I200J-1D01*
G02X172424Y1616496I-1640J-983D01*
G02X172152Y1615515I-1912J2D01*
G03X172124Y1615412I172J-102D01*
G01Y1612462D01*
G03X172152Y1612359I200J-1D01*
G02X172424Y1611378I-1640J-983D01*
G02X172152Y1610397I-1912J2D01*
G03X172124Y1610294I172J-102D01*
G01Y1609168D01*
G02X171922Y1608966I-202J0D01*
G01X169102D01*
G02X168900Y1609168I0J202D01*
G01Y1610294D01*
G03X168872Y1610397I-200J1D01*
G02X168600Y1611378I1640J983D01*
G02X168872Y1612359I1912J-2D01*
G03X168900Y1612462I-172J102D01*
G01Y1615412D01*
G03X168872Y1615515I-200J1D01*
G02X168600Y1616496I1640J983D01*
G02X168872Y1617477I1912J-2D01*
G03X168900Y1617580I-172J102D01*
G37*
G36*
G01X186222D02*
Y1618706D01*
G02X186425Y1618908I203J-1D01*
G01X189245D01*
G02X189448Y1618706I1J-202D01*
G01Y1617580D01*
G03X189476Y1617477I200J-1D01*
G02Y1615515I-1642J-981D01*
G03X189448Y1615412I172J-102D01*
G01Y1612462D01*
G03X189476Y1612359I200J-1D01*
G02Y1610397I-1642J-981D01*
G03X189448Y1610294I172J-102D01*
G01Y1609168D01*
G02X189245Y1608966I-203J1D01*
G01X186425D01*
G02X186222Y1609168I-1J202D01*
G01Y1610294D01*
G03X186194Y1610397I-200J1D01*
G02Y1612359I1642J981D01*
G03X186222Y1612462I-172J102D01*
G01Y1615412D01*
G03X186194Y1615515I-200J1D01*
G02Y1617477I1642J981D01*
G03X186222Y1617580I-172J102D01*
G37*
G36*
G01X29030Y1440464D02*
G02X28378Y1441702I849J1238D01*
G02X31382I1502J0D01*
G02X30714Y1440453I-1502J0D01*
G03X30710Y1439790I222J-333D01*
G02X31362Y1438552I-849J-1238D01*
G02X28358I-1502J0D01*
G02X29026Y1439801I1502J0D01*
G03X29030Y1440464I-222J333D01*
G37*
G36*
G01X49249Y839220D02*
G02X50473Y838588I0J-1501D01*
G03X50636Y838504I163J116D01*
G01X50962D01*
G03X51125Y838588I0J200D01*
G02X52349Y839220I1224J-869D01*
G02Y836216I0J-1502D01*
G02X51125Y836848I0J1501D01*
G03X50962Y836932I-163J-116D01*
G01X50636D01*
G03X50473Y836848I0J-200D01*
G02X49249Y836216I-1224J869D01*
G02X47986Y836906I0J1501D01*
G03X47817Y836998I-168J-108D01*
G01X47481D01*
G03X47312Y836906I-1J-200D01*
G02X46049Y836216I-1263J811D01*
G02Y839220I0J1502D01*
G02X47312Y838530I0J-1501D01*
G03X47481Y838438I168J108D01*
G01X47817D01*
G03X47986Y838530I1J200D01*
G02X49249Y839220I1263J-811D01*
G37*
G36*
G01X92897Y656857D02*
G02Y659861I0J1502D01*
G02X94085Y659278I0J-1502D01*
G01X94113Y659241D01*
X94197Y659200D01*
X94562Y659202D01*
G03X94720Y659280I-1J200D01*
G01Y659281D01*
G02X95917Y659876I1197J-907D01*
G02X97419Y658374I0J-1502D01*
G02X96991Y657324I-1502J0D01*
G01X96962Y657295D01*
X96933Y657221D01*
X96940Y656894D01*
G03X97002Y656754I200J5D01*
G01X97003Y656753D01*
G02X97475Y655660I-1030J-1093D01*
G02X94471I-1502J0D01*
G02X94899Y656710I1502J0D01*
G01X94928Y656739D01*
X94957Y656813D01*
X94950Y657140D01*
G03X94888Y657280I-200J-5D01*
G01X94887Y657281D01*
G02X94729Y657455I1030J1094D01*
G01X94701Y657492D01*
X94617Y657533D01*
X94252Y657531D01*
G03X94094Y657453I1J-200D01*
G01Y657452D01*
G02X92897Y656857I-1197J907D01*
G37*
G36*
G01X54554Y619590D02*
G02X53992Y620661I739J1071D01*
G02X56596I1302J0D01*
G02X56034Y619590I-1301J0D01*
G03Y618932I228J-329D01*
G02X56596Y617861I-739J-1071D01*
G02X53992I-1302J0D01*
G02X54554Y618932I1301J0D01*
G03Y619590I-228J329D01*
G37*
G36*
G01X51010D02*
G02X50448Y620661I739J1071D01*
G02X53052I1302J0D01*
G02X52490Y619590I-1301J0D01*
G03Y618932I228J-329D01*
G02X53052Y617861I-739J-1071D01*
G02X50448I-1302J0D01*
G02X51010Y618932I1301J0D01*
G03Y619590I-228J329D01*
G37*
G36*
G01X47467D02*
G02X46905Y620661I739J1071D01*
G02X49509I1302J0D01*
G02X48947Y619590I-1301J0D01*
G03Y618932I228J-329D01*
G02X49509Y617861I-739J-1071D01*
G02X46905I-1302J0D01*
G02X47467Y618932I1301J0D01*
G03Y619590I-228J329D01*
G37*
G36*
G01X43924D02*
G02X43362Y620661I739J1071D01*
G02X45966I1302J0D01*
G02X45404Y619590I-1301J0D01*
G03Y618932I228J-329D01*
G02X45966Y617861I-739J-1071D01*
G02X43362I-1302J0D01*
G02X43924Y618932I1301J0D01*
G03Y619590I-228J329D01*
G37*
G36*
G01X73838Y576484D02*
G02X76842I1502J0D01*
G02X76200Y575253I-1501J0D01*
G03X76116Y575114I114J-164D01*
G01X76073Y574778D01*
X76097Y574697D01*
X76125Y574665D01*
G02X76485Y573689I-1143J-976D01*
G02X75764Y572406I-1502J0D01*
G01X75720Y572379D01*
X75669Y572291D01*
X75661Y571849D01*
X75708Y571759D01*
X75751Y571731D01*
G02X76425Y570478I-828J-1253D01*
G02X74923Y568976I-1502J0D01*
G02X73744Y569547I0J1503D01*
G01X73718Y569580D01*
X73644Y569619D01*
X73265Y569648D01*
X73187Y569620D01*
X73156Y569591D01*
G02X72128Y569184I-1028J1095D01*
G02X70626Y570686I0J1502D01*
G02X71127Y571806I1502J0D01*
G01X71156Y571831D01*
X71190Y571901D01*
X71215Y572215D01*
G03X71171Y572356I-199J15D01*
G02X70835Y573303I1167J947D01*
G02X72337Y574805I1502J0D01*
G02X73228Y574512I0J-1501D01*
G01X73229D01*
X73260Y574489D01*
X73336Y574470D01*
X73692Y574522D01*
X73761Y574563D01*
X73784Y574594D01*
G02X74123Y574920I1198J-906D01*
G03X74207Y575059I-114J164D01*
G01X74250Y575395D01*
X74226Y575476D01*
X74198Y575508D01*
G02X73838Y576484I1143J976D01*
G37*
G36*
G01X62583Y545847D02*
X62877D01*
G03X63024Y545912I-1J200D01*
G02X64130Y546397I1106J-1019D01*
G02X65632Y544895I0J-1502D01*
G02X65053Y543710I-1502J0D01*
G03X64976Y543552I123J-158D01*
G01Y543238D01*
G03X65053Y543080I200J0D01*
G02X65632Y541895I-923J-1185D01*
G02X64130Y540393I-1502J0D01*
G02X63143Y540763I0J1501D01*
G01X63142D01*
Y540764D01*
G03X63012Y540812I-130J-152D01*
G01X62748D01*
G03X62618Y540764I0J-200D01*
G01X62617Y540763D01*
G02X61630Y540393I-987J1131D01*
G02X60128Y541895I0J1502D01*
G02X60600Y542988I1502J0D01*
G01X60601Y542989D01*
G03X60662Y543154I-138J145D01*
G01X60631Y543469D01*
G03X60537Y543619I-199J-20D01*
G02X59828Y544895I794J1276D01*
G02X61330Y546397I1502J0D01*
G02X62436Y545912I0J-1504D01*
G03X62583Y545847I148J135D01*
G37*
G36*
G01X38358Y530446D02*
G02Y533450I0J1502D01*
G02X39582Y532819I0J-1503D01*
G01X39609Y532780D01*
X39693Y532736D01*
X40061Y532728D01*
G03X40223Y532805I4J200D01*
G02X41408Y533384I1185J-923D01*
G02X42395Y533014I0J-1501D01*
G01X42396D01*
Y533013D01*
G03X42526Y532965I130J152D01*
G01X42790D01*
G03X42920Y533013I0J200D01*
G01X42921Y533014D01*
G02X44895I987J-1131D01*
G01X44896D01*
Y533013D01*
G03X45026Y532965I130J152D01*
G01X45290D01*
G03X45420Y533013I0J200D01*
G01X45421Y533014D01*
G02X46408Y533384I987J-1131D01*
G02X47910Y531882I0J-1502D01*
G02X47643Y531027I-1502J0D01*
G01X47620Y530993D01*
X47603Y530912D01*
X47683Y530545D01*
X47731Y530478D01*
X47766Y530457D01*
G02X48495Y529169I-773J-1288D01*
G02X45491I-1502J0D01*
G02X45758Y530024I1502J0D01*
G01X45781Y530058D01*
X45798Y530139D01*
X45718Y530506D01*
X45670Y530573D01*
X45635Y530594D01*
G02X45422Y530750I777J1285D01*
G03X45420Y530751I-88J-173D01*
G03X45290Y530799I-130J-152D01*
G01X45026D01*
G03X44896Y530751I0J-200D01*
G01X44895Y530750D01*
G02X42921I-987J1131D01*
G01X42920D01*
Y530751D01*
G03X42790Y530799I-130J-152D01*
G01X42526D01*
G03X42396Y530751I0J-200D01*
G01X42395Y530750D01*
G02X41408Y530380I-987J1131D01*
G02X40184Y531011I0J1503D01*
G01X40157Y531050D01*
X40073Y531094D01*
X39705Y531102D01*
G03X39543Y531025I-4J-200D01*
G02X38358Y530446I-1185J923D01*
G37*
G36*
G01X1756556Y485889D02*
G02X1756393Y485880I-164J1493D01*
G01X1756391D01*
G02X1757893Y487382I0J1502D01*
G01Y487381D01*
G02X1757814Y486901I-1502J1D01*
G03X1758236Y486375I379J-128D01*
G02X1758399Y486384I164J-1493D01*
G01X1758401D01*
G02X1756899Y484882I0J-1502D01*
G01Y484883D01*
G02X1756978Y485363I1502J-1D01*
G03X1756556Y485889I-379J128D01*
G37*
G36*
G01X56722Y465004D02*
G02X59726I1502J0D01*
G02X58367Y463509I-1502J0D01*
G03X58213Y463411I19J-199D01*
G01X58050Y463131D01*
G03X58040Y462948I173J-101D01*
G02X58169Y462339I-1373J-609D01*
G02X57799Y461352I-1501J0D01*
G01Y461351D01*
X57798D01*
G03X57750Y461221I152J-130D01*
G01Y460957D01*
G03X57798Y460827I200J0D01*
G01X57799Y460826D01*
G02Y458852I-1131J-987D01*
G01Y458851D01*
X57798D01*
G03X57750Y458721I152J-130D01*
G01Y458457D01*
G03X57798Y458327I200J0D01*
G01X57799Y458326D01*
G02X58169Y457339I-1131J-987D01*
G02X56667Y455837I-1502J0D01*
G02X55680Y456207I0J1501D01*
G01X55679D01*
Y456208D01*
G03X55549Y456256I-130J-152D01*
G01X55285D01*
G03X55155Y456208I0J-200D01*
G01X55154Y456207D01*
G02X54167Y455837I-987J1131D01*
G02X52665Y457339I0J1502D01*
G02X53035Y458326I1501J0D01*
G01Y458327D01*
X53036D01*
G03X53084Y458457I-152J130D01*
G01Y458721D01*
G03X53036Y458851I-200J0D01*
G01X53035Y458852D01*
G02Y460826I1131J987D01*
G01Y460827D01*
X53036D01*
G03X53084Y460957I-152J130D01*
G01Y461221D01*
G03X53036Y461351I-200J0D01*
G01X53035Y461352D01*
G02X52665Y462339I1131J987D01*
G02X54167Y463841I1502J0D01*
G02X55154Y463471I0J-1501D01*
G01X55155D01*
Y463470D01*
G03X55285Y463422I130J152D01*
G01X55549D01*
G03X55679Y463470I0J200D01*
G01X55680Y463471D01*
G02X56524Y463834I987J-1132D01*
G03X56678Y463932I-19J199D01*
G01X56841Y464212D01*
G03X56851Y464395I-173J101D01*
G02X56722Y465004I1373J609D01*
G37*
G36*
G01X1731357Y450937D02*
X1731671D01*
G03X1731829Y451014I0J200D01*
G02X1733014Y451593I1185J-923D01*
G02Y448589I0J-1502D01*
G02X1731829Y449168I0J1502D01*
G03X1731671Y449245I-158J-123D01*
G01X1731356D01*
G03X1731199Y449168I1J-200D01*
G02X1731127Y449083I-1181J928D01*
G01X1731097Y449050D01*
X1731071Y448966D01*
X1731119Y448619D01*
G03X1731209Y448477I198J26D01*
G02X1731906Y447209I-805J-1268D01*
G02X1730404Y445707I-1502J0D01*
G02X1729219Y446286I0J1502D01*
G03X1729061Y446363I-158J-123D01*
G01X1728747D01*
G03X1728589Y446286I0J-200D01*
G02X1727404Y445707I-1185J923D01*
G02X1725902Y447209I0J1502D01*
G01Y447229D01*
G03X1725821Y447392I-200J2D01*
G01X1725521Y447614D01*
X1725427Y447629D01*
X1725380Y447614D01*
G02X1724924Y447543I-456J1431D01*
G01X1724923D01*
G02X1726425Y449045I0J1502D01*
G01Y449025D01*
G03X1726506Y448862I200J-2D01*
G01X1726806Y448640D01*
X1726900Y448625D01*
X1726947Y448640D01*
G02X1727403Y448711I456J-1431D01*
G01X1727404D01*
G02X1728589Y448132I0J-1502D01*
G03X1728747Y448055I158J123D01*
G01X1729062D01*
G03X1729219Y448132I-1J200D01*
G02X1729291Y448217I1181J-928D01*
G01X1729321Y448250D01*
X1729347Y448334D01*
X1729299Y448681D01*
G03X1729209Y448823I-198J-26D01*
G02X1728512Y450091I805J1268D01*
G02X1730014Y451593I1502J0D01*
G02X1731199Y451014I0J-1502D01*
G03X1731357Y450937I158J123D01*
G37*
G36*
G01X1794554Y443889D02*
G02X1793483Y443327I-1071J739D01*
G02Y445931I0J1302D01*
G02X1794554Y445369I0J-1301D01*
G03X1795212I329J228D01*
G02X1796283Y445931I1071J-739D01*
G02Y443327I0J-1302D01*
G02X1795212Y443889I0J1301D01*
G03X1794554I-329J-228D01*
G37*
G36*
G01Y440346D02*
G02X1793483Y439784I-1071J739D01*
G02Y442388I0J1302D01*
G02X1794554Y441826I0J-1301D01*
G03X1795212I329J228D01*
G02X1796283Y442388I1071J-739D01*
G02Y439784I0J-1302D01*
G02X1795212Y440346I0J1301D01*
G03X1794554I-329J-228D01*
G37*
G36*
G01Y436803D02*
G02X1793483Y436241I-1071J739D01*
G02Y438845I0J1302D01*
G02X1794554Y438283I0J-1301D01*
G03X1795212I329J228D01*
G02X1796283Y438845I1071J-739D01*
G02Y436241I0J-1302D01*
G02X1795212Y436803I0J1301D01*
G03X1794554I-329J-228D01*
G37*
G36*
G01Y433259D02*
G02X1793483Y432697I-1071J739D01*
G02Y435301I0J1302D01*
G02X1794554Y434739I0J-1301D01*
G03X1795212I329J228D01*
G02X1796283Y435301I1071J-739D01*
G02Y432697I0J-1302D01*
G02X1795212Y433259I0J1301D01*
G03X1794554I-329J-228D01*
G37*
G36*
G01X1751530Y410385D02*
X1751844D01*
G03X1752002Y410462I0J200D01*
G02X1753187Y411041I1185J-923D01*
G02X1754689Y409539I0J-1502D01*
G02X1754319Y408552I-1501J0D01*
G01Y408551D01*
X1754318D01*
G03X1754270Y408421I152J-130D01*
G01Y408157D01*
G03X1754318Y408027I200J0D01*
G01X1754319Y408026D01*
G02X1754689Y407039I-1131J-987D01*
G02X1753187Y405537I-1502J0D01*
G02X1752094Y406009I0J1502D01*
G01X1752093Y406010D01*
G03X1751928Y406071I-145J-138D01*
G01X1751613Y406040D01*
G03X1751463Y405946I20J-199D01*
G02X1750187Y405237I-1276J794D01*
G02X1748685Y406739I0J1502D01*
G02X1749170Y407845I1504J0D01*
G03X1749235Y407992I-135J148D01*
G01Y408286D01*
G03X1749170Y408433I-200J-1D01*
G02X1748685Y409539I1019J1106D01*
G02X1750187Y411041I1502J0D01*
G02X1751372Y410462I0J-1502D01*
G03X1751530Y410385I158J123D01*
G37*
G36*
G01X1764004Y379426D02*
G02X1763995Y379589I1493J164D01*
G01Y379591D01*
G02X1765497Y378089I1502J0D01*
G01X1765496D01*
G02X1765016Y378168I1J1502D01*
G03X1764490Y377746I-128J-379D01*
G02X1764499Y377583I-1493J-164D01*
G01Y377581D01*
G02X1762997Y379083I-1502J0D01*
G01X1762998D01*
G02X1763478Y379004I-1J-1502D01*
G03X1764004Y379426I128J379D01*
G37*
G36*
G01X308952Y355373D02*
G02Y358377I0J1502D01*
G02X310307Y357523I0J-1502D01*
G01X310331Y357473D01*
X310424Y357412D01*
X310890Y357394D01*
X310986Y357447D01*
X311014Y357496D01*
G02X312316Y358249I1302J-749D01*
G02X313509Y357660I0J-1503D01*
G01X313537Y357623D01*
X313619Y357581D01*
X313981Y357577D01*
G03X314139Y357652I2J200D01*
G02X315310Y358214I1171J-939D01*
G02X316619Y357449I0J-1502D01*
G01X316644Y357405D01*
X316730Y357351D01*
X317117Y357327D01*
G03X317290Y357407I13J200D01*
G01Y357408D01*
G02X318500Y358021I1210J-888D01*
G02X320002Y356519I0J-1502D01*
G02X318759Y355040I-1501J0D01*
G01X318758D01*
G03X318607Y354914I36J-197D01*
G01X318484Y354593D01*
G03X318513Y354399I187J-71D01*
G01X318514Y354398D01*
G02X318835Y353470I-1181J-928D01*
G02X315831I-1502J0D01*
G02X317074Y354949I1501J0D01*
G01X317075D01*
G03X317226Y355075I-36J197D01*
G01X317349Y355396D01*
G03X317320Y355590I-187J71D01*
G01X317319Y355591D01*
G02X317191Y355782I1180J929D01*
G01X317166Y355826D01*
X317080Y355880D01*
X316693Y355904D01*
G03X316520Y355824I-13J-200D01*
G01Y355823D01*
G02X315310Y355210I-1210J888D01*
G02X314117Y355799I0J1503D01*
G01X314089Y355836D01*
X314007Y355878D01*
X313645Y355882D01*
G03X313487Y355807I-2J-200D01*
G02X312316Y355245I-1171J939D01*
G02X310961Y356099I0J1502D01*
G01X310937Y356149D01*
X310844Y356210D01*
X310378Y356228D01*
X310282Y356175D01*
X310254Y356126D01*
G02X308952Y355373I-1302J749D01*
G37*
G36*
G01X1665010Y352646D02*
G02X1663650Y351781I-1360J637D01*
G02Y354785I0J1502D01*
G02X1664825Y354219I0J-1503D01*
G03X1665500Y354298I313J249D01*
G02X1666860Y355163I1360J-637D01*
G02Y352159I0J-1502D01*
G02X1665685Y352725I0J1503D01*
G03X1665010Y352646I-313J-249D01*
G37*
G36*
G01X1685415Y313706D02*
G02X1684837Y314890I924J1184D01*
G02X1687841I1502J0D01*
G02X1687086Y313587I-1502J0D01*
G03X1687039Y312924I199J-347D01*
G02X1687617Y311740I-924J-1184D01*
G02X1684613I-1502J0D01*
G02X1685368Y313043I1502J0D01*
G03X1685415Y313706I-199J347D01*
G37*
G36*
G01X314155D02*
G02X313577Y314890I924J1184D01*
G02X316581I1502J0D01*
G02X315826Y313587I-1502J0D01*
G03X315779Y312924I199J-347D01*
G02X316357Y311740I-924J-1184D01*
G02X313353I-1502J0D01*
G02X314108Y313043I1502J0D01*
G03X314155Y313706I-199J347D01*
G37*
G36*
G01X918776Y270384D02*
G02X918075Y271654I800J1270D01*
G02X921079I1502J0D01*
G02X920409Y270404I-1501J0D01*
G03X920417Y269732I221J-333D01*
G02X921118Y268462I-800J-1270D01*
G02X918114I-1502J0D01*
G02X918784Y269712I1501J0D01*
G03X918776Y270384I-221J333D01*
G37*
G36*
G01X1710395Y245418D02*
G02X1710028Y245372I-369J1456D01*
G02X1711530Y246874I0J1502D01*
G02X1711414Y246295I-1503J0D01*
G03X1711881Y245753I369J-154D01*
G02X1712248Y245799I369J-1456D01*
G02X1710746Y244297I0J-1502D01*
G02X1710862Y244876I1503J0D01*
G03X1710395Y245418I-369J154D01*
G37*
G36*
G01X1608033D02*
G02X1607666Y245372I-369J1456D01*
G02X1609168Y246874I0J1502D01*
G02X1609052Y246295I-1503J0D01*
G03X1609519Y245753I369J-154D01*
G02X1609886Y245799I369J-1456D01*
G02X1608384Y244297I0J-1502D01*
G02X1608500Y244876I1503J0D01*
G03X1608033Y245418I-369J154D01*
G37*
G36*
G01X1505671D02*
G02X1505304Y245372I-369J1456D01*
G02X1506806Y246874I0J1502D01*
G02X1506690Y246295I-1503J0D01*
G03X1507157Y245753I369J-154D01*
G02X1507524Y245799I369J-1456D01*
G02X1506022Y244297I0J-1502D01*
G02X1506138Y244876I1503J0D01*
G03X1505671Y245418I-369J154D01*
G37*
G36*
G01X1403309D02*
G02X1402942Y245372I-369J1456D01*
G02X1404444Y246874I0J1502D01*
G02X1404328Y246295I-1503J0D01*
G03X1404795Y245753I369J-154D01*
G02X1405162Y245799I369J-1456D01*
G02X1403660Y244297I0J-1502D01*
G02X1403776Y244876I1503J0D01*
G03X1403309Y245418I-369J154D01*
G37*
G36*
G01X1253308D02*
G02X1252941Y245372I-369J1456D01*
G02X1254443Y246874I0J1502D01*
G02X1254327Y246295I-1503J0D01*
G03X1254794Y245753I369J-154D01*
G02X1255161Y245799I369J-1456D01*
G02X1253659Y244297I0J-1502D01*
G02X1253775Y244876I1503J0D01*
G03X1253308Y245418I-369J154D01*
G37*
G36*
G01X1150946D02*
G02X1150579Y245372I-369J1456D01*
G02X1152081Y246874I0J1502D01*
G02X1151965Y246295I-1503J0D01*
G03X1152432Y245753I369J-154D01*
G02X1152799Y245799I369J-1456D01*
G02X1151297Y244297I0J-1502D01*
G02X1151413Y244876I1503J0D01*
G03X1150946Y245418I-369J154D01*
G37*
G36*
G01X1048584D02*
G02X1048217Y245372I-369J1456D01*
G02X1049719Y246874I0J1502D01*
G02X1049603Y246295I-1503J0D01*
G03X1050070Y245753I369J-154D01*
G02X1050437Y245799I369J-1456D01*
G02X1048935Y244297I0J-1502D01*
G02X1049051Y244876I1503J0D01*
G03X1048584Y245418I-369J154D01*
G37*
G36*
G01X796222D02*
G02X795855Y245372I-369J1456D01*
G02X797357Y246874I0J1502D01*
G02X797241Y246295I-1503J0D01*
G03X797708Y245753I369J-154D01*
G02X798075Y245799I369J-1456D01*
G02X796573Y244297I0J-1502D01*
G02X796689Y244876I1503J0D01*
G03X796222Y245418I-369J154D01*
G37*
G36*
G01X693860D02*
G02X693493Y245372I-369J1456D01*
G02X694995Y246874I0J1502D01*
G02X694879Y246295I-1503J0D01*
G03X695346Y245753I369J-154D01*
G02X695713Y245799I369J-1456D01*
G02X694211Y244297I0J-1502D01*
G02X694327Y244876I1503J0D01*
G03X693860Y245418I-369J154D01*
G37*
G36*
G01X591498D02*
G02X591131Y245372I-369J1456D01*
G02X592633Y246874I0J1502D01*
G02X592517Y246295I-1503J0D01*
G03X592984Y245753I369J-154D01*
G02X593351Y245799I369J-1456D01*
G02X591849Y244297I0J-1502D01*
G02X591965Y244876I1503J0D01*
G03X591498Y245418I-369J154D01*
G37*
G36*
G01X489136D02*
G02X488769Y245372I-369J1456D01*
G02X490271Y246874I0J1502D01*
G02X490155Y246295I-1503J0D01*
G03X490622Y245753I369J-154D01*
G02X490989Y245799I369J-1456D01*
G02X489487Y244297I0J-1502D01*
G02X489603Y244876I1503J0D01*
G03X489136Y245418I-369J154D01*
G37*
G36*
G01X339135D02*
G02X338768Y245372I-369J1456D01*
G02X340270Y246874I0J1502D01*
G02X340154Y246295I-1503J0D01*
G03X340621Y245753I369J-154D01*
G02X340988Y245799I369J-1456D01*
G02X339486Y244297I0J-1502D01*
G02X339602Y244876I1503J0D01*
G03X339135Y245418I-369J154D01*
G37*
G36*
G01X236773D02*
G02X236406Y245372I-369J1456D01*
G02X237908Y246874I0J1502D01*
G02X237792Y246295I-1503J0D01*
G03X238259Y245753I369J-154D01*
G02X238626Y245799I369J-1456D01*
G02X237124Y244297I0J-1502D01*
G02X237240Y244876I1503J0D01*
G03X236773Y245418I-369J154D01*
G37*
G36*
G01X32049D02*
G02X31682Y245372I-369J1456D01*
G02X33184Y246874I0J1502D01*
G02X33068Y246295I-1503J0D01*
G03X33535Y245753I369J-154D01*
G02X33902Y245799I369J-1456D01*
G02X32400Y244297I0J-1502D01*
G02X32516Y244876I1503J0D01*
G03X32049Y245418I-369J154D01*
G37*
G36*
G01X1750107Y213197D02*
G02X1751609Y211695I0J-1502D01*
G02X1751137Y210602I-1502J0D01*
G01X1751136Y210601D01*
G03X1751075Y210436I138J-145D01*
G01X1751106Y210121D01*
G03X1751200Y209971I199J20D01*
G02X1751909Y208695I-794J-1276D01*
G02X1750407Y207193I-1502J0D01*
G02X1749301Y207678I0J1504D01*
G03X1749154Y207743I-148J-135D01*
G01X1748860D01*
G03X1748713Y207678I1J-200D01*
G02X1747607Y207193I-1106J1019D01*
G02X1746105Y208695I0J1502D01*
G02X1746684Y209880I1502J0D01*
G03X1746761Y210038I-123J158D01*
G01Y210352D01*
G03X1746684Y210510I-200J0D01*
G02X1746105Y211695I923J1185D01*
G02X1747607Y213197I1502J0D01*
G02X1748594Y212827I0J-1501D01*
G01X1748595D01*
Y212826D01*
G03X1748725Y212778I130J152D01*
G01X1748989D01*
G03X1749119Y212826I0J200D01*
G01X1749120Y212827D01*
G02X1750107Y213197I987J-1131D01*
G37*
G36*
G01X1647745D02*
G02X1649247Y211695I0J-1502D01*
G02X1648775Y210602I-1502J0D01*
G01X1648774Y210601D01*
G03X1648713Y210436I138J-145D01*
G01X1648744Y210121D01*
G03X1648838Y209971I199J20D01*
G02X1649547Y208695I-794J-1276D01*
G02X1648045Y207193I-1502J0D01*
G02X1646939Y207678I0J1504D01*
G03X1646792Y207743I-148J-135D01*
G01X1646498D01*
G03X1646351Y207678I1J-200D01*
G02X1645245Y207193I-1106J1019D01*
G02X1643743Y208695I0J1502D01*
G02X1644322Y209880I1502J0D01*
G03X1644399Y210038I-123J158D01*
G01Y210352D01*
G03X1644322Y210510I-200J0D01*
G02X1643743Y211695I923J1185D01*
G02X1645245Y213197I1502J0D01*
G02X1646232Y212827I0J-1501D01*
G01X1646233D01*
Y212826D01*
G03X1646363Y212778I130J152D01*
G01X1646627D01*
G03X1646757Y212826I0J200D01*
G01X1646758Y212827D01*
G02X1647745Y213197I987J-1131D01*
G37*
G36*
G01X1545383D02*
G02X1546885Y211695I0J-1502D01*
G02X1546413Y210602I-1502J0D01*
G01X1546412Y210601D01*
G03X1546351Y210436I138J-145D01*
G01X1546382Y210121D01*
G03X1546476Y209971I199J20D01*
G02X1547185Y208695I-794J-1276D01*
G02X1545683Y207193I-1502J0D01*
G02X1544577Y207678I0J1504D01*
G03X1544430Y207743I-148J-135D01*
G01X1544136D01*
G03X1543989Y207678I1J-200D01*
G02X1542883Y207193I-1106J1019D01*
G02X1541381Y208695I0J1502D01*
G02X1541960Y209880I1502J0D01*
G03X1542037Y210038I-123J158D01*
G01Y210352D01*
G03X1541960Y210510I-200J0D01*
G02X1541381Y211695I923J1185D01*
G02X1542883Y213197I1502J0D01*
G02X1543870Y212827I0J-1501D01*
G01X1543871D01*
Y212826D01*
G03X1544001Y212778I130J152D01*
G01X1544265D01*
G03X1544395Y212826I0J200D01*
G01X1544396Y212827D01*
G02X1545383Y213197I987J-1131D01*
G37*
G36*
G01X1443021D02*
G02X1444523Y211695I0J-1502D01*
G02X1444051Y210602I-1502J0D01*
G01X1444050Y210601D01*
G03X1443989Y210436I138J-145D01*
G01X1444020Y210121D01*
G03X1444114Y209971I199J20D01*
G02X1444823Y208695I-794J-1276D01*
G02X1443321Y207193I-1502J0D01*
G02X1442215Y207678I0J1504D01*
G03X1442068Y207743I-148J-135D01*
G01X1441774D01*
G03X1441627Y207678I1J-200D01*
G02X1440521Y207193I-1106J1019D01*
G02X1439019Y208695I0J1502D01*
G02X1439598Y209880I1502J0D01*
G03X1439675Y210038I-123J158D01*
G01Y210352D01*
G03X1439598Y210510I-200J0D01*
G02X1439019Y211695I923J1185D01*
G02X1440521Y213197I1502J0D01*
G02X1441508Y212827I0J-1501D01*
G01X1441509D01*
Y212826D01*
G03X1441639Y212778I130J152D01*
G01X1441903D01*
G03X1442033Y212826I0J200D01*
G01X1442034Y212827D01*
G02X1443021Y213197I987J-1131D01*
G37*
G36*
G01X1293020D02*
G02X1294522Y211695I0J-1502D01*
G02X1294050Y210602I-1502J0D01*
G01X1294049Y210601D01*
G03X1293988Y210436I138J-145D01*
G01X1294019Y210121D01*
G03X1294113Y209971I199J20D01*
G02X1294822Y208695I-794J-1276D01*
G02X1293320Y207193I-1502J0D01*
G02X1292214Y207678I0J1504D01*
G03X1292067Y207743I-148J-135D01*
G01X1291773D01*
G03X1291626Y207678I1J-200D01*
G02X1290520Y207193I-1106J1019D01*
G02X1289018Y208695I0J1502D01*
G02X1289597Y209880I1502J0D01*
G03X1289674Y210038I-123J158D01*
G01Y210352D01*
G03X1289597Y210510I-200J0D01*
G02X1289018Y211695I923J1185D01*
G02X1290520Y213197I1502J0D01*
G02X1291507Y212827I0J-1501D01*
G01X1291508D01*
Y212826D01*
G03X1291638Y212778I130J152D01*
G01X1291902D01*
G03X1292032Y212826I0J200D01*
G01X1292033Y212827D01*
G02X1293020Y213197I987J-1131D01*
G37*
G36*
G01X1190658D02*
G02X1192160Y211695I0J-1502D01*
G02X1191688Y210602I-1502J0D01*
G01X1191687Y210601D01*
G03X1191626Y210436I138J-145D01*
G01X1191657Y210121D01*
G03X1191751Y209971I199J20D01*
G02X1192460Y208695I-794J-1276D01*
G02X1190958Y207193I-1502J0D01*
G02X1189852Y207678I0J1504D01*
G03X1189705Y207743I-148J-135D01*
G01X1189411D01*
G03X1189264Y207678I1J-200D01*
G02X1188158Y207193I-1106J1019D01*
G02X1186656Y208695I0J1502D01*
G02X1187235Y209880I1502J0D01*
G03X1187312Y210038I-123J158D01*
G01Y210352D01*
G03X1187235Y210510I-200J0D01*
G02X1186656Y211695I923J1185D01*
G02X1188158Y213197I1502J0D01*
G02X1189145Y212827I0J-1501D01*
G01X1189146D01*
Y212826D01*
G03X1189276Y212778I130J152D01*
G01X1189540D01*
G03X1189670Y212826I0J200D01*
G01X1189671Y212827D01*
G02X1190658Y213197I987J-1131D01*
G37*
G36*
G01X1088296D02*
G02X1089798Y211695I0J-1502D01*
G02X1089326Y210602I-1502J0D01*
G01X1089325Y210601D01*
G03X1089264Y210436I138J-145D01*
G01X1089295Y210121D01*
G03X1089389Y209971I199J20D01*
G02X1090098Y208695I-794J-1276D01*
G02X1088596Y207193I-1502J0D01*
G02X1087490Y207678I0J1504D01*
G03X1087343Y207743I-148J-135D01*
G01X1087049D01*
G03X1086902Y207678I1J-200D01*
G02X1085796Y207193I-1106J1019D01*
G02X1084294Y208695I0J1502D01*
G02X1084873Y209880I1502J0D01*
G03X1084950Y210038I-123J158D01*
G01Y210352D01*
G03X1084873Y210510I-200J0D01*
G02X1084294Y211695I923J1185D01*
G02X1085796Y213197I1502J0D01*
G02X1086783Y212827I0J-1501D01*
G01X1086784D01*
Y212826D01*
G03X1086914Y212778I130J152D01*
G01X1087178D01*
G03X1087308Y212826I0J200D01*
G01X1087309Y212827D01*
G02X1088296Y213197I987J-1131D01*
G37*
G36*
G01X985934D02*
G02X987436Y211695I0J-1502D01*
G02X986964Y210602I-1502J0D01*
G01X986963Y210601D01*
G03X986902Y210436I138J-145D01*
G01X986933Y210121D01*
G03X987027Y209971I199J20D01*
G02X987736Y208695I-794J-1276D01*
G02X986234Y207193I-1502J0D01*
G02X985128Y207678I0J1504D01*
G03X984981Y207743I-148J-135D01*
G01X984687D01*
G03X984540Y207678I1J-200D01*
G02X983434Y207193I-1106J1019D01*
G02X981932Y208695I0J1502D01*
G02X982511Y209880I1502J0D01*
G03X982588Y210038I-123J158D01*
G01Y210352D01*
G03X982511Y210510I-200J0D01*
G02X981932Y211695I923J1185D01*
G02X983434Y213197I1502J0D01*
G02X984421Y212827I0J-1501D01*
G01X984422D01*
Y212826D01*
G03X984552Y212778I130J152D01*
G01X984816D01*
G03X984946Y212826I0J200D01*
G01X984947Y212827D01*
G02X985934Y213197I987J-1131D01*
G37*
G36*
G01X835934D02*
G02X837436Y211695I0J-1502D01*
G02X836964Y210602I-1502J0D01*
G01X836963Y210601D01*
G03X836902Y210436I138J-145D01*
G01X836933Y210121D01*
G03X837027Y209971I199J20D01*
G02X837736Y208695I-794J-1276D01*
G02X836234Y207193I-1502J0D01*
G02X835128Y207678I0J1504D01*
G03X834981Y207743I-148J-135D01*
G01X834687D01*
G03X834540Y207678I1J-200D01*
G02X833434Y207193I-1106J1019D01*
G02X831932Y208695I0J1502D01*
G02X832511Y209880I1502J0D01*
G03X832588Y210038I-123J158D01*
G01Y210352D01*
G03X832511Y210510I-200J0D01*
G02X831932Y211695I923J1185D01*
G02X833434Y213197I1502J0D01*
G02X834421Y212827I0J-1501D01*
G01X834422D01*
Y212826D01*
G03X834552Y212778I130J152D01*
G01X834816D01*
G03X834946Y212826I0J200D01*
G01X834947Y212827D01*
G02X835934Y213197I987J-1131D01*
G37*
G36*
G01X733572D02*
G02X735074Y211695I0J-1502D01*
G02X734602Y210602I-1502J0D01*
G01X734601Y210601D01*
G03X734540Y210436I138J-145D01*
G01X734571Y210121D01*
G03X734665Y209971I199J20D01*
G02X735374Y208695I-794J-1276D01*
G02X733872Y207193I-1502J0D01*
G02X732766Y207678I0J1504D01*
G03X732619Y207743I-148J-135D01*
G01X732325D01*
G03X732178Y207678I1J-200D01*
G02X731072Y207193I-1106J1019D01*
G02X729570Y208695I0J1502D01*
G02X730149Y209880I1502J0D01*
G03X730226Y210038I-123J158D01*
G01Y210352D01*
G03X730149Y210510I-200J0D01*
G02X729570Y211695I923J1185D01*
G02X731072Y213197I1502J0D01*
G02X732059Y212827I0J-1501D01*
G01X732060D01*
Y212826D01*
G03X732190Y212778I130J152D01*
G01X732454D01*
G03X732584Y212826I0J200D01*
G01X732585Y212827D01*
G02X733572Y213197I987J-1131D01*
G37*
G36*
G01X631210D02*
G02X632712Y211695I0J-1502D01*
G02X632240Y210602I-1502J0D01*
G01X632239Y210601D01*
G03X632178Y210436I138J-145D01*
G01X632209Y210121D01*
G03X632303Y209971I199J20D01*
G02X633012Y208695I-794J-1276D01*
G02X631510Y207193I-1502J0D01*
G02X630404Y207678I0J1504D01*
G03X630257Y207743I-148J-135D01*
G01X629963D01*
G03X629816Y207678I1J-200D01*
G02X628710Y207193I-1106J1019D01*
G02X627208Y208695I0J1502D01*
G02X627787Y209880I1502J0D01*
G03X627864Y210038I-123J158D01*
G01Y210352D01*
G03X627787Y210510I-200J0D01*
G02X627208Y211695I923J1185D01*
G02X628710Y213197I1502J0D01*
G02X629697Y212827I0J-1501D01*
G01X629698D01*
Y212826D01*
G03X629828Y212778I130J152D01*
G01X630092D01*
G03X630222Y212826I0J200D01*
G01X630223Y212827D01*
G02X631210Y213197I987J-1131D01*
G37*
G36*
G01X528848D02*
G02X530350Y211695I0J-1502D01*
G02X529878Y210602I-1502J0D01*
G01X529877Y210601D01*
G03X529816Y210436I138J-145D01*
G01X529847Y210121D01*
G03X529941Y209971I199J20D01*
G02X530650Y208695I-794J-1276D01*
G02X529148Y207193I-1502J0D01*
G02X528042Y207678I0J1504D01*
G03X527895Y207743I-148J-135D01*
G01X527601D01*
G03X527454Y207678I1J-200D01*
G02X526348Y207193I-1106J1019D01*
G02X524846Y208695I0J1502D01*
G02X525425Y209880I1502J0D01*
G03X525502Y210038I-123J158D01*
G01Y210352D01*
G03X525425Y210510I-200J0D01*
G02X524846Y211695I923J1185D01*
G02X526348Y213197I1502J0D01*
G02X527335Y212827I0J-1501D01*
G01X527336D01*
Y212826D01*
G03X527466Y212778I130J152D01*
G01X527730D01*
G03X527860Y212826I0J200D01*
G01X527861Y212827D01*
G02X528848Y213197I987J-1131D01*
G37*
G36*
G01X378847D02*
G02X380349Y211695I0J-1502D01*
G02X379877Y210602I-1502J0D01*
G01X379876Y210601D01*
G03X379815Y210436I138J-145D01*
G01X379846Y210121D01*
G03X379940Y209971I199J20D01*
G02X380649Y208695I-794J-1276D01*
G02X379147Y207193I-1502J0D01*
G02X378041Y207678I0J1504D01*
G03X377894Y207743I-148J-135D01*
G01X377600D01*
G03X377453Y207678I1J-200D01*
G02X376347Y207193I-1106J1019D01*
G02X374845Y208695I0J1502D01*
G02X375424Y209880I1502J0D01*
G03X375501Y210038I-123J158D01*
G01Y210352D01*
G03X375424Y210510I-200J0D01*
G02X374845Y211695I923J1185D01*
G02X376347Y213197I1502J0D01*
G02X377334Y212827I0J-1501D01*
G01X377335D01*
Y212826D01*
G03X377465Y212778I130J152D01*
G01X377729D01*
G03X377859Y212826I0J200D01*
G01X377860Y212827D01*
G02X378847Y213197I987J-1131D01*
G37*
G36*
G01X276485D02*
G02X277987Y211695I0J-1502D01*
G02X277515Y210602I-1502J0D01*
G01X277514Y210601D01*
G03X277453Y210436I138J-145D01*
G01X277484Y210121D01*
G03X277578Y209971I199J20D01*
G02X278287Y208695I-794J-1276D01*
G02X276785Y207193I-1502J0D01*
G02X275679Y207678I0J1504D01*
G03X275532Y207743I-148J-135D01*
G01X275238D01*
G03X275091Y207678I1J-200D01*
G02X273985Y207193I-1106J1019D01*
G02X272483Y208695I0J1502D01*
G02X273062Y209880I1502J0D01*
G03X273139Y210038I-123J158D01*
G01Y210352D01*
G03X273062Y210510I-200J0D01*
G02X272483Y211695I923J1185D01*
G02X273985Y213197I1502J0D01*
G02X274972Y212827I0J-1501D01*
G01X274973D01*
Y212826D01*
G03X275103Y212778I130J152D01*
G01X275367D01*
G03X275497Y212826I0J200D01*
G01X275498Y212827D01*
G02X276485Y213197I987J-1131D01*
G37*
G36*
G01X174123D02*
G02X175625Y211695I0J-1502D01*
G02X175153Y210602I-1502J0D01*
G01X175152Y210601D01*
G03X175091Y210436I138J-145D01*
G01X175122Y210121D01*
G03X175216Y209971I199J20D01*
G02X175925Y208695I-794J-1276D01*
G02X174423Y207193I-1502J0D01*
G02X173317Y207678I0J1504D01*
G03X173170Y207743I-148J-135D01*
G01X172876D01*
G03X172729Y207678I1J-200D01*
G02X171623Y207193I-1106J1019D01*
G02X170121Y208695I0J1502D01*
G02X170700Y209880I1502J0D01*
G03X170777Y210038I-123J158D01*
G01Y210352D01*
G03X170700Y210510I-200J0D01*
G02X170121Y211695I923J1185D01*
G02X171623Y213197I1502J0D01*
G02X172610Y212827I0J-1501D01*
G01X172611D01*
Y212826D01*
G03X172741Y212778I130J152D01*
G01X173005D01*
G03X173135Y212826I0J200D01*
G01X173136Y212827D01*
G02X174123Y213197I987J-1131D01*
G37*
G36*
G01X71761D02*
G02X73263Y211695I0J-1502D01*
G02X72791Y210602I-1502J0D01*
G01X72790Y210601D01*
G03X72729Y210436I138J-145D01*
G01X72760Y210121D01*
G03X72854Y209971I199J20D01*
G02X73563Y208695I-794J-1276D01*
G02X72061Y207193I-1502J0D01*
G02X70955Y207678I0J1504D01*
G03X70808Y207743I-148J-135D01*
G01X70514D01*
G03X70367Y207678I1J-200D01*
G02X69261Y207193I-1106J1019D01*
G02X67759Y208695I0J1502D01*
G02X68338Y209880I1502J0D01*
G03X68415Y210038I-123J158D01*
G01Y210352D01*
G03X68338Y210510I-200J0D01*
G02X67759Y211695I923J1185D01*
G02X69261Y213197I1502J0D01*
G02X70248Y212827I0J-1501D01*
G01X70249D01*
Y212826D01*
G03X70379Y212778I130J152D01*
G01X70643D01*
G03X70773Y212826I0J200D01*
G01X70774Y212827D01*
G02X71761Y213197I987J-1131D01*
G37*
G36*
G01X412890Y206766D02*
X414658D01*
G02Y202962I0J-1902D01*
G01X413761D01*
G03X413619Y202903I0J-200D01*
G01X413125Y202409D01*
G03X413066Y202267I141J-142D01*
G01Y198172D01*
G03X413178Y197992I200J0D01*
G01X413500Y197834D01*
G03X413710Y197855I88J179D01*
G02X414626Y198167I916J-1189D01*
G02Y195163I0J-1502D01*
G02X413710Y195475I0J1501D01*
G03X413500Y195496I-122J-158D01*
G01X413178Y195338D01*
G03X413066Y195158I88J-180D01*
G01Y194172D01*
G03X413178Y193992I200J0D01*
G01X413500Y193834D01*
G03X413710Y193855I88J179D01*
G02X414626Y194167I916J-1189D01*
G02Y191163I0J-1502D01*
G02X413710Y191475I0J1501D01*
G03X413500Y191496I-122J-158D01*
G01X413178Y191338D01*
G03X413066Y191158I88J-180D01*
G01Y191068D01*
G02X412509Y189723I-1902J0D01*
G01X408070Y185284D01*
G02X407391Y184848I-1344J1346D01*
G01X407389D01*
X407353Y184834D01*
X407296Y184781D01*
X407144Y184455D01*
X407141Y184376D01*
X407154Y184339D01*
G02X407241Y183836I-1415J-504D01*
G01Y183834D01*
G02X404237I-1502J0D01*
G02X404954Y185115I1503J0D01*
G01X404987Y185135D01*
X405034Y185199D01*
X405111Y185510D01*
G03X405089Y185659I-194J47D01*
G01Y185660D01*
G02X404824Y186629I1636J968D01*
G02X405380Y187974I1902J1D01*
G01X405411Y188005D01*
G03X405458Y188217I-141J142D01*
G01X405330Y188558D01*
G03X405157Y188687I-187J-71D01*
G01X405156D01*
G02X403757Y190185I103J1498D01*
G02X405259Y191687I1502J0D01*
G02X406757Y190288I0J-1502D01*
G01Y190287D01*
G03X406886Y190114I200J14D01*
G01X407227Y189986D01*
G03X407439Y190032I70J187D01*
G01X409203Y191797D01*
G03X409262Y191939I-141J142D01*
G01Y203138D01*
G02X409819Y204483I1902J0D01*
G01X411545Y206209D01*
G02X412890Y206766I1345J-1345D01*
G37*
G36*
G01X1706429Y201748D02*
G02X1707931Y203250I1502J0D01*
G02X1709024Y202778I0J-1502D01*
G01X1709025Y202777D01*
G03X1709190Y202716I145J138D01*
G01X1709505Y202747D01*
G03X1709655Y202841I-20J199D01*
G02X1710931Y203550I1276J-794D01*
G02X1712433Y202048I0J-1502D01*
G02X1711948Y200942I-1504J0D01*
G03X1711883Y200795I135J-148D01*
G01Y200501D01*
G03X1711948Y200354I200J1D01*
G02X1712433Y199248I-1019J-1106D01*
G02X1710931Y197746I-1502J0D01*
G02X1709746Y198325I0J1502D01*
G03X1709588Y198402I-158J-123D01*
G01X1709274D01*
G03X1709116Y198325I0J-200D01*
G02X1707931Y197746I-1185J923D01*
G02X1706429Y199248I0J1502D01*
G02X1706799Y200235I1501J0D01*
G01Y200236D01*
X1706800D01*
G03X1706848Y200366I-152J130D01*
G01Y200630D01*
G03X1706800Y200760I-200J0D01*
G01X1706799Y200761D01*
G02X1706429Y201748I1131J987D01*
G37*
G36*
G01X1604067D02*
G02X1605569Y203250I1502J0D01*
G02X1606662Y202778I0J-1502D01*
G01X1606663Y202777D01*
G03X1606828Y202716I145J138D01*
G01X1607143Y202747D01*
G03X1607293Y202841I-20J199D01*
G02X1608569Y203550I1276J-794D01*
G02X1610071Y202048I0J-1502D01*
G02X1609586Y200942I-1504J0D01*
G03X1609521Y200795I135J-148D01*
G01Y200501D01*
G03X1609586Y200354I200J1D01*
G02X1610071Y199248I-1019J-1106D01*
G02X1608569Y197746I-1502J0D01*
G02X1607384Y198325I0J1502D01*
G03X1607226Y198402I-158J-123D01*
G01X1606912D01*
G03X1606754Y198325I0J-200D01*
G02X1605569Y197746I-1185J923D01*
G02X1604067Y199248I0J1502D01*
G02X1604437Y200235I1501J0D01*
G01Y200236D01*
X1604438D01*
G03X1604486Y200366I-152J130D01*
G01Y200630D01*
G03X1604438Y200760I-200J0D01*
G01X1604437Y200761D01*
G02X1604067Y201748I1131J987D01*
G37*
G36*
G01X1501705D02*
G02X1503207Y203250I1502J0D01*
G02X1504300Y202778I0J-1502D01*
G01X1504301Y202777D01*
G03X1504466Y202716I145J138D01*
G01X1504781Y202747D01*
G03X1504931Y202841I-20J199D01*
G02X1506207Y203550I1276J-794D01*
G02X1507709Y202048I0J-1502D01*
G02X1507224Y200942I-1504J0D01*
G03X1507159Y200795I135J-148D01*
G01Y200501D01*
G03X1507224Y200354I200J1D01*
G02X1507709Y199248I-1019J-1106D01*
G02X1506207Y197746I-1502J0D01*
G02X1505022Y198325I0J1502D01*
G03X1504864Y198402I-158J-123D01*
G01X1504550D01*
G03X1504392Y198325I0J-200D01*
G02X1503207Y197746I-1185J923D01*
G02X1501705Y199248I0J1502D01*
G02X1502075Y200235I1501J0D01*
G01Y200236D01*
X1502076D01*
G03X1502124Y200366I-152J130D01*
G01Y200630D01*
G03X1502076Y200760I-200J0D01*
G01X1502075Y200761D01*
G02X1501705Y201748I1131J987D01*
G37*
G36*
G01X1399343D02*
G02X1400845Y203250I1502J0D01*
G02X1401938Y202778I0J-1502D01*
G01X1401939Y202777D01*
G03X1402104Y202716I145J138D01*
G01X1402419Y202747D01*
G03X1402569Y202841I-20J199D01*
G02X1403845Y203550I1276J-794D01*
G02X1405347Y202048I0J-1502D01*
G02X1404862Y200942I-1504J0D01*
G03X1404797Y200795I135J-148D01*
G01Y200501D01*
G03X1404862Y200354I200J1D01*
G02X1405347Y199248I-1019J-1106D01*
G02X1403845Y197746I-1502J0D01*
G02X1402660Y198325I0J1502D01*
G03X1402502Y198402I-158J-123D01*
G01X1402188D01*
G03X1402030Y198325I0J-200D01*
G02X1400845Y197746I-1185J923D01*
G02X1399343Y199248I0J1502D01*
G02X1399713Y200235I1501J0D01*
G01Y200236D01*
X1399714D01*
G03X1399762Y200366I-152J130D01*
G01Y200630D01*
G03X1399714Y200760I-200J0D01*
G01X1399713Y200761D01*
G02X1399343Y201748I1131J987D01*
G37*
G36*
G01X1249342D02*
G02X1250844Y203250I1502J0D01*
G02X1251937Y202778I0J-1502D01*
G01X1251938Y202777D01*
G03X1252103Y202716I145J138D01*
G01X1252418Y202747D01*
G03X1252568Y202841I-20J199D01*
G02X1253844Y203550I1276J-794D01*
G02X1255346Y202048I0J-1502D01*
G02X1254861Y200942I-1504J0D01*
G03X1254796Y200795I135J-148D01*
G01Y200501D01*
G03X1254861Y200354I200J1D01*
G02X1255346Y199248I-1019J-1106D01*
G02X1253844Y197746I-1502J0D01*
G02X1252659Y198325I0J1502D01*
G03X1252501Y198402I-158J-123D01*
G01X1252187D01*
G03X1252029Y198325I0J-200D01*
G02X1250844Y197746I-1185J923D01*
G02X1249342Y199248I0J1502D01*
G02X1249712Y200235I1501J0D01*
G01Y200236D01*
X1249713D01*
G03X1249761Y200366I-152J130D01*
G01Y200630D01*
G03X1249713Y200760I-200J0D01*
G01X1249712Y200761D01*
G02X1249342Y201748I1131J987D01*
G37*
G36*
G01X1146980D02*
G02X1148482Y203250I1502J0D01*
G02X1149575Y202778I0J-1502D01*
G01X1149576Y202777D01*
G03X1149741Y202716I145J138D01*
G01X1150056Y202747D01*
G03X1150206Y202841I-20J199D01*
G02X1151482Y203550I1276J-794D01*
G02X1152984Y202048I0J-1502D01*
G02X1152499Y200942I-1504J0D01*
G03X1152434Y200795I135J-148D01*
G01Y200501D01*
G03X1152499Y200354I200J1D01*
G02X1152984Y199248I-1019J-1106D01*
G02X1151482Y197746I-1502J0D01*
G02X1150297Y198325I0J1502D01*
G03X1150139Y198402I-158J-123D01*
G01X1149825D01*
G03X1149667Y198325I0J-200D01*
G02X1148482Y197746I-1185J923D01*
G02X1146980Y199248I0J1502D01*
G02X1147350Y200235I1501J0D01*
G01Y200236D01*
X1147351D01*
G03X1147399Y200366I-152J130D01*
G01Y200630D01*
G03X1147351Y200760I-200J0D01*
G01X1147350Y200761D01*
G02X1146980Y201748I1131J987D01*
G37*
G36*
G01X1044618D02*
G02X1046120Y203250I1502J0D01*
G02X1047213Y202778I0J-1502D01*
G01X1047214Y202777D01*
G03X1047379Y202716I145J138D01*
G01X1047694Y202747D01*
G03X1047844Y202841I-20J199D01*
G02X1049120Y203550I1276J-794D01*
G02X1050622Y202048I0J-1502D01*
G02X1050137Y200942I-1504J0D01*
G03X1050072Y200795I135J-148D01*
G01Y200501D01*
G03X1050137Y200354I200J1D01*
G02X1050622Y199248I-1019J-1106D01*
G02X1049120Y197746I-1502J0D01*
G02X1047935Y198325I0J1502D01*
G03X1047777Y198402I-158J-123D01*
G01X1047463D01*
G03X1047305Y198325I0J-200D01*
G02X1046120Y197746I-1185J923D01*
G02X1044618Y199248I0J1502D01*
G02X1044988Y200235I1501J0D01*
G01Y200236D01*
X1044989D01*
G03X1045037Y200366I-152J130D01*
G01Y200630D01*
G03X1044989Y200760I-200J0D01*
G01X1044988Y200761D01*
G02X1044618Y201748I1131J987D01*
G37*
G36*
G01X792256D02*
G02X793758Y203250I1502J0D01*
G02X794851Y202778I0J-1502D01*
G01X794852Y202777D01*
G03X795017Y202716I145J138D01*
G01X795332Y202747D01*
G03X795482Y202841I-20J199D01*
G02X796758Y203550I1276J-794D01*
G02X798260Y202048I0J-1502D01*
G02X797775Y200942I-1504J0D01*
G03X797710Y200795I135J-148D01*
G01Y200501D01*
G03X797775Y200354I200J1D01*
G02X798260Y199248I-1019J-1106D01*
G02X796758Y197746I-1502J0D01*
G02X795573Y198325I0J1502D01*
G03X795415Y198402I-158J-123D01*
G01X795101D01*
G03X794943Y198325I0J-200D01*
G02X793758Y197746I-1185J923D01*
G02X792256Y199248I0J1502D01*
G02X792626Y200235I1501J0D01*
G01Y200236D01*
X792627D01*
G03X792675Y200366I-152J130D01*
G01Y200630D01*
G03X792627Y200760I-200J0D01*
G01X792626Y200761D01*
G02X792256Y201748I1131J987D01*
G37*
G36*
G01X689894D02*
G02X691396Y203250I1502J0D01*
G02X692489Y202778I0J-1502D01*
G01X692490Y202777D01*
G03X692655Y202716I145J138D01*
G01X692970Y202747D01*
G03X693120Y202841I-20J199D01*
G02X694396Y203550I1276J-794D01*
G02X695898Y202048I0J-1502D01*
G02X695413Y200942I-1504J0D01*
G03X695348Y200795I135J-148D01*
G01Y200501D01*
G03X695413Y200354I200J1D01*
G02X695898Y199248I-1019J-1106D01*
G02X694396Y197746I-1502J0D01*
G02X693211Y198325I0J1502D01*
G03X693053Y198402I-158J-123D01*
G01X692739D01*
G03X692581Y198325I0J-200D01*
G02X691396Y197746I-1185J923D01*
G02X689894Y199248I0J1502D01*
G02X690264Y200235I1501J0D01*
G01Y200236D01*
X690265D01*
G03X690313Y200366I-152J130D01*
G01Y200630D01*
G03X690265Y200760I-200J0D01*
G01X690264Y200761D01*
G02X689894Y201748I1131J987D01*
G37*
G36*
G01X587532D02*
G02X589034Y203250I1502J0D01*
G02X590127Y202778I0J-1502D01*
G01X590128Y202777D01*
G03X590293Y202716I145J138D01*
G01X590608Y202747D01*
G03X590758Y202841I-20J199D01*
G02X592034Y203550I1276J-794D01*
G02X593536Y202048I0J-1502D01*
G02X593051Y200942I-1504J0D01*
G03X592986Y200795I135J-148D01*
G01Y200501D01*
G03X593051Y200354I200J1D01*
G02X593536Y199248I-1019J-1106D01*
G02X592034Y197746I-1502J0D01*
G02X590849Y198325I0J1502D01*
G03X590691Y198402I-158J-123D01*
G01X590377D01*
G03X590219Y198325I0J-200D01*
G02X589034Y197746I-1185J923D01*
G02X587532Y199248I0J1502D01*
G02X587902Y200235I1501J0D01*
G01Y200236D01*
X587903D01*
G03X587951Y200366I-152J130D01*
G01Y200630D01*
G03X587903Y200760I-200J0D01*
G01X587902Y200761D01*
G02X587532Y201748I1131J987D01*
G37*
G36*
G01X485170D02*
G02X486672Y203250I1502J0D01*
G02X487765Y202778I0J-1502D01*
G01X487766Y202777D01*
G03X487931Y202716I145J138D01*
G01X488246Y202747D01*
G03X488396Y202841I-20J199D01*
G02X489672Y203550I1276J-794D01*
G02X491174Y202048I0J-1502D01*
G02X490689Y200942I-1504J0D01*
G03X490624Y200795I135J-148D01*
G01Y200501D01*
G03X490689Y200354I200J1D01*
G02X491174Y199248I-1019J-1106D01*
G02X489672Y197746I-1502J0D01*
G02X488487Y198325I0J1502D01*
G03X488329Y198402I-158J-123D01*
G01X488015D01*
G03X487857Y198325I0J-200D01*
G02X486672Y197746I-1185J923D01*
G02X485170Y199248I0J1502D01*
G02X485540Y200235I1501J0D01*
G01Y200236D01*
X485541D01*
G03X485589Y200366I-152J130D01*
G01Y200630D01*
G03X485541Y200760I-200J0D01*
G01X485540Y200761D01*
G02X485170Y201748I1131J987D01*
G37*
G36*
G01X335169D02*
G02X336671Y203250I1502J0D01*
G02X337764Y202778I0J-1502D01*
G01X337765Y202777D01*
G03X337930Y202716I145J138D01*
G01X338245Y202747D01*
G03X338395Y202841I-20J199D01*
G02X339671Y203550I1276J-794D01*
G02X341173Y202048I0J-1502D01*
G02X340688Y200942I-1504J0D01*
G03X340623Y200795I135J-148D01*
G01Y200501D01*
G03X340688Y200354I200J1D01*
G02X341173Y199248I-1019J-1106D01*
G02X339671Y197746I-1502J0D01*
G02X338486Y198325I0J1502D01*
G03X338328Y198402I-158J-123D01*
G01X338014D01*
G03X337856Y198325I0J-200D01*
G02X336671Y197746I-1185J923D01*
G02X335169Y199248I0J1502D01*
G02X335539Y200235I1501J0D01*
G01Y200236D01*
X335540D01*
G03X335588Y200366I-152J130D01*
G01Y200630D01*
G03X335540Y200760I-200J0D01*
G01X335539Y200761D01*
G02X335169Y201748I1131J987D01*
G37*
G36*
G01X232807D02*
G02X234309Y203250I1502J0D01*
G02X235402Y202778I0J-1502D01*
G01X235403Y202777D01*
G03X235568Y202716I145J138D01*
G01X235883Y202747D01*
G03X236033Y202841I-20J199D01*
G02X237309Y203550I1276J-794D01*
G02X238811Y202048I0J-1502D01*
G02X238326Y200942I-1504J0D01*
G03X238261Y200795I135J-148D01*
G01Y200501D01*
G03X238326Y200354I200J1D01*
G02X238811Y199248I-1019J-1106D01*
G02X237309Y197746I-1502J0D01*
G02X236124Y198325I0J1502D01*
G03X235966Y198402I-158J-123D01*
G01X235652D01*
G03X235494Y198325I0J-200D01*
G02X234309Y197746I-1185J923D01*
G02X232807Y199248I0J1502D01*
G02X233177Y200235I1501J0D01*
G01Y200236D01*
X233178D01*
G03X233226Y200366I-152J130D01*
G01Y200630D01*
G03X233178Y200760I-200J0D01*
G01X233177Y200761D01*
G02X232807Y201748I1131J987D01*
G37*
G36*
G01X130445D02*
G02X131947Y203250I1502J0D01*
G02X133040Y202778I0J-1502D01*
G01X133041Y202777D01*
G03X133206Y202716I145J138D01*
G01X133521Y202747D01*
G03X133671Y202841I-20J199D01*
G02X134947Y203550I1276J-794D01*
G02X136449Y202048I0J-1502D01*
G02X135964Y200942I-1504J0D01*
G03X135899Y200795I135J-148D01*
G01Y200501D01*
G03X135964Y200354I200J1D01*
G02X136449Y199248I-1019J-1106D01*
G02X134947Y197746I-1502J0D01*
G02X133762Y198325I0J1502D01*
G03X133604Y198402I-158J-123D01*
G01X133290D01*
G03X133132Y198325I0J-200D01*
G02X131947Y197746I-1185J923D01*
G02X130445Y199248I0J1502D01*
G02X130815Y200235I1501J0D01*
G01Y200236D01*
X130816D01*
G03X130864Y200366I-152J130D01*
G01Y200630D01*
G03X130816Y200760I-200J0D01*
G01X130815Y200761D01*
G02X130445Y201748I1131J987D01*
G37*
G36*
G01X28083D02*
G02X29585Y203250I1502J0D01*
G02X30678Y202778I0J-1502D01*
G01X30679Y202777D01*
G03X30844Y202716I145J138D01*
G01X31159Y202747D01*
G03X31309Y202841I-20J199D01*
G02X32585Y203550I1276J-794D01*
G02X34087Y202048I0J-1502D01*
G02X33602Y200942I-1504J0D01*
G03X33537Y200795I135J-148D01*
G01Y200501D01*
G03X33602Y200354I200J1D01*
G02X34087Y199248I-1019J-1106D01*
G02X32585Y197746I-1502J0D01*
G02X31400Y198325I0J1502D01*
G03X31242Y198402I-158J-123D01*
G01X30928D01*
G03X30770Y198325I0J-200D01*
G02X29585Y197746I-1185J923D01*
G02X28083Y199248I0J1502D01*
G02X28453Y200235I1501J0D01*
G01Y200236D01*
X28454D01*
G03X28502Y200366I-152J130D01*
G01Y200630D01*
G03X28454Y200760I-200J0D01*
G01X28453Y200761D01*
G02X28083Y201748I1131J987D01*
G37*
G36*
G01X1011641Y201149D02*
G02X1013116Y202366I1475J-285D01*
G02Y199362I0J-1502D01*
G02X1012360Y199566I0J1503D01*
G03X1011766Y199297I-202J-345D01*
G02X1010291Y198080I-1475J285D01*
G02Y201084I0J1502D01*
G02X1011047Y200880I0J-1503D01*
G03X1011641Y201149I202J345D01*
G37*
G36*
G01X297622Y190988D02*
G02Y193992I0J1502D01*
G02X298790Y193434I0J-1501D01*
G01X298822Y193394D01*
X298917Y193356D01*
X299304Y193400D01*
G03X299461Y193512I-23J199D01*
G02X300814Y194361I1353J-654D01*
G02X302316Y192859I0J-1502D01*
G02X302174Y192222I-1502J0D01*
G01X302150Y192171D01*
X302163Y192059D01*
X302452Y191688D01*
X302556Y191649D01*
X302612Y191660D01*
G02X302894Y191687I284J-1475D01*
G01X302897D01*
G02X301395Y190185I0J-1502D01*
G02X301537Y190822I1502J0D01*
G01X301561Y190873D01*
X301548Y190985D01*
X301259Y191356D01*
X301155Y191395D01*
X301099Y191384D01*
G02X300817Y191357I-284J1475D01*
G01X300814D01*
G02X299646Y191915I0J1501D01*
G01X299614Y191955D01*
X299519Y191993D01*
X299132Y191949D01*
G03X298975Y191837I23J-199D01*
G02X297622Y190988I-1353J654D01*
G37*
G36*
G01X942922Y186919D02*
G02X944424Y188421I1502J0D01*
G02X945517Y187949I0J-1502D01*
G01X945518Y187948D01*
G03X945683Y187887I145J138D01*
G01X945998Y187918D01*
G03X946148Y188012I-20J199D01*
G02X947424Y188721I1276J-794D01*
G02X948926Y187219I0J-1502D01*
G02X948441Y186113I-1504J0D01*
G03X948376Y185966I135J-148D01*
G01Y185672D01*
G03X948441Y185525I200J1D01*
G02X948926Y184419I-1019J-1106D01*
G02X947424Y182917I-1502J0D01*
G02X946239Y183496I0J1502D01*
G03X946081Y183573I-158J-123D01*
G01X945767D01*
G03X945609Y183496I0J-200D01*
G02X944424Y182917I-1185J923D01*
G02X942922Y184419I0J1502D01*
G02X943292Y185406I1501J0D01*
G01Y185407D01*
X943293D01*
G03X943341Y185537I-152J130D01*
G01Y185801D01*
G03X943293Y185931I-200J0D01*
G01X943292Y185932D01*
G02X942922Y186919I1131J987D01*
G37*
G36*
G01X1749627Y184221D02*
G02X1751129Y185723I1502J0D01*
G02X1752249Y185222I0J-1502D01*
G01X1752274Y185193D01*
X1752344Y185159D01*
X1752658Y185134D01*
G03X1752799Y185178I15J199D01*
G02X1753746Y185514I947J-1167D01*
G02X1755248Y184012I0J-1502D01*
G02X1754955Y183121I-1501J0D01*
G01Y183120D01*
X1754932Y183089D01*
X1754913Y183013D01*
X1754965Y182657D01*
X1755006Y182588D01*
X1755037Y182565D01*
G02X1755363Y182226I-906J-1198D01*
G03X1755502Y182142I164J114D01*
G01X1755838Y182099D01*
X1755919Y182123D01*
X1755951Y182151D01*
G02X1756927Y182511I976J-1143D01*
G02Y179507I0J-1502D01*
G02X1755696Y180149I0J1501D01*
G03X1755557Y180233I-164J-114D01*
G01X1755221Y180276D01*
X1755140Y180252D01*
X1755108Y180224D01*
G02X1754132Y179864I-976J1143D01*
G02X1752849Y180585I0J1502D01*
G01X1752822Y180629D01*
X1752734Y180680D01*
X1752292Y180688D01*
X1752202Y180641D01*
X1752174Y180598D01*
G02X1750921Y179924I-1253J828D01*
G02X1749419Y181426I0J1502D01*
G02X1749990Y182605I1503J0D01*
G01X1750023Y182631D01*
X1750062Y182705D01*
X1750091Y183084D01*
X1750063Y183162D01*
X1750034Y183193D01*
G02X1749627Y184221I1095J1028D01*
G37*
G36*
G01X1647265D02*
G02X1648767Y185723I1502J0D01*
G02X1649887Y185222I0J-1502D01*
G01X1649912Y185193D01*
X1649982Y185159D01*
X1650296Y185134D01*
G03X1650437Y185178I15J199D01*
G02X1651384Y185514I947J-1167D01*
G02X1652886Y184012I0J-1502D01*
G02X1652593Y183121I-1501J0D01*
G01Y183120D01*
X1652570Y183089D01*
X1652551Y183013D01*
X1652603Y182657D01*
X1652644Y182588D01*
X1652675Y182565D01*
G02X1653001Y182226I-906J-1198D01*
G03X1653140Y182142I164J114D01*
G01X1653476Y182099D01*
X1653557Y182123D01*
X1653589Y182151D01*
G02X1654565Y182511I976J-1143D01*
G02Y179507I0J-1502D01*
G02X1653334Y180149I0J1501D01*
G03X1653195Y180233I-164J-114D01*
G01X1652859Y180276D01*
X1652778Y180252D01*
X1652746Y180224D01*
G02X1651770Y179864I-976J1143D01*
G02X1650487Y180585I0J1502D01*
G01X1650460Y180629D01*
X1650372Y180680D01*
X1649930Y180688D01*
X1649840Y180641D01*
X1649812Y180598D01*
G02X1648559Y179924I-1253J828D01*
G02X1647057Y181426I0J1502D01*
G02X1647628Y182605I1503J0D01*
G01X1647661Y182631D01*
X1647700Y182705D01*
X1647729Y183084D01*
X1647701Y183162D01*
X1647672Y183193D01*
G02X1647265Y184221I1095J1028D01*
G37*
G36*
G01X1544903D02*
G02X1546405Y185723I1502J0D01*
G02X1547525Y185222I0J-1502D01*
G01X1547550Y185193D01*
X1547620Y185159D01*
X1547934Y185134D01*
G03X1548075Y185178I15J199D01*
G02X1549022Y185514I947J-1167D01*
G02X1550524Y184012I0J-1502D01*
G02X1550231Y183121I-1501J0D01*
G01Y183120D01*
X1550208Y183089D01*
X1550189Y183013D01*
X1550241Y182657D01*
X1550282Y182588D01*
X1550313Y182565D01*
G02X1550639Y182226I-906J-1198D01*
G03X1550778Y182142I164J114D01*
G01X1551114Y182099D01*
X1551195Y182123D01*
X1551227Y182151D01*
G02X1552203Y182511I976J-1143D01*
G02Y179507I0J-1502D01*
G02X1550972Y180149I0J1501D01*
G03X1550833Y180233I-164J-114D01*
G01X1550497Y180276D01*
X1550416Y180252D01*
X1550384Y180224D01*
G02X1549408Y179864I-976J1143D01*
G02X1548125Y180585I0J1502D01*
G01X1548098Y180629D01*
X1548010Y180680D01*
X1547568Y180688D01*
X1547478Y180641D01*
X1547450Y180598D01*
G02X1546197Y179924I-1253J828D01*
G02X1544695Y181426I0J1502D01*
G02X1545266Y182605I1503J0D01*
G01X1545299Y182631D01*
X1545338Y182705D01*
X1545367Y183084D01*
X1545339Y183162D01*
X1545310Y183193D01*
G02X1544903Y184221I1095J1028D01*
G37*
G36*
G01X1442541D02*
G02X1444043Y185723I1502J0D01*
G02X1445163Y185222I0J-1502D01*
G01X1445188Y185193D01*
X1445258Y185159D01*
X1445572Y185134D01*
G03X1445713Y185178I15J199D01*
G02X1446660Y185514I947J-1167D01*
G02X1448162Y184012I0J-1502D01*
G02X1447869Y183121I-1501J0D01*
G01Y183120D01*
X1447846Y183089D01*
X1447827Y183013D01*
X1447879Y182657D01*
X1447920Y182588D01*
X1447951Y182565D01*
G02X1448277Y182226I-906J-1198D01*
G03X1448416Y182142I164J114D01*
G01X1448752Y182099D01*
X1448833Y182123D01*
X1448865Y182151D01*
G02X1449841Y182511I976J-1143D01*
G02Y179507I0J-1502D01*
G02X1448610Y180149I0J1501D01*
G03X1448471Y180233I-164J-114D01*
G01X1448135Y180276D01*
X1448054Y180252D01*
X1448022Y180224D01*
G02X1447046Y179864I-976J1143D01*
G02X1445763Y180585I0J1502D01*
G01X1445736Y180629D01*
X1445648Y180680D01*
X1445206Y180688D01*
X1445116Y180641D01*
X1445088Y180598D01*
G02X1443835Y179924I-1253J828D01*
G02X1442333Y181426I0J1502D01*
G02X1442904Y182605I1503J0D01*
G01X1442937Y182631D01*
X1442976Y182705D01*
X1443005Y183084D01*
X1442977Y183162D01*
X1442948Y183193D01*
G02X1442541Y184221I1095J1028D01*
G37*
G36*
G01X1292540D02*
G02X1294042Y185723I1502J0D01*
G02X1295162Y185222I0J-1502D01*
G01X1295187Y185193D01*
X1295257Y185159D01*
X1295571Y185134D01*
G03X1295712Y185178I15J199D01*
G02X1296659Y185514I947J-1167D01*
G02X1298161Y184012I0J-1502D01*
G02X1297868Y183121I-1501J0D01*
G01Y183120D01*
X1297845Y183089D01*
X1297826Y183013D01*
X1297878Y182657D01*
X1297919Y182588D01*
X1297950Y182565D01*
G02X1298276Y182226I-906J-1198D01*
G03X1298415Y182142I164J114D01*
G01X1298751Y182099D01*
X1298832Y182123D01*
X1298864Y182151D01*
G02X1299840Y182511I976J-1143D01*
G02Y179507I0J-1502D01*
G02X1298609Y180149I0J1501D01*
G03X1298470Y180233I-164J-114D01*
G01X1298134Y180276D01*
X1298053Y180252D01*
X1298021Y180224D01*
G02X1297045Y179864I-976J1143D01*
G02X1295762Y180585I0J1502D01*
G01X1295735Y180629D01*
X1295647Y180680D01*
X1295205Y180688D01*
X1295115Y180641D01*
X1295087Y180598D01*
G02X1293834Y179924I-1253J828D01*
G02X1292332Y181426I0J1502D01*
G02X1292903Y182605I1503J0D01*
G01X1292936Y182631D01*
X1292975Y182705D01*
X1293004Y183084D01*
X1292976Y183162D01*
X1292947Y183193D01*
G02X1292540Y184221I1095J1028D01*
G37*
G36*
G01X1190178D02*
G02X1191680Y185723I1502J0D01*
G02X1192800Y185222I0J-1502D01*
G01X1192825Y185193D01*
X1192895Y185159D01*
X1193209Y185134D01*
G03X1193350Y185178I15J199D01*
G02X1194297Y185514I947J-1167D01*
G02X1195799Y184012I0J-1502D01*
G02X1195506Y183121I-1501J0D01*
G01Y183120D01*
X1195483Y183089D01*
X1195464Y183013D01*
X1195516Y182657D01*
X1195557Y182588D01*
X1195588Y182565D01*
G02X1195914Y182226I-906J-1198D01*
G03X1196053Y182142I164J114D01*
G01X1196389Y182099D01*
X1196470Y182123D01*
X1196502Y182151D01*
G02X1197478Y182511I976J-1143D01*
G02Y179507I0J-1502D01*
G02X1196247Y180149I0J1501D01*
G03X1196108Y180233I-164J-114D01*
G01X1195772Y180276D01*
X1195691Y180252D01*
X1195659Y180224D01*
G02X1194683Y179864I-976J1143D01*
G02X1193400Y180585I0J1502D01*
G01X1193373Y180629D01*
X1193285Y180680D01*
X1192843Y180688D01*
X1192753Y180641D01*
X1192725Y180598D01*
G02X1191472Y179924I-1253J828D01*
G02X1189970Y181426I0J1502D01*
G02X1190541Y182605I1503J0D01*
G01X1190574Y182631D01*
X1190613Y182705D01*
X1190642Y183084D01*
X1190614Y183162D01*
X1190585Y183193D01*
G02X1190178Y184221I1095J1028D01*
G37*
G36*
G01X1087816D02*
G02X1089318Y185723I1502J0D01*
G02X1090438Y185222I0J-1502D01*
G01X1090463Y185193D01*
X1090533Y185159D01*
X1090847Y185134D01*
G03X1090988Y185178I15J199D01*
G02X1091935Y185514I947J-1167D01*
G02X1093437Y184012I0J-1502D01*
G02X1093144Y183121I-1501J0D01*
G01Y183120D01*
X1093121Y183089D01*
X1093102Y183013D01*
X1093154Y182657D01*
X1093195Y182588D01*
X1093226Y182565D01*
G02X1093552Y182226I-906J-1198D01*
G03X1093691Y182142I164J114D01*
G01X1094027Y182099D01*
X1094108Y182123D01*
X1094140Y182151D01*
G02X1095116Y182511I976J-1143D01*
G02Y179507I0J-1502D01*
G02X1093885Y180149I0J1501D01*
G03X1093746Y180233I-164J-114D01*
G01X1093410Y180276D01*
X1093329Y180252D01*
X1093297Y180224D01*
G02X1092321Y179864I-976J1143D01*
G02X1091038Y180585I0J1502D01*
G01X1091011Y180629D01*
X1090923Y180680D01*
X1090481Y180688D01*
X1090391Y180641D01*
X1090363Y180598D01*
G02X1089110Y179924I-1253J828D01*
G02X1087608Y181426I0J1502D01*
G02X1088179Y182605I1503J0D01*
G01X1088212Y182631D01*
X1088251Y182705D01*
X1088280Y183084D01*
X1088252Y183162D01*
X1088223Y183193D01*
G02X1087816Y184221I1095J1028D01*
G37*
G36*
G01X985454D02*
G02X986956Y185723I1502J0D01*
G02X988076Y185222I0J-1502D01*
G01X988101Y185193D01*
X988171Y185159D01*
X988485Y185134D01*
G03X988626Y185178I15J199D01*
G02X989573Y185514I947J-1167D01*
G02X991075Y184012I0J-1502D01*
G02X990782Y183121I-1501J0D01*
G01Y183120D01*
X990759Y183089D01*
X990740Y183013D01*
X990792Y182657D01*
X990833Y182588D01*
X990864Y182565D01*
G02X991190Y182226I-906J-1198D01*
G03X991329Y182142I164J114D01*
G01X991665Y182099D01*
X991746Y182123D01*
X991778Y182151D01*
G02X992754Y182511I976J-1143D01*
G02Y179507I0J-1502D01*
G02X991523Y180149I0J1501D01*
G03X991384Y180233I-164J-114D01*
G01X991048Y180276D01*
X990967Y180252D01*
X990935Y180224D01*
G02X989959Y179864I-976J1143D01*
G02X988676Y180585I0J1502D01*
G01X988649Y180629D01*
X988561Y180680D01*
X988119Y180688D01*
X988029Y180641D01*
X988001Y180598D01*
G02X986748Y179924I-1253J828D01*
G02X985246Y181426I0J1502D01*
G02X985817Y182605I1503J0D01*
G01X985850Y182631D01*
X985889Y182705D01*
X985918Y183084D01*
X985890Y183162D01*
X985861Y183193D01*
G02X985454Y184221I1095J1028D01*
G37*
G36*
G01X835454D02*
G02X836956Y185723I1502J0D01*
G02X838076Y185222I0J-1502D01*
G01X838101Y185193D01*
X838171Y185159D01*
X838485Y185134D01*
G03X838626Y185178I15J199D01*
G02X839573Y185514I947J-1167D01*
G02X841075Y184012I0J-1502D01*
G02X840782Y183121I-1501J0D01*
G01Y183120D01*
X840759Y183089D01*
X840740Y183013D01*
X840792Y182657D01*
X840833Y182588D01*
X840864Y182565D01*
G02X841190Y182226I-906J-1198D01*
G03X841329Y182142I164J114D01*
G01X841665Y182099D01*
X841746Y182123D01*
X841778Y182151D01*
G02X842754Y182511I976J-1143D01*
G02Y179507I0J-1502D01*
G02X841523Y180149I0J1501D01*
G03X841384Y180233I-164J-114D01*
G01X841048Y180276D01*
X840967Y180252D01*
X840935Y180224D01*
G02X839959Y179864I-976J1143D01*
G02X838676Y180585I0J1502D01*
G01X838649Y180629D01*
X838561Y180680D01*
X838119Y180688D01*
X838029Y180641D01*
X838001Y180598D01*
G02X836748Y179924I-1253J828D01*
G02X835246Y181426I0J1502D01*
G02X835817Y182605I1503J0D01*
G01X835850Y182631D01*
X835889Y182705D01*
X835918Y183084D01*
X835890Y183162D01*
X835861Y183193D01*
G02X835454Y184221I1095J1028D01*
G37*
G36*
G01X733092D02*
G02X734594Y185723I1502J0D01*
G02X735714Y185222I0J-1502D01*
G01X735739Y185193D01*
X735809Y185159D01*
X736123Y185134D01*
G03X736264Y185178I15J199D01*
G02X737211Y185514I947J-1167D01*
G02X738713Y184012I0J-1502D01*
G02X738420Y183121I-1501J0D01*
G01Y183120D01*
X738397Y183089D01*
X738378Y183013D01*
X738430Y182657D01*
X738471Y182588D01*
X738502Y182565D01*
G02X738828Y182226I-906J-1198D01*
G03X738967Y182142I164J114D01*
G01X739303Y182099D01*
X739384Y182123D01*
X739416Y182151D01*
G02X740392Y182511I976J-1143D01*
G02Y179507I0J-1502D01*
G02X739161Y180149I0J1501D01*
G03X739022Y180233I-164J-114D01*
G01X738686Y180276D01*
X738605Y180252D01*
X738573Y180224D01*
G02X737597Y179864I-976J1143D01*
G02X736314Y180585I0J1502D01*
G01X736287Y180629D01*
X736199Y180680D01*
X735757Y180688D01*
X735667Y180641D01*
X735639Y180598D01*
G02X734386Y179924I-1253J828D01*
G02X732884Y181426I0J1502D01*
G02X733455Y182605I1503J0D01*
G01X733488Y182631D01*
X733527Y182705D01*
X733556Y183084D01*
X733528Y183162D01*
X733499Y183193D01*
G02X733092Y184221I1095J1028D01*
G37*
G36*
G01X630730D02*
G02X632232Y185723I1502J0D01*
G02X633352Y185222I0J-1502D01*
G01X633377Y185193D01*
X633447Y185159D01*
X633761Y185134D01*
G03X633902Y185178I15J199D01*
G02X634849Y185514I947J-1167D01*
G02X636351Y184012I0J-1502D01*
G02X636058Y183121I-1501J0D01*
G01Y183120D01*
X636035Y183089D01*
X636016Y183013D01*
X636068Y182657D01*
X636109Y182588D01*
X636140Y182565D01*
G02X636466Y182226I-906J-1198D01*
G03X636605Y182142I164J114D01*
G01X636941Y182099D01*
X637022Y182123D01*
X637054Y182151D01*
G02X638030Y182511I976J-1143D01*
G02Y179507I0J-1502D01*
G02X636799Y180149I0J1501D01*
G03X636660Y180233I-164J-114D01*
G01X636324Y180276D01*
X636243Y180252D01*
X636211Y180224D01*
G02X635235Y179864I-976J1143D01*
G02X633952Y180585I0J1502D01*
G01X633925Y180629D01*
X633837Y180680D01*
X633395Y180688D01*
X633305Y180641D01*
X633277Y180598D01*
G02X632024Y179924I-1253J828D01*
G02X630522Y181426I0J1502D01*
G02X631093Y182605I1503J0D01*
G01X631126Y182631D01*
X631165Y182705D01*
X631194Y183084D01*
X631166Y183162D01*
X631137Y183193D01*
G02X630730Y184221I1095J1028D01*
G37*
G36*
G01X528368D02*
G02X529870Y185723I1502J0D01*
G02X530990Y185222I0J-1502D01*
G01X531015Y185193D01*
X531085Y185159D01*
X531399Y185134D01*
G03X531540Y185178I15J199D01*
G02X532487Y185514I947J-1167D01*
G02X533989Y184012I0J-1502D01*
G02X533696Y183121I-1501J0D01*
G01Y183120D01*
X533673Y183089D01*
X533654Y183013D01*
X533706Y182657D01*
X533747Y182588D01*
X533778Y182565D01*
G02X534104Y182226I-906J-1198D01*
G03X534243Y182142I164J114D01*
G01X534579Y182099D01*
X534660Y182123D01*
X534692Y182151D01*
G02X535668Y182511I976J-1143D01*
G02Y179507I0J-1502D01*
G02X534437Y180149I0J1501D01*
G03X534298Y180233I-164J-114D01*
G01X533962Y180276D01*
X533881Y180252D01*
X533849Y180224D01*
G02X532873Y179864I-976J1143D01*
G02X531590Y180585I0J1502D01*
G01X531563Y180629D01*
X531475Y180680D01*
X531033Y180688D01*
X530943Y180641D01*
X530915Y180598D01*
G02X529662Y179924I-1253J828D01*
G02X528160Y181426I0J1502D01*
G02X528731Y182605I1503J0D01*
G01X528764Y182631D01*
X528803Y182705D01*
X528832Y183084D01*
X528804Y183162D01*
X528775Y183193D01*
G02X528368Y184221I1095J1028D01*
G37*
G36*
G01X378367D02*
G02X379869Y185723I1502J0D01*
G02X380989Y185222I0J-1502D01*
G01X381014Y185193D01*
X381084Y185159D01*
X381398Y185134D01*
G03X381539Y185178I15J199D01*
G02X382486Y185514I947J-1167D01*
G02X383988Y184012I0J-1502D01*
G02X383695Y183121I-1501J0D01*
G01Y183120D01*
X383672Y183089D01*
X383653Y183013D01*
X383705Y182657D01*
X383746Y182588D01*
X383777Y182565D01*
G02X384103Y182226I-906J-1198D01*
G03X384242Y182142I164J114D01*
G01X384578Y182099D01*
X384659Y182123D01*
X384691Y182151D01*
G02X385667Y182511I976J-1143D01*
G02Y179507I0J-1502D01*
G02X384436Y180149I0J1501D01*
G03X384297Y180233I-164J-114D01*
G01X383961Y180276D01*
X383880Y180252D01*
X383848Y180224D01*
G02X382872Y179864I-976J1143D01*
G02X381589Y180585I0J1502D01*
G01X381562Y180629D01*
X381474Y180680D01*
X381032Y180688D01*
X380942Y180641D01*
X380914Y180598D01*
G02X379661Y179924I-1253J828D01*
G02X378159Y181426I0J1502D01*
G02X378730Y182605I1503J0D01*
G01X378763Y182631D01*
X378802Y182705D01*
X378831Y183084D01*
X378803Y183162D01*
X378774Y183193D01*
G02X378367Y184221I1095J1028D01*
G37*
G36*
G01X276005D02*
G02X277507Y185723I1502J0D01*
G02X278627Y185222I0J-1502D01*
G01X278652Y185193D01*
X278722Y185159D01*
X279036Y185134D01*
G03X279177Y185178I15J199D01*
G02X280124Y185514I947J-1167D01*
G02X281626Y184012I0J-1502D01*
G02X281333Y183121I-1501J0D01*
G01Y183120D01*
X281310Y183089D01*
X281291Y183013D01*
X281343Y182657D01*
X281384Y182588D01*
X281415Y182565D01*
G02X281741Y182226I-906J-1198D01*
G03X281880Y182142I164J114D01*
G01X282216Y182099D01*
X282297Y182123D01*
X282329Y182151D01*
G02X283305Y182511I976J-1143D01*
G02Y179507I0J-1502D01*
G02X282074Y180149I0J1501D01*
G03X281935Y180233I-164J-114D01*
G01X281599Y180276D01*
X281518Y180252D01*
X281486Y180224D01*
G02X280510Y179864I-976J1143D01*
G02X279227Y180585I0J1502D01*
G01X279200Y180629D01*
X279112Y180680D01*
X278670Y180688D01*
X278580Y180641D01*
X278552Y180598D01*
G02X277299Y179924I-1253J828D01*
G02X275797Y181426I0J1502D01*
G02X276368Y182605I1503J0D01*
G01X276401Y182631D01*
X276440Y182705D01*
X276469Y183084D01*
X276441Y183162D01*
X276412Y183193D01*
G02X276005Y184221I1095J1028D01*
G37*
G36*
G01X173643D02*
G02X175145Y185723I1502J0D01*
G02X176265Y185222I0J-1502D01*
G01X176290Y185193D01*
X176360Y185159D01*
X176674Y185134D01*
G03X176815Y185178I15J199D01*
G02X177762Y185514I947J-1167D01*
G02X179264Y184012I0J-1502D01*
G02X178971Y183121I-1501J0D01*
G01Y183120D01*
X178948Y183089D01*
X178929Y183013D01*
X178981Y182657D01*
X179022Y182588D01*
X179053Y182565D01*
G02X179379Y182226I-906J-1198D01*
G03X179518Y182142I164J114D01*
G01X179854Y182099D01*
X179935Y182123D01*
X179967Y182151D01*
G02X180943Y182511I976J-1143D01*
G02Y179507I0J-1502D01*
G02X179712Y180149I0J1501D01*
G03X179573Y180233I-164J-114D01*
G01X179237Y180276D01*
X179156Y180252D01*
X179124Y180224D01*
G02X178148Y179864I-976J1143D01*
G02X176865Y180585I0J1502D01*
G01X176838Y180629D01*
X176750Y180680D01*
X176308Y180688D01*
X176218Y180641D01*
X176190Y180598D01*
G02X174937Y179924I-1253J828D01*
G02X173435Y181426I0J1502D01*
G02X174006Y182605I1503J0D01*
G01X174039Y182631D01*
X174078Y182705D01*
X174107Y183084D01*
X174079Y183162D01*
X174050Y183193D01*
G02X173643Y184221I1095J1028D01*
G37*
G36*
G01X71281D02*
G02X72783Y185723I1502J0D01*
G02X73903Y185222I0J-1502D01*
G01X73928Y185193D01*
X73998Y185159D01*
X74312Y185134D01*
G03X74453Y185178I15J199D01*
G02X75400Y185514I947J-1167D01*
G02X76902Y184012I0J-1502D01*
G02X76609Y183121I-1501J0D01*
G01Y183120D01*
X76586Y183089D01*
X76567Y183013D01*
X76619Y182657D01*
X76660Y182588D01*
X76691Y182565D01*
G02X77017Y182226I-906J-1198D01*
G03X77156Y182142I164J114D01*
G01X77492Y182099D01*
X77573Y182123D01*
X77605Y182151D01*
G02X78581Y182511I976J-1143D01*
G02Y179507I0J-1502D01*
G02X77350Y180149I0J1501D01*
G03X77211Y180233I-164J-114D01*
G01X76875Y180276D01*
X76794Y180252D01*
X76762Y180224D01*
G02X75786Y179864I-976J1143D01*
G02X74503Y180585I0J1502D01*
G01X74476Y180629D01*
X74388Y180680D01*
X73946Y180688D01*
X73856Y180641D01*
X73828Y180598D01*
G02X72575Y179924I-1253J828D01*
G02X71073Y181426I0J1502D01*
G02X71644Y182605I1503J0D01*
G01X71677Y182631D01*
X71716Y182705D01*
X71745Y183084D01*
X71717Y183162D01*
X71688Y183193D01*
G02X71281Y184221I1095J1028D01*
G37*
G36*
G01X1672089Y151610D02*
G02X1670795Y150871I-1294J763D01*
G02Y153875I0J1502D01*
G02X1671989Y153285I0J-1503D01*
G03X1672651Y153325I318J243D01*
G02X1673945Y154064I1294J-763D01*
G02Y151060I0J-1502D01*
G02X1672751Y151650I0J1503D01*
G03X1672089Y151610I-318J-243D01*
G37*
G36*
G01X1569727D02*
G02X1568433Y150871I-1294J763D01*
G02Y153875I0J1502D01*
G02X1569627Y153285I0J-1503D01*
G03X1570289Y153325I318J243D01*
G02X1571583Y154064I1294J-763D01*
G02Y151060I0J-1502D01*
G02X1570389Y151650I0J1503D01*
G03X1569727Y151610I-318J-243D01*
G37*
G36*
G01X1467365D02*
G02X1466071Y150871I-1294J763D01*
G02Y153875I0J1502D01*
G02X1467265Y153285I0J-1503D01*
G03X1467927Y153325I318J243D01*
G02X1469221Y154064I1294J-763D01*
G02Y151060I0J-1502D01*
G02X1468027Y151650I0J1503D01*
G03X1467365Y151610I-318J-243D01*
G37*
G36*
G01X1365003D02*
G02X1363709Y150871I-1294J763D01*
G02Y153875I0J1502D01*
G02X1364903Y153285I0J-1503D01*
G03X1365565Y153325I318J243D01*
G02X1366859Y154064I1294J-763D01*
G02Y151060I0J-1502D01*
G02X1365665Y151650I0J1503D01*
G03X1365003Y151610I-318J-243D01*
G37*
G36*
G01X1112640D02*
G02X1111346Y150871I-1294J763D01*
G02Y153875I0J1502D01*
G02X1112540Y153285I0J-1503D01*
G03X1113202Y153325I318J243D01*
G02X1114496Y154064I1294J-763D01*
G02Y151060I0J-1502D01*
G02X1113302Y151650I0J1503D01*
G03X1112640Y151610I-318J-243D01*
G37*
G36*
G01X1010278D02*
G02X1008984Y150871I-1294J763D01*
G02Y153875I0J1502D01*
G02X1010178Y153285I0J-1503D01*
G03X1010840Y153325I318J243D01*
G02X1012134Y154064I1294J-763D01*
G02Y151060I0J-1502D01*
G02X1010940Y151650I0J1503D01*
G03X1010278Y151610I-318J-243D01*
G37*
G36*
G01X907916D02*
G02X906622Y150871I-1294J763D01*
G02Y153875I0J1502D01*
G02X907816Y153285I0J-1503D01*
G03X908478Y153325I318J243D01*
G02X909772Y154064I1294J-763D01*
G02Y151060I0J-1502D01*
G02X908578Y151650I0J1503D01*
G03X907916Y151610I-318J-243D01*
G37*
G36*
G01X757916D02*
G02X756622Y150871I-1294J763D01*
G02Y153875I0J1502D01*
G02X757816Y153285I0J-1503D01*
G03X758478Y153325I318J243D01*
G02X759772Y154064I1294J-763D01*
G02Y151060I0J-1502D01*
G02X758578Y151650I0J1503D01*
G03X757916Y151610I-318J-243D01*
G37*
G36*
G01X655554D02*
G02X654260Y150871I-1294J763D01*
G02Y153875I0J1502D01*
G02X655454Y153285I0J-1503D01*
G03X656116Y153325I318J243D01*
G02X657410Y154064I1294J-763D01*
G02Y151060I0J-1502D01*
G02X656216Y151650I0J1503D01*
G03X655554Y151610I-318J-243D01*
G37*
G36*
G01X553192D02*
G02X551898Y150871I-1294J763D01*
G02Y153875I0J1502D01*
G02X553092Y153285I0J-1503D01*
G03X553754Y153325I318J243D01*
G02X555048Y154064I1294J-763D01*
G02Y151060I0J-1502D01*
G02X553854Y151650I0J1503D01*
G03X553192Y151610I-318J-243D01*
G37*
G36*
G01X450830D02*
G02X449536Y150871I-1294J763D01*
G02Y153875I0J1502D01*
G02X450730Y153285I0J-1503D01*
G03X451392Y153325I318J243D01*
G02X452686Y154064I1294J-763D01*
G02Y151060I0J-1502D01*
G02X451492Y151650I0J1503D01*
G03X450830Y151610I-318J-243D01*
G37*
G36*
G01X300829D02*
G02X299535Y150871I-1294J763D01*
G02Y153875I0J1502D01*
G02X300729Y153285I0J-1503D01*
G03X301391Y153325I318J243D01*
G02X302685Y154064I1294J-763D01*
G02Y151060I0J-1502D01*
G02X301491Y151650I0J1503D01*
G03X300829Y151610I-318J-243D01*
G37*
G36*
G01X198467D02*
G02X197173Y150871I-1294J763D01*
G02Y153875I0J1502D01*
G02X198367Y153285I0J-1503D01*
G03X199029Y153325I318J243D01*
G02X200323Y154064I1294J-763D01*
G02Y151060I0J-1502D01*
G02X199129Y151650I0J1503D01*
G03X198467Y151610I-318J-243D01*
G37*
G36*
G01X96105D02*
G02X94811Y150871I-1294J763D01*
G02Y153875I0J1502D01*
G02X96005Y153285I0J-1503D01*
G03X96667Y153325I318J243D01*
G02X97961Y154064I1294J-763D01*
G02Y151060I0J-1502D01*
G02X96767Y151650I0J1503D01*
G03X96105Y151610I-318J-243D01*
G37*
G36*
G01X91100Y143321D02*
G02X90835Y144172I1237J852D01*
G02X93839I1502J0D01*
G02X92696Y142713I-1503J0D01*
G03X92461Y142098I95J-389D01*
G02X92726Y141247I-1237J-852D01*
G02X89722I-1502J0D01*
G02X90865Y142706I1503J0D01*
G03X91100Y143321I-95J389D01*
G37*
G36*
G01X1712652Y105360D02*
G02X1712051Y106561I901J1202D01*
G02X1715055I1502J0D01*
G02X1714329Y105275I-1502J0D01*
G03X1714295Y104612I206J-343D01*
G02X1714896Y103411I-901J-1202D01*
G02X1711892I-1502J0D01*
G02X1712618Y104697I1502J0D01*
G03X1712652Y105360I-206J343D01*
G37*
G36*
G01X1610290D02*
G02X1609689Y106561I901J1202D01*
G02X1612693I1502J0D01*
G02X1611967Y105275I-1502J0D01*
G03X1611933Y104612I206J-343D01*
G02X1612534Y103411I-901J-1202D01*
G02X1609530I-1502J0D01*
G02X1610256Y104697I1502J0D01*
G03X1610290Y105360I-206J343D01*
G37*
G36*
G01X1507928D02*
G02X1507327Y106561I901J1202D01*
G02X1510331I1502J0D01*
G02X1509605Y105275I-1502J0D01*
G03X1509571Y104612I206J-343D01*
G02X1510172Y103411I-901J-1202D01*
G02X1507168I-1502J0D01*
G02X1507894Y104697I1502J0D01*
G03X1507928Y105360I-206J343D01*
G37*
G36*
G01X1405566D02*
G02X1404965Y106561I901J1202D01*
G02X1407969I1502J0D01*
G02X1407243Y105275I-1502J0D01*
G03X1407209Y104612I206J-343D01*
G02X1407810Y103411I-901J-1202D01*
G02X1404806I-1502J0D01*
G02X1405532Y104697I1502J0D01*
G03X1405566Y105360I-206J343D01*
G37*
G36*
G01X1255565D02*
G02X1254964Y106561I901J1202D01*
G02X1257968I1502J0D01*
G02X1257242Y105275I-1502J0D01*
G03X1257208Y104612I206J-343D01*
G02X1257809Y103411I-901J-1202D01*
G02X1254805I-1502J0D01*
G02X1255531Y104697I1502J0D01*
G03X1255565Y105360I-206J343D01*
G37*
G36*
G01X1153203D02*
G02X1152602Y106561I901J1202D01*
G02X1155606I1502J0D01*
G02X1154880Y105275I-1502J0D01*
G03X1154846Y104612I206J-343D01*
G02X1155447Y103411I-901J-1202D01*
G02X1152443I-1502J0D01*
G02X1153169Y104697I1502J0D01*
G03X1153203Y105360I-206J343D01*
G37*
G36*
G01X1050841D02*
G02X1050240Y106561I901J1202D01*
G02X1053244I1502J0D01*
G02X1052518Y105275I-1502J0D01*
G03X1052484Y104612I206J-343D01*
G02X1053085Y103411I-901J-1202D01*
G02X1050081I-1502J0D01*
G02X1050807Y104697I1502J0D01*
G03X1050841Y105360I-206J343D01*
G37*
G36*
G01X948479D02*
G02X947878Y106561I901J1202D01*
G02X950882I1502J0D01*
G02X950156Y105275I-1502J0D01*
G03X950122Y104612I206J-343D01*
G02X950723Y103411I-901J-1202D01*
G02X947719I-1502J0D01*
G02X948445Y104697I1502J0D01*
G03X948479Y105360I-206J343D01*
G37*
G36*
G01X798479D02*
G02X797878Y106561I901J1202D01*
G02X800882I1502J0D01*
G02X800156Y105275I-1502J0D01*
G03X800122Y104612I206J-343D01*
G02X800723Y103411I-901J-1202D01*
G02X797719I-1502J0D01*
G02X798445Y104697I1502J0D01*
G03X798479Y105360I-206J343D01*
G37*
G36*
G01X696117D02*
G02X695516Y106561I901J1202D01*
G02X698520I1502J0D01*
G02X697794Y105275I-1502J0D01*
G03X697760Y104612I206J-343D01*
G02X698361Y103411I-901J-1202D01*
G02X695357I-1502J0D01*
G02X696083Y104697I1502J0D01*
G03X696117Y105360I-206J343D01*
G37*
G36*
G01X593755D02*
G02X593154Y106561I901J1202D01*
G02X596158I1502J0D01*
G02X595432Y105275I-1502J0D01*
G03X595398Y104612I206J-343D01*
G02X595999Y103411I-901J-1202D01*
G02X592995I-1502J0D01*
G02X593721Y104697I1502J0D01*
G03X593755Y105360I-206J343D01*
G37*
G36*
G01X491393D02*
G02X490792Y106561I901J1202D01*
G02X493796I1502J0D01*
G02X493070Y105275I-1502J0D01*
G03X493036Y104612I206J-343D01*
G02X493637Y103411I-901J-1202D01*
G02X490633I-1502J0D01*
G02X491359Y104697I1502J0D01*
G03X491393Y105360I-206J343D01*
G37*
G36*
G01X341392D02*
G02X340791Y106561I901J1202D01*
G02X343795I1502J0D01*
G02X343069Y105275I-1502J0D01*
G03X343035Y104612I206J-343D01*
G02X343636Y103411I-901J-1202D01*
G02X340632I-1502J0D01*
G02X341358Y104697I1502J0D01*
G03X341392Y105360I-206J343D01*
G37*
G36*
G01X239030D02*
G02X238429Y106561I901J1202D01*
G02X241433I1502J0D01*
G02X240707Y105275I-1502J0D01*
G03X240673Y104612I206J-343D01*
G02X241274Y103411I-901J-1202D01*
G02X238270I-1502J0D01*
G02X238996Y104697I1502J0D01*
G03X239030Y105360I-206J343D01*
G37*
G36*
G01X136668D02*
G02X136067Y106561I901J1202D01*
G02X139071I1502J0D01*
G02X138345Y105275I-1502J0D01*
G03X138311Y104612I206J-343D01*
G02X138912Y103411I-901J-1202D01*
G02X135908I-1502J0D01*
G02X136634Y104697I1502J0D01*
G03X136668Y105360I-206J343D01*
G37*
G36*
G01X34306D02*
G02X33705Y106561I901J1202D01*
G02X36709I1502J0D01*
G02X35983Y105275I-1502J0D01*
G03X35949Y104612I206J-343D01*
G02X36550Y103411I-901J-1202D01*
G02X33546I-1502J0D01*
G02X34272Y104697I1502J0D01*
G03X34306Y105360I-206J343D01*
G37*
G36*
G01X1450830Y33256D02*
G02X1449685Y32726I-1145J972D01*
G02Y35730I0J1502D01*
G02X1450935Y35061I0J-1502D01*
G03X1451572Y35024I332J222D01*
G02X1452717Y35554I1145J-972D01*
G02Y32550I0J-1502D01*
G02X1451467Y33219I0J1502D01*
G03X1450830Y33256I-332J-222D01*
G37*
G36*
G01X1329461Y32041D02*
G02X1328003Y30901I-1458J362D01*
G02Y33905I0J1502D01*
G01X1328004D01*
G02X1328970Y33553I0J-1502D01*
G03X1329615Y33762I257J306D01*
G02X1331073Y34902I1458J-362D01*
G02Y31898I0J-1502D01*
G01X1331072D01*
G02X1330106Y32250I0J1502D01*
G03X1329461Y32041I-257J-306D01*
G37*
G36*
G01X415318Y32063D02*
G02X413904Y31067I-1414J506D01*
G02Y34071I0J1502D01*
G02X414856Y33731I0J-1503D01*
G03X415486Y33906I253J310D01*
G02X416900Y34902I1414J-506D01*
G02Y31898I0J-1502D01*
G02X415948Y32238I0J1503D01*
G03X415318Y32063I-253J-310D01*
G37*
G36*
G01X368376Y947702D02*
X368679Y947918D01*
X368722Y947987D01*
X368728Y948028D01*
G02X370214Y949314I1486J-216D01*
G02Y946310I0J-1502D01*
G02X370028Y946322I4J1502D01*
G01X369987Y946327D01*
X369909Y946304D01*
X369620Y946069D01*
X369583Y945997D01*
X369580Y945956D01*
G02X369555Y945771I-1636J127D01*
G01X369545Y945723D01*
X369572Y945631D01*
X369864Y945324D01*
X369955Y945292D01*
X370004Y945299D01*
G02X370214Y945314I212J-1487D01*
G02X368712Y943812I0J-1502D01*
G02X368727Y944022I1502J-2D01*
G01X368734Y944071D01*
X368702Y944162D01*
X368395Y944454D01*
X368303Y944481D01*
X368255Y944471D01*
G02X367944Y944442I-307J1611D01*
G02Y947722I0J1640D01*
G02X368256Y947693I5J-1640D01*
G01X368297Y947685D01*
X368376Y947702D01*
G37*
G36*
G01X77030Y948279D02*
G02X76665Y949261I1137J982D01*
G02X79669I1502J0D01*
G02X78375Y947773I-1503J0D01*
G03X78128Y947116I56J-396D01*
G02X78493Y946134I-1137J-982D01*
G02X75489I-1502J0D01*
G02X76783Y947622I1503J0D01*
G03X77030Y948279I-56J396D01*
G37*
G36*
G01X102572Y1008703D02*
X102278D01*
G03X102131Y1008638I1J-200D01*
G02X101025Y1008153I-1105J1017D01*
G02Y1011157I0J1502D01*
G02X102131Y1010672I1J-1502D01*
G03X102278Y1010607I148J135D01*
G01X102572D01*
G03X102719Y1010672I-1J200D01*
G02X103825Y1011157I1105J-1017D01*
G02Y1008153I0J-1502D01*
G02X102719Y1008638I-1J1502D01*
G03X102572Y1008703I-148J-135D01*
G37*
G36*
G01X92457Y1005787D02*
G02X91128Y1004985I-1329J700D01*
G02Y1007989I0J1502D01*
G02X92382Y1007314I0J-1502D01*
G03X93069Y1007348I333J221D01*
G02X94398Y1008150I1329J-700D01*
G02Y1005146I0J-1502D01*
G02X93144Y1005821I0J1502D01*
G03X92457Y1005787I-333J-221D01*
G37*
G36*
G01X183178Y1114197D02*
X183169Y1114246D01*
G02X183148Y1114468I1181J224D01*
G02X184350Y1113266I1202J0D01*
G02X184128Y1113287I2J1202D01*
G01X184079Y1113296D01*
X183986Y1113267D01*
X183681Y1112962D01*
X183652Y1112869D01*
X183661Y1112820D01*
G02X183682Y1112598I-1181J-224D01*
G02X181278I-1202J0D01*
G02X181299Y1112820I1202J-2D01*
G01X181308Y1112869D01*
X181279Y1112962D01*
X180974Y1113267D01*
X180881Y1113296D01*
X180832Y1113287D01*
G02X180610Y1113266I-224J1181D01*
G02X180388Y1113287I2J1202D01*
G01X180339Y1113296D01*
X180246Y1113267D01*
X179941Y1112962D01*
X179912Y1112869D01*
X179921Y1112820D01*
G02X179942Y1112598I-1181J-224D01*
G02X177538I-1202J0D01*
G02X177559Y1112820I1202J-2D01*
G01X177568Y1112869D01*
X177539Y1112962D01*
X177234Y1113267D01*
X177141Y1113296D01*
X177092Y1113287D01*
G02X176870Y1113266I-224J1181D01*
G02X178072Y1114468I0J1202D01*
G02X178051Y1114246I-1202J2D01*
G01X178042Y1114197D01*
X178071Y1114104D01*
X178376Y1113799D01*
X178469Y1113770D01*
X178518Y1113779D01*
G02X178740Y1113800I224J-1181D01*
G02X178962Y1113779I-2J-1202D01*
G01X179011Y1113770D01*
X179104Y1113799D01*
X179409Y1114104D01*
X179438Y1114197D01*
X179429Y1114246D01*
G02X179408Y1114468I1181J224D01*
G02X181812I1202J0D01*
G02X181791Y1114246I-1202J2D01*
G01X181782Y1114197D01*
X181811Y1114104D01*
X182116Y1113799D01*
X182209Y1113770D01*
X182258Y1113779D01*
G02X182480Y1113800I224J-1181D01*
G02X182702Y1113779I-2J-1202D01*
G01X182751Y1113770D01*
X182844Y1113799D01*
X183149Y1114104D01*
X183178Y1114197D01*
G37*
G36*
G01X356538Y1186651D02*
X356635Y1187039D01*
X356617Y1187126D01*
X356590Y1187162D01*
G02X356294Y1188058I1206J895D01*
G02X359298I1502J0D01*
G02X358439Y1186700I-1503J0D01*
G01X358398Y1186681D01*
X358341Y1186612D01*
X358244Y1186224D01*
X358262Y1186137D01*
X358289Y1186101D01*
G02X358585Y1185205I-1206J-895D01*
G02X355581I-1502J0D01*
G02X356440Y1186563I1503J0D01*
G01X356481Y1186582D01*
X356538Y1186651D01*
G37*
G36*
G01X338582Y1195694D02*
X338224Y1195628D01*
X338159Y1195586D01*
X338136Y1195552D01*
G02X336901Y1194905I-1235J855D01*
G02Y1197909I0J1502D01*
G02X337750Y1197646I0J-1502D01*
G01X337783Y1197623D01*
X337859Y1197607D01*
X338217Y1197673D01*
X338282Y1197715D01*
X338305Y1197749D01*
G02X339540Y1198396I1235J-855D01*
G02Y1195392I0J-1502D01*
G02X338691Y1195655I0J1502D01*
G01X338658Y1195678D01*
X338582Y1195694D01*
G37*
G36*
G01X402921Y1199403D02*
Y1199739D01*
X402896Y1199806D01*
X402872Y1199834D01*
G02X402502Y1200821I1131J987D01*
G02X405506I1502J0D01*
G02X405136Y1199834I-1501J0D01*
G01X405112Y1199806D01*
X405087Y1199739D01*
Y1199403D01*
X405112Y1199336D01*
X405136Y1199308D01*
G02X405506Y1198321I-1131J-987D01*
G02X402502I-1502J0D01*
G02X402872Y1199308I1501J0D01*
G01X402896Y1199336D01*
X402921Y1199403D01*
G37*
G36*
G01X416386D02*
Y1199739D01*
X416361Y1199806D01*
X416337Y1199834D01*
G02X415967Y1200821I1131J987D01*
G02X418971I1502J0D01*
G02X418601Y1199834I-1501J0D01*
G01X418577Y1199806D01*
X418552Y1199739D01*
Y1199403D01*
X418577Y1199336D01*
X418601Y1199308D01*
G02X418971Y1198321I-1131J-987D01*
G02X415967I-1502J0D01*
G02X416337Y1199308I1501J0D01*
G01X416361Y1199336D01*
X416386Y1199403D01*
G37*
G36*
G01X421851D02*
Y1199739D01*
X421826Y1199806D01*
X421802Y1199834D01*
G02X421432Y1200821I1131J987D01*
G02X424436I1502J0D01*
G02X424066Y1199834I-1501J0D01*
G01X424042Y1199806D01*
X424017Y1199739D01*
Y1199403D01*
X424042Y1199336D01*
X424066Y1199308D01*
G02X424436Y1198321I-1131J-987D01*
G02X421432I-1502J0D01*
G02X421802Y1199308I1501J0D01*
G01X421826Y1199336D01*
X421851Y1199403D01*
G37*
G36*
G01X429851D02*
Y1199739D01*
X429826Y1199806D01*
X429802Y1199834D01*
G02X429432Y1200821I1131J987D01*
G02X432436I1502J0D01*
G02X432066Y1199834I-1501J0D01*
G01X432042Y1199806D01*
X432017Y1199739D01*
Y1199403D01*
X432042Y1199336D01*
X432066Y1199308D01*
G02X432436Y1198321I-1131J-987D01*
G02X429432I-1502J0D01*
G02X429802Y1199308I1501J0D01*
G01X429826Y1199336D01*
X429851Y1199403D01*
G37*
G36*
G01X448781D02*
Y1199739D01*
X448756Y1199806D01*
X448732Y1199834D01*
G02X448362Y1200821I1131J987D01*
G02X451366I1502J0D01*
G02X450996Y1199834I-1501J0D01*
G01X450972Y1199806D01*
X450947Y1199739D01*
Y1199403D01*
X450972Y1199336D01*
X450996Y1199308D01*
G02X451366Y1198321I-1131J-987D01*
G02X448362I-1502J0D01*
G02X448732Y1199308I1501J0D01*
G01X448756Y1199336D01*
X448781Y1199403D01*
G37*
G36*
G01X405236Y1210487D02*
Y1210823D01*
X405211Y1210890D01*
X405187Y1210918D01*
G02X404817Y1211905I1131J987D01*
G02X407821I1502J0D01*
G02X407451Y1210918I-1501J0D01*
G01X407427Y1210890D01*
X407402Y1210823D01*
Y1210487D01*
X407427Y1210420D01*
X407451Y1210392D01*
G02Y1208418I-1131J-987D01*
G01X407427Y1208390D01*
X407402Y1208323D01*
Y1207987D01*
X407427Y1207920D01*
X407451Y1207892D01*
G02Y1205918I-1131J-987D01*
G01X407427Y1205890D01*
X407402Y1205823D01*
Y1205487D01*
X407427Y1205420D01*
X407451Y1205392D01*
G02X407821Y1204405I-1131J-987D01*
G02X404817I-1502J0D01*
G02X405187Y1205392I1501J0D01*
G01X405211Y1205420D01*
X405236Y1205487D01*
Y1205823D01*
X405211Y1205890D01*
X405187Y1205918D01*
G02Y1207892I1131J987D01*
G01X405211Y1207920D01*
X405236Y1207987D01*
Y1208323D01*
X405211Y1208390D01*
X405187Y1208418D01*
G02Y1210392I1131J987D01*
G01X405211Y1210420D01*
X405236Y1210487D01*
G37*
G36*
G01X432166D02*
Y1210823D01*
X432141Y1210890D01*
X432117Y1210918D01*
G02X431747Y1211905I1131J987D01*
G02X434751I1502J0D01*
G02X434381Y1210918I-1501J0D01*
G01X434357Y1210890D01*
X434332Y1210823D01*
Y1210487D01*
X434357Y1210420D01*
X434381Y1210392D01*
G02Y1208418I-1131J-987D01*
G01X434357Y1208390D01*
X434332Y1208323D01*
Y1207987D01*
X434357Y1207920D01*
X434381Y1207892D01*
G02Y1205918I-1131J-987D01*
G01X434357Y1205890D01*
X434332Y1205823D01*
Y1205487D01*
X434357Y1205420D01*
X434381Y1205392D01*
G02X434751Y1204405I-1131J-987D01*
G02X431747I-1502J0D01*
G02X432117Y1205392I1501J0D01*
G01X432141Y1205420D01*
X432166Y1205487D01*
Y1205823D01*
X432141Y1205890D01*
X432117Y1205918D01*
G02Y1207892I1131J987D01*
G01X432141Y1207920D01*
X432166Y1207987D01*
Y1208323D01*
X432141Y1208390D01*
X432117Y1208418D01*
G02Y1210392I1131J987D01*
G01X432141Y1210420D01*
X432166Y1210487D01*
G37*
G36*
G01X419536Y1210699D02*
Y1211035D01*
X419511Y1211102D01*
X419487Y1211130D01*
G02X419117Y1212117I1131J987D01*
G02X422121I1502J0D01*
G02X421751Y1211130I-1501J0D01*
G01X421727Y1211102D01*
X421702Y1211035D01*
Y1210699D01*
X421727Y1210632D01*
X421751Y1210604D01*
G02Y1208630I-1131J-987D01*
G01X421727Y1208602D01*
X421702Y1208535D01*
Y1208199D01*
X421727Y1208132D01*
X421751Y1208104D01*
G02Y1206130I-1131J-987D01*
G01X421727Y1206102D01*
X421702Y1206035D01*
Y1205699D01*
X421727Y1205632D01*
X421751Y1205604D01*
G02X422121Y1204617I-1131J-987D01*
G02X419117I-1502J0D01*
G02X419487Y1205604I1501J0D01*
G01X419511Y1205632D01*
X419536Y1205699D01*
Y1206035D01*
X419511Y1206102D01*
X419487Y1206130D01*
G02Y1208104I1131J987D01*
G01X419511Y1208132D01*
X419536Y1208199D01*
Y1208535D01*
X419511Y1208602D01*
X419487Y1208630D01*
G02Y1210604I1131J987D01*
G01X419511Y1210632D01*
X419536Y1210699D01*
G37*
G36*
G01X446466D02*
Y1211035D01*
X446441Y1211102D01*
X446417Y1211130D01*
G02X446047Y1212117I1131J987D01*
G02X449051I1502J0D01*
G02X448681Y1211130I-1501J0D01*
G01X448657Y1211102D01*
X448632Y1211035D01*
Y1210699D01*
X448657Y1210632D01*
X448681Y1210604D01*
G02Y1208630I-1131J-987D01*
G01X448657Y1208602D01*
X448632Y1208535D01*
Y1208199D01*
X448657Y1208132D01*
X448681Y1208104D01*
G02Y1206130I-1131J-987D01*
G01X448657Y1206102D01*
X448632Y1206035D01*
Y1205699D01*
X448657Y1205632D01*
X448681Y1205604D01*
G02X449051Y1204617I-1131J-987D01*
G02X446047I-1502J0D01*
G02X446417Y1205604I1501J0D01*
G01X446441Y1205632D01*
X446466Y1205699D01*
Y1206035D01*
X446441Y1206102D01*
X446417Y1206130D01*
G02Y1208104I1131J987D01*
G01X446441Y1208132D01*
X446466Y1208199D01*
Y1208535D01*
X446441Y1208602D01*
X446417Y1208630D01*
G02Y1210604I1131J987D01*
G01X446441Y1210632D01*
X446466Y1210699D01*
G37*
G36*
G01X445044Y1261006D02*
X445360D01*
G03X445517Y1261083I-1J200D01*
G02X447887I1185J-923D01*
G03X448044Y1261006I158J123D01*
G01X448360D01*
G03X448517Y1261083I-1J200D01*
G02X449702Y1261662I1185J-923D01*
G02X451204Y1260160I0J-1502D01*
G02X450625Y1258975I-1502J0D01*
G03X450548Y1258818I123J-158D01*
G01Y1258502D01*
G03X450625Y1258345I200J1D01*
G02X451204Y1257160I-923J-1185D01*
G02X449702Y1255658I-1502J0D01*
G02X448517Y1256237I0J1502D01*
G03X448360Y1256314I-158J-123D01*
G01X448044D01*
G03X447887Y1256237I1J-200D01*
G02X445517I-1185J923D01*
G03X445360Y1256314I-158J-123D01*
G01X445044D01*
G03X444887Y1256237I1J-200D01*
G02X442517I-1185J923D01*
G03X442360Y1256314I-158J-123D01*
G01X442044D01*
G03X441887Y1256237I1J-200D01*
G02X439517I-1185J923D01*
G03X439360Y1256314I-158J-123D01*
G01X439044D01*
G03X438887Y1256237I1J-200D01*
G02X436517I-1185J923D01*
G03X436360Y1256314I-158J-123D01*
G01X436044D01*
G03X435887Y1256237I1J-200D01*
G02X433517I-1185J923D01*
G03X433360Y1256314I-158J-123D01*
G01X433044D01*
G03X432887Y1256237I1J-200D01*
G02X430517I-1185J923D01*
G03X430360Y1256314I-158J-123D01*
G01X430044D01*
G03X429887Y1256237I1J-200D01*
G02X427517I-1185J923D01*
G03X427360Y1256314I-158J-123D01*
G01X427044D01*
G03X426887Y1256237I1J-200D01*
G02X424517I-1185J923D01*
G03X424360Y1256314I-158J-123D01*
G01X424044D01*
G03X423887Y1256237I1J-200D01*
G02X421517I-1185J923D01*
G03X421360Y1256314I-158J-123D01*
G01X421044D01*
G03X420887Y1256237I1J-200D01*
G02X419702Y1255658I-1185J923D01*
G02X418200Y1257160I0J1502D01*
G02X418779Y1258345I1502J0D01*
G03X418856Y1258502I-123J158D01*
G01Y1258818D01*
G03X418779Y1258975I-200J-1D01*
G02X418200Y1260160I923J1185D01*
G02X419702Y1261662I1502J0D01*
G02X420887Y1261083I0J-1502D01*
G03X421044Y1261006I158J123D01*
G01X421360D01*
G03X421517Y1261083I-1J200D01*
G02X423887I1185J-923D01*
G03X424044Y1261006I158J123D01*
G01X424360D01*
G03X424517Y1261083I-1J200D01*
G02X426887I1185J-923D01*
G03X427044Y1261006I158J123D01*
G01X427360D01*
G03X427517Y1261083I-1J200D01*
G02X429887I1185J-923D01*
G03X430044Y1261006I158J123D01*
G01X430360D01*
G03X430517Y1261083I-1J200D01*
G02X432887I1185J-923D01*
G03X433044Y1261006I158J123D01*
G01X433360D01*
G03X433517Y1261083I-1J200D01*
G02X435887I1185J-923D01*
G03X436044Y1261006I158J123D01*
G01X436360D01*
G03X436517Y1261083I-1J200D01*
G02X438887I1185J-923D01*
G03X439044Y1261006I158J123D01*
G01X439360D01*
G03X439517Y1261083I-1J200D01*
G02X441887I1185J-923D01*
G03X442044Y1261006I158J123D01*
G01X442360D01*
G03X442517Y1261083I-1J200D01*
G02X444887I1185J-923D01*
G03X445044Y1261006I158J123D01*
G37*
G36*
G01X213099Y1110457D02*
X213090Y1110506D01*
G02X213069Y1110728I1181J224D01*
G02X215473I1202J0D01*
G02X215452Y1110506I-1202J2D01*
G01X215443Y1110457D01*
X215472Y1110364D01*
X215777Y1110059D01*
X215870Y1110030D01*
X215919Y1110039D01*
G02X216141Y1110060I224J-1181D01*
G02X214939Y1108858I0J-1202D01*
G02X214960Y1109080I1202J-2D01*
G01X214969Y1109129D01*
X214940Y1109222D01*
X214635Y1109527D01*
X214542Y1109556D01*
X214493Y1109547D01*
G02X214271Y1109526I-224J1181D01*
G02X214049Y1109547I2J1202D01*
G01X214000Y1109556D01*
X213907Y1109527D01*
X213602Y1109222D01*
X213573Y1109129D01*
X213582Y1109080D01*
G02X213603Y1108858I-1181J-224D01*
G02X212401Y1110060I-1202J0D01*
G02X212623Y1110039I-2J-1202D01*
G01X212672Y1110030D01*
X212765Y1110059D01*
X213070Y1110364D01*
X213099Y1110457D01*
G37*
G36*
G01X356373Y1134122D02*
X356354Y1134169D01*
G02X356246Y1134729I1394J559D01*
G02X359250I1502J0D01*
G02X357746Y1133227I-1502J0D01*
G01X357695D01*
X357606Y1133180D01*
X357366Y1132815D01*
X357358Y1132715D01*
X357378Y1132668D01*
G02X357508Y1132042I-1449J-627D01*
G02X354350I-1579J0D01*
G02X354494Y1132699I1579J-2D01*
G01X354518Y1132751D01*
X354504Y1132863D01*
X354211Y1133231D01*
X354105Y1133269D01*
X354050Y1133258D01*
G02X353748Y1133227I-304J1471D01*
G02X353547Y1133241I4J1502D01*
G01X353498Y1133247D01*
X353406Y1133214D01*
X353117Y1132899D01*
X353092Y1132805D01*
X353103Y1132756D01*
G02X353142Y1132410I-1540J-349D01*
G02X349984I-1579J0D01*
G02X350021Y1132746I1579J-4D01*
G01X350030Y1132789D01*
X350011Y1132874D01*
X349775Y1133186D01*
X349698Y1133227D01*
X349655Y1133230D01*
G02X348413Y1134041I93J1499D01*
G01X348387Y1134092D01*
X348292Y1134150D01*
X347822D01*
X347727Y1134092D01*
X347701Y1134041D01*
G02X346366Y1133227I-1335J688D01*
G02Y1136231I0J1502D01*
G02X347701Y1135417I0J-1502D01*
G01X347727Y1135366D01*
X347822Y1135308D01*
X348292D01*
X348387Y1135366D01*
X348413Y1135417D01*
G02X349748Y1136231I1335J-688D01*
G02X351250Y1134729I0J-1502D01*
G02X351226Y1134459I-1502J-3D01*
G01X351218Y1134416D01*
X351239Y1134332D01*
X351486Y1134028D01*
X351564Y1133989D01*
X351608Y1133988D01*
G02X351817Y1133968I-46J-1578D01*
G01X351866Y1133960D01*
X351959Y1133991D01*
X352256Y1134298D01*
X352284Y1134391D01*
X352274Y1134440D01*
G02X352246Y1134729I1474J289D01*
G02X355250I1502J0D01*
G02X355126Y1134131I-1502J0D01*
G01X355103Y1134079D01*
X355119Y1133968D01*
X355419Y1133605D01*
X355526Y1133569D01*
X355581Y1133582D01*
G02X355929Y1133620I344J-1540D01*
G01X355972D01*
X356023Y1133619D01*
X356113Y1133664D01*
X356362Y1134022D01*
X356373Y1134122D01*
G37*
G36*
G01X325304Y1136638D02*
X325295Y1136687D01*
G02X325274Y1136909I1181J224D01*
G02X326476Y1135707I1202J0D01*
G02X326254Y1135728I2J1202D01*
G01X326205Y1135737D01*
X326112Y1135708D01*
X325807Y1135403D01*
X325778Y1135310D01*
X325787Y1135261D01*
G02X325808Y1135039I-1181J-224D01*
G02X323404I-1202J0D01*
G02X323425Y1135261I1202J-2D01*
G01X323434Y1135310D01*
X323405Y1135403D01*
X323100Y1135708D01*
X323007Y1135737D01*
X322958Y1135728D01*
G02X322736Y1135707I-224J1181D01*
G02X322514Y1135728I2J1202D01*
G01X322465Y1135737D01*
X322372Y1135708D01*
X322067Y1135403D01*
X322038Y1135310D01*
X322047Y1135261D01*
G02X322068Y1135039I-1181J-224D01*
G02X319664I-1202J0D01*
G02X319685Y1135261I1202J-2D01*
G01X319694Y1135310D01*
X319665Y1135403D01*
X319360Y1135708D01*
X319267Y1135737D01*
X319218Y1135728D01*
G02X318996Y1135707I-224J1181D01*
G02X318841Y1135717I0J1202D01*
G01X318793Y1135723D01*
X318704Y1135692D01*
X318414Y1135391D01*
X318386Y1135301D01*
X318394Y1135254D01*
G02X318412Y1135039I-1269J-214D01*
G02X315838I-1287J0D01*
G02X315856Y1135254I1287J1D01*
G01X315863Y1135301D01*
X315836Y1135391D01*
X315546Y1135692D01*
X315457Y1135723D01*
X315410Y1135717D01*
G02X315255Y1135707I-155J1192D01*
G02X315100Y1135717I0J1202D01*
G01X315053Y1135723D01*
X314964Y1135692D01*
X314674Y1135391D01*
X314647Y1135301D01*
X314654Y1135254D01*
G02X314672Y1135039I-1269J-214D01*
G02X312098I-1287J0D01*
G02X312116Y1135254I1287J1D01*
G01X312123Y1135301D01*
X312096Y1135391D01*
X311806Y1135692D01*
X311717Y1135723D01*
X311670Y1135717D01*
G02X311515Y1135707I-155J1192D01*
G02X311293Y1135728I2J1202D01*
G01X311244Y1135737D01*
X311151Y1135708D01*
X310846Y1135403D01*
X310817Y1135310D01*
X310826Y1135261D01*
G02X310847Y1135039I-1181J-224D01*
G02X309645Y1136241I-1202J0D01*
G02X309867Y1136220I-2J-1202D01*
G01X309916Y1136211D01*
X310009Y1136240D01*
X310314Y1136545D01*
X310343Y1136638D01*
X310334Y1136687D01*
G02X310313Y1136909I1181J224D01*
G02X312717I1202J0D01*
G02X312707Y1136754I-1202J0D01*
G01X312701Y1136707D01*
X312732Y1136618D01*
X313033Y1136328D01*
X313123Y1136301D01*
X313170Y1136308D01*
G02X313385Y1136326I214J-1269D01*
G02X313600Y1136308I1J-1287D01*
G01X313647Y1136301D01*
X313737Y1136328D01*
X314038Y1136618D01*
X314069Y1136707D01*
X314063Y1136754D01*
G02X314053Y1136909I1192J155D01*
G02X316457I1202J0D01*
G02X316447Y1136754I-1202J0D01*
G01X316441Y1136707D01*
X316472Y1136618D01*
X316773Y1136328D01*
X316863Y1136301D01*
X316910Y1136308D01*
G02X317125Y1136326I214J-1269D01*
G02X317340Y1136308I1J-1287D01*
G01X317388Y1136300D01*
X317478Y1136328D01*
X317779Y1136617D01*
X317810Y1136707D01*
X317804Y1136754D01*
G02X317794Y1136909I1192J155D01*
G02X320198I1202J0D01*
G02X320177Y1136687I-1202J2D01*
G01X320168Y1136638D01*
X320197Y1136545D01*
X320502Y1136240D01*
X320595Y1136211D01*
X320644Y1136220D01*
G02X320866Y1136241I224J-1181D01*
G02X321088Y1136220I-2J-1202D01*
G01X321137Y1136211D01*
X321230Y1136240D01*
X321535Y1136545D01*
X321564Y1136638D01*
X321555Y1136687D01*
G02X321534Y1136909I1181J224D01*
G02X323938I1202J0D01*
G02X323917Y1136687I-1202J2D01*
G01X323908Y1136638D01*
X323937Y1136545D01*
X324242Y1136240D01*
X324335Y1136211D01*
X324384Y1136220D01*
G02X324606Y1136241I224J-1181D01*
G02X324828Y1136220I-2J-1202D01*
G01X324877Y1136211D01*
X324970Y1136240D01*
X325275Y1136545D01*
X325304Y1136638D01*
G37*
G36*
G01X291643Y1140378D02*
X291634Y1140427D01*
G02X291613Y1140649I1181J224D01*
G02X292815Y1139447I1202J0D01*
G02X292592Y1139468I1J1202D01*
G01X292544Y1139477D01*
X292449Y1139448D01*
X292145Y1139144D01*
X292116Y1139050D01*
X292125Y1139001D01*
G02X292146Y1138779I-1181J-224D01*
G02X289742I-1202J0D01*
G02X289763Y1139001I1202J-2D01*
G01X289772Y1139050D01*
X289743Y1139143D01*
X289438Y1139448D01*
X289345Y1139477D01*
X289296Y1139468D01*
G02X289074Y1139447I-224J1181D01*
G02X290276Y1140649I0J1202D01*
G02X290255Y1140427I-1202J2D01*
G01X290246Y1140378D01*
X290275Y1140285D01*
X290580Y1139980D01*
X290673Y1139951D01*
X290722Y1139960D01*
G02X290944Y1139981I224J-1181D01*
G02X291167Y1139960I-1J-1202D01*
G01X291215Y1139951D01*
X291310Y1139980D01*
X291614Y1140284D01*
X291643Y1140378D01*
G37*
G36*
G01X367815Y1148843D02*
G02X367155Y1150087I842J1244D01*
G02X370159I1502J0D01*
G02X369499Y1148843I-1502J0D01*
G03Y1148181I224J-331D01*
G02X370159Y1146937I-842J-1244D01*
G02X367155I-1502J0D01*
G02X367815Y1148181I1502J0D01*
G03Y1148843I-224J331D01*
G37*
G36*
G01X352636Y1158669D02*
G02X352536Y1158666I-95J1499D01*
G02X354038Y1160168I0J1502D01*
G02X353924Y1159594I-1502J0D01*
G03X354320Y1159043I370J-152D01*
G02X354420Y1159046I95J-1499D01*
G02X352918Y1157544I0J-1502D01*
G02X353032Y1158118I1502J0D01*
G03X352636Y1158669I-370J152D01*
G37*
G36*
G01X341689Y1188868D02*
X341708Y1188921D01*
G02X343121Y1189914I1413J-509D01*
G02Y1186910I0J-1502D01*
G02X341893Y1187548I0J1501D01*
G01X341860Y1187594D01*
X341758Y1187638D01*
X341295Y1187576D01*
X341208Y1187506D01*
X341189Y1187453D01*
G02X339776Y1186460I-1413J509D01*
G02X339582Y1186473I3J1502D01*
G01X339539Y1186478D01*
X339457Y1186453D01*
X339166Y1186197D01*
X339131Y1186119D01*
Y1186075D01*
G02X336127Y1186071I-1502J-4D01*
G02X336142Y1186280I1502J-3D01*
G01X336148Y1186327D01*
X336119Y1186415D01*
X335829Y1186708D01*
X335741Y1186738D01*
X335694Y1186732D01*
G02X335502Y1186720I-190J1490D01*
G02X337004Y1188222I0J1502D01*
G02X336989Y1188013I-1502J3D01*
G01X336983Y1187966D01*
X337012Y1187878D01*
X337302Y1187585D01*
X337390Y1187555D01*
X337437Y1187561D01*
G02X337629Y1187573I190J-1490D01*
G02X337823Y1187560I-3J-1502D01*
G01X337866Y1187555D01*
X337948Y1187580D01*
X338239Y1187836D01*
X338274Y1187914D01*
Y1187958D01*
G02X339776Y1189464I1502J4D01*
G02X341004Y1188826I0J-1501D01*
G01X341037Y1188780D01*
X341139Y1188736D01*
X341602Y1188798D01*
X341689Y1188868D01*
G37*
G36*
G01X299123Y1189000D02*
X299114Y1189049D01*
G02X299093Y1189271I1181J224D01*
G02X300295Y1188069I1202J0D01*
G02X300073Y1188090I2J1202D01*
G01X300024Y1188099D01*
X299931Y1188070D01*
X299626Y1187765D01*
X299597Y1187672D01*
X299606Y1187623D01*
G02X299627Y1187401I-1181J-224D01*
G02X299606Y1187179I-1202J2D01*
G01X299597Y1187130D01*
X299626Y1187037D01*
X299931Y1186732D01*
X300024Y1186703D01*
X300073Y1186712D01*
G02X300295Y1186733I224J-1181D01*
G02X299093Y1185531I0J-1202D01*
G02X299114Y1185753I1202J-2D01*
G01X299123Y1185802D01*
X299094Y1185895D01*
X298789Y1186200D01*
X298696Y1186229D01*
X298647Y1186220D01*
G02X298425Y1186199I-224J1181D01*
G02Y1188603I0J1202D01*
G02X298647Y1188582I-2J-1202D01*
G01X298696Y1188573D01*
X298789Y1188602D01*
X299094Y1188907D01*
X299123Y1189000D01*
G37*
G36*
G01X289772Y1190870D02*
X289763Y1190919D01*
G02X289742Y1191141I1181J224D01*
G02X292146I1202J0D01*
G02X292125Y1190919I-1202J2D01*
G01X292116Y1190870D01*
X292145Y1190777D01*
X292450Y1190472D01*
X292543Y1190443D01*
X292592Y1190452D01*
G02X292814Y1190473I224J-1181D01*
G02X291612Y1189271I0J-1202D01*
G02X291633Y1189493I1202J-2D01*
G01X291642Y1189542D01*
X291613Y1189635D01*
X291308Y1189940D01*
X291215Y1189969D01*
X291166Y1189960D01*
G02X290944Y1189939I-224J1181D01*
G02X290722Y1189960I2J1202D01*
G01X290673Y1189969D01*
X290580Y1189940D01*
X290275Y1189635D01*
X290246Y1189542D01*
X290255Y1189493D01*
G02X290276Y1189271I-1181J-224D01*
G02X289074Y1190473I-1202J0D01*
G02X289296Y1190452I-2J-1202D01*
G01X289345Y1190443D01*
X289438Y1190472D01*
X289743Y1190777D01*
X289772Y1190870D01*
G37*
G36*
G01X358469Y1191769D02*
G02X357297Y1191207I-1172J941D01*
G02Y1194211I0J1502D01*
G02X358673Y1193311I0J-1502D01*
G03X359351Y1193222I366J161D01*
G02X360523Y1193784I1172J-941D01*
G02Y1190780I0J-1502D01*
G02X359147Y1191680I0J1502D01*
G03X358469Y1191769I-366J-161D01*
G37*
G36*
G01X312213Y1198350D02*
X312204Y1198399D01*
G02X312183Y1198621I1181J224D01*
G02X313385Y1197419I1202J0D01*
G02X313163Y1197440I2J1202D01*
G01X313114Y1197449D01*
X313021Y1197420D01*
X312716Y1197115D01*
X312687Y1197022D01*
X312696Y1196973D01*
G02X312717Y1196751I-1181J-224D01*
G02X310313I-1202J0D01*
G02X310334Y1196973I1202J-2D01*
G01X310343Y1197022D01*
X310314Y1197115D01*
X310009Y1197420D01*
X309916Y1197449D01*
X309867Y1197440D01*
G02X309645Y1197419I-224J1181D01*
G02X310847Y1198621I0J1202D01*
G02X310826Y1198399I-1202J2D01*
G01X310817Y1198350D01*
X310846Y1198257D01*
X311151Y1197952D01*
X311244Y1197923D01*
X311293Y1197932D01*
G02X311515Y1197953I224J-1181D01*
G02X311737Y1197932I-2J-1202D01*
G01X311786Y1197923D01*
X311879Y1197952D01*
X312184Y1198257D01*
X312213Y1198350D01*
G37*
G36*
G01X363581Y1213755D02*
X363569Y1213807D01*
G02X363527Y1214158I1460J353D01*
G02X365029Y1212656I1502J0D01*
G02X364678Y1212698I2J1502D01*
G01X364626Y1212710D01*
X364527Y1212682D01*
X364211Y1212366D01*
X364183Y1212267D01*
X364195Y1212215D01*
G02X364237Y1211864I-1460J-353D01*
G02X362735Y1210362I-1502J0D01*
G02X362591Y1210369I1J1502D01*
G01X362546Y1210373D01*
X362462Y1210343D01*
X362180Y1210061D01*
X362150Y1209978D01*
X362154Y1209933D01*
G02X362161Y1209789I-1495J-145D01*
G02X360659Y1211291I-1502J0D01*
G02X360803Y1211284I-1J-1502D01*
G01X360848Y1211280D01*
X360932Y1211310D01*
X361214Y1211592D01*
X361244Y1211675D01*
X361240Y1211720D01*
G02X361233Y1211864I1495J145D01*
G02X362735Y1213366I1502J0D01*
G02X363086Y1213324I-2J-1502D01*
G01X363138Y1213312D01*
X363237Y1213340D01*
X363553Y1213656D01*
X363581Y1213755D01*
G37*
G36*
G01X201452Y1216150D02*
X201403Y1216141D01*
G02X201181Y1216120I-224J1181D01*
G02X202383Y1217322I0J1202D01*
G02X202362Y1217100I-1202J2D01*
G01X202353Y1217051D01*
X202382Y1216958D01*
X202687Y1216653D01*
X202780Y1216624D01*
X202829Y1216633D01*
G02X203051Y1216654I224J-1181D01*
G02X204253Y1215452I0J-1202D01*
G02X204232Y1215230I-1202J2D01*
G01X204223Y1215181D01*
X204252Y1215088D01*
X204557Y1214783D01*
X204650Y1214754D01*
X204699Y1214763D01*
G02X204921Y1214784I224J-1181D01*
G02X203719Y1213582I0J-1202D01*
G02X203740Y1213804I1202J-2D01*
G01X203749Y1213853D01*
X203720Y1213946D01*
X203415Y1214251D01*
X203322Y1214280D01*
X203273Y1214271D01*
G02X203051Y1214250I-224J1181D01*
G02X202829Y1214271I2J1202D01*
G01X202780Y1214280D01*
X202687Y1214251D01*
X202382Y1213946D01*
X202353Y1213853D01*
X202362Y1213804D01*
G02X202383Y1213582I-1181J-224D01*
G02X201181Y1214784I-1202J0D01*
G02X201403Y1214763I-2J-1202D01*
G01X201452Y1214754D01*
X201545Y1214783D01*
X201850Y1215088D01*
X201879Y1215181D01*
X201870Y1215230D01*
G02X201849Y1215452I1181J224D01*
G02X201870Y1215674I1202J-2D01*
G01X201879Y1215723D01*
X201850Y1215816D01*
X201545Y1216121D01*
X201452Y1216150D01*
G37*
G36*
G01X208932D02*
X208883Y1216141D01*
G02X208661Y1216120I-224J1181D01*
G02X209863Y1217322I0J1202D01*
G02X209842Y1217100I-1202J2D01*
G01X209833Y1217051D01*
X209862Y1216958D01*
X210167Y1216653D01*
X210260Y1216624D01*
X210309Y1216633D01*
G02X210531Y1216654I224J-1181D01*
G02Y1214250I0J-1202D01*
G02X210309Y1214271I2J1202D01*
G01X210260Y1214280D01*
X210167Y1214251D01*
X209862Y1213946D01*
X209833Y1213853D01*
X209842Y1213804D01*
G02X209863Y1213582I-1181J-224D01*
G02X209842Y1213360I-1202J2D01*
G01X209833Y1213311D01*
X209862Y1213218D01*
X210167Y1212913D01*
X210260Y1212884D01*
X210309Y1212893D01*
G02X210531Y1212914I224J-1181D01*
G02X209329Y1211712I0J-1202D01*
G02X209350Y1211934I1202J-2D01*
G01X209359Y1211983D01*
X209330Y1212076D01*
X209025Y1212381D01*
X208932Y1212410D01*
X208883Y1212401D01*
G02X208661Y1212380I-224J1181D01*
G02Y1214784I0J1202D01*
G02X208883Y1214763I-2J-1202D01*
G01X208932Y1214754D01*
X209025Y1214783D01*
X209330Y1215088D01*
X209359Y1215181D01*
X209350Y1215230D01*
G02X209329Y1215452I1181J224D01*
G02X209350Y1215674I1202J-2D01*
G01X209359Y1215723D01*
X209330Y1215816D01*
X209025Y1216121D01*
X208932Y1216150D01*
G37*
G36*
G01X218709Y1217051D02*
X218700Y1217100D01*
G02X218679Y1217322I1181J224D01*
G02X221083I1202J0D01*
G02X221062Y1217100I-1202J2D01*
G01X221053Y1217051D01*
X221082Y1216957D01*
X221386Y1216653D01*
X221481Y1216624D01*
X221529Y1216633D01*
G02X221752Y1216654I224J-1181D01*
G02X220550Y1215452I0J-1202D01*
G02X220571Y1215674I1202J-2D01*
G01X220580Y1215723D01*
X220551Y1215817D01*
X220247Y1216121D01*
X220152Y1216150D01*
X220104Y1216141D01*
G02X219881Y1216120I-224J1181D01*
G02X219659Y1216141I2J1202D01*
G01X219610Y1216150D01*
X219517Y1216121D01*
X219212Y1215816D01*
X219183Y1215723D01*
X219192Y1215674D01*
G02X219213Y1215452I-1181J-224D01*
G02X218011Y1216654I-1202J0D01*
G02X218233Y1216633I-2J-1202D01*
G01X218282Y1216624D01*
X218375Y1216653D01*
X218680Y1216958D01*
X218709Y1217051D01*
G37*
G36*
G01X241150D02*
X241141Y1217100D01*
G02X241120Y1217322I1181J224D01*
G02X243524I1202J0D01*
G02X243503Y1217100I-1202J2D01*
G01X243494Y1217051D01*
X243523Y1216958D01*
X243828Y1216653D01*
X243921Y1216624D01*
X243970Y1216633D01*
G02X244192Y1216654I224J-1181D01*
G02X242990Y1215452I0J-1202D01*
G02X243011Y1215674I1202J-2D01*
G01X243020Y1215723D01*
X242991Y1215816D01*
X242686Y1216121D01*
X242593Y1216150D01*
X242544Y1216141D01*
G02X242322Y1216120I-224J1181D01*
G02X242100Y1216141I2J1202D01*
G01X242051Y1216150D01*
X241958Y1216121D01*
X241653Y1215816D01*
X241624Y1215723D01*
X241633Y1215674D01*
G02X241654Y1215452I-1181J-224D01*
G02X239250I-1202J0D01*
G02X239271Y1215674I1202J-2D01*
G01X239280Y1215723D01*
X239251Y1215816D01*
X238946Y1216121D01*
X238853Y1216150D01*
X238804Y1216141D01*
G02X238582Y1216120I-224J1181D01*
G02X238360Y1216141I2J1202D01*
G01X238311Y1216150D01*
X238218Y1216121D01*
X237913Y1215816D01*
X237884Y1215723D01*
X237893Y1215674D01*
G02X237914Y1215452I-1181J-224D01*
G02X236712Y1216654I-1202J0D01*
G02X236934Y1216633I-2J-1202D01*
G01X236983Y1216624D01*
X237076Y1216653D01*
X237381Y1216958D01*
X237410Y1217051D01*
X237401Y1217100D01*
G02X237380Y1217322I1181J224D01*
G02X239784I1202J0D01*
G02X239763Y1217100I-1202J2D01*
G01X239754Y1217051D01*
X239783Y1216958D01*
X240088Y1216653D01*
X240181Y1216624D01*
X240230Y1216633D01*
G02X240452Y1216654I224J-1181D01*
G02X240674Y1216633I-2J-1202D01*
G01X240723Y1216624D01*
X240816Y1216653D01*
X241121Y1216958D01*
X241150Y1217051D01*
G37*
G36*
G01X360838Y1230107D02*
X360834Y1230151D01*
G02X360830Y1230265I1498J110D01*
G02X362332Y1228763I1502J0D01*
G02X362204Y1228768I-5J1502D01*
G01X362159Y1228772D01*
X362077Y1228743D01*
X361798Y1228466D01*
X361767Y1228384D01*
X361771Y1228340D01*
G02X361775Y1228226I-1498J-110D01*
G02X360273Y1226724I-1502J0D01*
G02X360005Y1226748I-1J1502D01*
G01X359956Y1226757D01*
X359863Y1226728D01*
X359560Y1226425D01*
X359531Y1226332D01*
X359540Y1226283D01*
G02X359564Y1226016I-1478J-267D01*
G02X358062Y1227518I-1502J0D01*
G02X358330Y1227494I1J-1502D01*
G01X358379Y1227485D01*
X358472Y1227514D01*
X358775Y1227817D01*
X358804Y1227910D01*
X358795Y1227959D01*
G02X358771Y1228226I1478J267D01*
G02X360273Y1229728I1502J0D01*
G02X360401Y1229723I5J-1502D01*
G01X360446Y1229719D01*
X360528Y1229748D01*
X360807Y1230025D01*
X360838Y1230107D01*
G37*
G36*
G01X394649Y1422791D02*
X394339D01*
G03X394183Y1422717I-1J-200D01*
G02X393094Y1422198I-1089J883D01*
G02Y1425002I0J1402D01*
G02X394183Y1424483I0J-1402D01*
G03X394339Y1424409I155J126D01*
G01X394649D01*
G03X394805Y1424483I1J200D01*
G02X395894Y1425002I1089J-883D01*
G02Y1422198I0J-1402D01*
G02X394805Y1422717I0J1402D01*
G03X394649Y1422791I-155J-126D01*
G37*
G36*
G01X359450Y1515218D02*
Y1516344D01*
G02X359653Y1516546I203J-1D01*
G01X362473D01*
G02X362676Y1516344I1J-202D01*
G01Y1515218D01*
G03X362704Y1515115I200J-1D01*
G02Y1513153I-1640J-981D01*
G03X362676Y1513050I172J-102D01*
G01Y1510100D01*
G03X362704Y1509997I200J-1D01*
G02Y1508035I-1640J-981D01*
G03X362676Y1507932I172J-102D01*
G01Y1506806D01*
G02X362473Y1506604I-203J1D01*
G01X359653D01*
G02X359450Y1506806I-1J202D01*
G01Y1507932D01*
G03X359422Y1508035I-200J1D01*
G02Y1509997I1640J981D01*
G03X359450Y1510100I-172J102D01*
G01Y1513050D01*
G03X359422Y1513153I-200J1D01*
G02Y1515115I1640J981D01*
G03X359450Y1515218I-172J102D01*
G37*
G36*
G01X393308Y1536368D02*
Y1536704D01*
X393283Y1536771D01*
X393259Y1536799D01*
G02X392889Y1537786I1131J987D01*
G02X395893I1502J0D01*
G02X395523Y1536799I-1501J0D01*
G01X395499Y1536771D01*
X395474Y1536704D01*
Y1536368D01*
X395499Y1536301D01*
X395523Y1536273D01*
G02X395893Y1535286I-1131J-987D01*
G02X392889I-1502J0D01*
G02X393259Y1536273I1501J0D01*
G01X393283Y1536301D01*
X393308Y1536368D01*
G37*
G36*
G01X359450Y1571518D02*
Y1572644D01*
G02X359653Y1572846I203J-1D01*
G01X362473D01*
G02X362676Y1572644I1J-202D01*
G01Y1571518D01*
G03X362704Y1571415I200J-1D01*
G02Y1569453I-1640J-981D01*
G03X362676Y1569350I172J-102D01*
G01Y1566399D01*
G03X362704Y1566296I200J-1D01*
G02Y1564334I-1640J-981D01*
G03X362676Y1564231I172J-102D01*
G01Y1563106D01*
G02X362473Y1562904I-203J1D01*
G01X359653D01*
G02X359450Y1563106I-1J202D01*
G01Y1564231D01*
G03X359422Y1564334I-200J1D01*
G02Y1566296I1640J981D01*
G03X359450Y1566399I-172J102D01*
G01Y1569350D01*
G03X359422Y1569453I-200J1D01*
G02Y1571415I1640J981D01*
G03X359450Y1571518I-172J102D01*
G37*
G36*
G01X394483Y1449492D02*
G02X394386Y1450022I1405J531D01*
G02X395888Y1448520I1502J0D01*
G02X395764Y1448525I-2J1502D01*
G03X395356Y1447985I-34J-399D01*
G02X395453Y1447455I-1405J-531D01*
G02X393951Y1448957I-1502J0D01*
G02X394075Y1448952I2J-1502D01*
G03X394483Y1449492I34J399D01*
G37*
G36*
G01X396691Y1500306D02*
G02X395370Y1499520I-1321J717D01*
G02Y1502524I0J1502D01*
G02X396716Y1501688I0J-1502D01*
G03X397426Y1501675I358J177D01*
G02X398747Y1502461I1321J-717D01*
G02Y1499457I0J-1502D01*
G02X397401Y1500293I0J1502D01*
G03X396691Y1500306I-358J-177D01*
G37*
G36*
G01X359450Y1602226D02*
Y1603352D01*
G02X359653Y1603554I203J-1D01*
G01X362473D01*
G02X362676Y1603352I1J-202D01*
G01Y1602226D01*
G03X362704Y1602123I200J-1D01*
G02Y1600161I-1640J-981D01*
G03X362676Y1600058I172J-102D01*
G01Y1597108D01*
G03X362704Y1597005I200J-1D01*
G02Y1595043I-1640J-981D01*
G03X362676Y1594940I172J-102D01*
G01Y1593814D01*
G02X362473Y1593612I-203J1D01*
G01X359653D01*
G02X359450Y1593814I-1J202D01*
G01Y1594940D01*
G03X359422Y1595043I-200J1D01*
G02Y1597005I1640J981D01*
G03X359450Y1597108I-172J102D01*
G01Y1600058D01*
G03X359422Y1600161I-200J1D01*
G02Y1602123I1640J981D01*
G03X359450Y1602226I-172J102D01*
G37*
G36*
G01Y1617580D02*
Y1618706D01*
G02X359653Y1618908I203J-1D01*
G01X362473D01*
G02X362676Y1618706I1J-202D01*
G01Y1617580D01*
G03X362704Y1617477I200J-1D01*
G02Y1615515I-1640J-981D01*
G03X362676Y1615412I172J-102D01*
G01Y1612462D01*
G03X362704Y1612359I200J-1D01*
G02Y1610397I-1640J-981D01*
G03X362676Y1610294I172J-102D01*
G01Y1609168D01*
G02X362473Y1608966I-203J1D01*
G01X359653D01*
G02X359450Y1609168I-1J202D01*
G01Y1610294D01*
G03X359422Y1610397I-200J1D01*
G02Y1612359I1640J981D01*
G03X359450Y1612462I-172J102D01*
G01Y1615412D01*
G03X359422Y1615515I-200J1D01*
G02Y1617477I1640J981D01*
G03X359450Y1617580I-172J102D01*
G37*
G36*
G01X721092Y530846D02*
G02X721517Y530795I-1J-1802D01*
G01X721519D01*
X721559Y530785D01*
X721640Y530800D01*
X721957Y531010D01*
X722001Y531079D01*
X722008Y531121D01*
G02X723491Y532388I1483J-234D01*
G02Y529384I0J-1502D01*
G01X723489D01*
G02X723224Y529408I2J1502D01*
G03X723058Y529362I-35J-197D01*
G01X722962Y529279D01*
G03X722892Y529119I130J-152D01*
G02X722894Y529045I-1800J-86D01*
G01Y525644D01*
G02X722892Y525566I-1802J7D01*
G03X722962Y525406I200J-8D01*
G01X723058Y525323D01*
G03X723224Y525277I131J151D01*
G02X723489Y525301I267J-1478D01*
G01X723491D01*
G02Y522297I0J-1502D01*
G02X722007Y523566I0J1502D01*
G01X722001Y523608D01*
X721956Y523678D01*
X721640Y523888D01*
X721559Y523902D01*
X721518Y523892D01*
G02X721092Y523842I-422J1753D01*
G02X720727Y523879I-2J1802D01*
G01X720726D01*
G03X720573Y523848I-40J-196D01*
G01X720301Y523661D01*
X720257Y523591D01*
X720251Y523550D01*
G02X718692Y522220I-1559J249D01*
G02X717637Y522625I1J1579D01*
G03X717504Y522676I-133J-149D01*
G01X717380D01*
G03X717247Y522625I0J-200D01*
G02X716192Y522220I-1056J1174D01*
G02X715926Y522243I3J1579D01*
G03X715763Y522199I-34J-197D01*
G01X715665Y522117D01*
G03X715594Y521964I129J-153D01*
G01Y518559D01*
Y518557D01*
Y518547D01*
G03X715665Y518394I200J0D01*
G01X715762Y518312D01*
G03X715925Y518268I129J153D01*
G02X716192Y518290I263J-1556D01*
G02X717247Y517886I0J-1580D01*
G03X717380Y517835I133J149D01*
G01X717504D01*
G03X717637Y517886I0J200D01*
G02X718692Y518290I1055J-1176D01*
G02X720250Y516964I0J-1578D01*
G01X720257Y516923D01*
X720300Y516855D01*
X720607Y516644D01*
X720686Y516628D01*
X720726Y516636D01*
G02X721092Y516674I368J-1765D01*
G02X721517Y516622I-5J-1802D01*
G01X721519D01*
X721559Y516612D01*
X721640Y516627D01*
X721957Y516837D01*
X722001Y516906D01*
X722008Y516948D01*
G02X723491Y518215I1483J-234D01*
G02Y515211I0J-1502D01*
G01X723489D01*
G02X723224Y515235I2J1502D01*
G03X723058Y515189I-35J-197D01*
G01X722962Y515106D01*
G03X722892Y514946I130J-152D01*
G02X722894Y514872I-1800J-86D01*
G01Y511471D01*
G02X722892Y511393I-1802J7D01*
G03X722962Y511233I200J-8D01*
G01X723058Y511150D01*
G03X723224Y511104I131J151D01*
G02X723489Y511128I267J-1478D01*
G01X723491D01*
G02X724993Y509626I0J-1502D01*
G02X724988Y509501I-1502J-3D01*
G03X725082Y509314I199J-17D01*
G01X725383Y509127D01*
G03X725592Y509125I106J169D01*
G02X726775Y509452I1184J-1979D01*
G01X729589D01*
G03X729789Y509649I0J200D01*
G02X732793I1502J-23D01*
G03X732993Y509452I200J3D01*
G01X739900D01*
G03X740100Y509649I0J200D01*
G02X741602Y511128I1502J-23D01*
G02X743104Y509626I0J-1502D01*
G02X743058Y509258I-1502J1D01*
G03X743139Y509045I194J-48D01*
G02X743460Y508777I-1312J-1897D01*
G01X747927Y504309D01*
G03X748069Y504250I142J141D01*
G01X821991D01*
G03X822133Y504309I0J200D01*
G01X826137Y508314D01*
G02X827768Y508990I1632J-1631D01*
G01X833269D01*
G02Y504376I0J-2307D01*
G01X828806D01*
G03X828664Y504317I0J-200D01*
G01X824660Y500313D01*
G02X823030Y499638I-1630J1631D01*
G01X820877D01*
G03X820722Y499565I0J-200D01*
G01X820466Y499253D01*
X820468Y499244D01*
G02X820510Y498927I-1162J-315D01*
G01Y493375D01*
G02X820157Y492523I-1204J0D01*
G01X820077Y492443D01*
X820071Y492287D01*
X820119Y492230D01*
G02X820475Y491260I-1146J-971D01*
G01Y491258D01*
G02X820105Y490271I-1501J0D01*
G01Y490270D01*
X820104D01*
G03X820056Y490140I152J-130D01*
G01Y489876D01*
G03X820104Y489746I200J0D01*
G01X820105Y489745D01*
G02X820475Y488758I-1131J-987D01*
G02X820456Y488517I-1502J-3D01*
G01X820433Y488381D01*
G02X820461Y488366I-555J-1069D01*
G01X820766Y488197D01*
G02X821384Y487146I-586J-1052D01*
G01Y486861D01*
G03X821469Y486697I200J0D01*
G01X821774Y486482D01*
X821869Y486469D01*
X821915Y486485D01*
G02X822418Y486572I504J-1415D01*
G02X823920Y485070I0J-1502D01*
G02X823550Y484083I-1501J0D01*
G01Y484082D01*
X823549D01*
G03X823501Y483952I152J-130D01*
G01Y483688D01*
G03X823549Y483558I200J0D01*
G01X823550Y483557D01*
G02X823920Y482570I-1131J-987D01*
G02X822418Y481068I-1502J0D01*
G02X821170Y481734I0J1502D01*
G01Y481735D01*
G03X821023Y481822I-166J-112D01*
G01X820719Y481852D01*
G03X820558Y481794I-19J-199D01*
G01X819791Y481026D01*
G03X819789Y481024I140J-142D01*
G01X819650Y480880D01*
G02X819581Y480833I-145J138D01*
G01X819203Y480681D01*
G02X819128Y480666I-76J185D01*
G01X809500D01*
G03X809358Y480607I0J-200D01*
G01X807889Y479138D01*
G03X807830Y478996I141J-142D01*
G01Y468310D01*
G03X807889Y468168I200J0D01*
G01X811304Y464753D01*
G03X811446Y464694I142J141D01*
G01X824623D01*
G02X825581Y464218I-1J-1204D01*
G01X825625Y464159D01*
G02X825639Y464138I-159J-121D01*
G01X825841Y463785D01*
G02X825846Y463776I-1050J-589D01*
G01X825983Y463802D01*
G02X826262Y463828I278J-1476D01*
G02X826541Y463802I1J-1502D01*
G01X826601Y463791D01*
X826717Y463844D01*
X826856Y464087D01*
G02X827901Y464694I1046J-597D01*
G01X834282D01*
G02X835134Y464341I0J-1204D01*
G01X835646Y463829D01*
G02X835656Y463819I-847J-857D01*
G02X836000Y462976I-860J-843D01*
G01Y457584D01*
G02X835230Y456461I-1204J0D01*
G01X834751Y456276D01*
X834683Y456189D01*
X834677Y456136D01*
G02X833631Y454875I-1492J173D01*
G01X833571Y454856D01*
X833494Y454751D01*
Y453867D01*
X833571Y453762D01*
X833631Y453743D01*
G02X834687Y452309I-446J-1434D01*
G02X833186Y450807I-1502J0D01*
G01X833184D01*
G02X833021Y450298I-1200J104D01*
G01X833013Y450282D01*
X833240Y449860D01*
X833321Y449806D01*
X833369Y449800D01*
G02X834687Y448309I-184J-1491D01*
G02X831683I-1502J0D01*
G02X831913Y449107I1502J-1D01*
G03X831782Y449410I-169J107D01*
G01X826139D01*
G03X825964Y449307I0J-200D01*
G02X825401Y448734I-1314J728D01*
G03X825301Y448561I100J-173D01*
G01Y448213D01*
G03X825401Y448040I200J0D01*
G02X826152Y446740I-750J-1300D01*
G02X823148I-1502J0D01*
G02X823899Y448040I1501J0D01*
G03X823999Y448213I-100J173D01*
G01Y448561D01*
G03X823899Y448734I-200J0D01*
G02X823336Y449307I751J1301D01*
G03X823161Y449410I-175J-97D01*
G01X812131D01*
G03X811962Y449318I-1J-200D01*
G01X811754Y448993D01*
X811747Y448891D01*
X811769Y448845D01*
G02X811908Y448214I-1363J-631D01*
G02X808904I-1502J0D01*
G02X809043Y448845I1502J0D01*
G01X809065Y448891D01*
X809058Y448993D01*
X808850Y449318D01*
G03X808681Y449410I-168J-108D01*
G01X803911D01*
G03X803746Y449323I0J-200D01*
G01X803561Y449054D01*
G03X803539Y448870I165J-113D01*
G02X803638Y448334I-1403J-536D01*
G02X800634I-1502J0D01*
G02X800901Y449189I1502J0D01*
G01X800914Y449208D01*
X800953Y449305D01*
X800890Y449457D01*
X800856Y449471D01*
G02X800742Y449515I376J1144D01*
G03X800661Y449532I-81J-183D01*
G01X795407D01*
X795403Y449536D01*
X795316D01*
G02X793030I-1143J973D01*
G01X792943D01*
X792939Y449532D01*
X780263D01*
X780259Y449536D01*
X780172D01*
G02X777886I-1143J973D01*
G01X777799D01*
X777795Y449532D01*
X758489D01*
G03X758347Y449473I0J-200D01*
G01X756525Y447652D01*
G03X756466Y447501I141J-142D01*
G01X756480Y447209D01*
G03X756551Y447065I200J9D01*
G01X756552Y447064D01*
G02X757095Y445908I-959J-1156D01*
G02X755593Y444406I-1502J0D01*
G02X754142Y445520I0J1502D01*
G01X754122Y445512D01*
X737979D01*
G03X737837Y445453I0J-200D01*
G01X736495Y444110D01*
G03X736436Y443968I141J-142D01*
G01Y425457D01*
Y425455D01*
G02X736434Y425383I-1204J-3D01*
G01Y425372D01*
X736550Y425256D01*
X740098D01*
G02X743798Y421555I-1J-3701D01*
G02X740806Y417922I-3702J0D01*
G01X740752Y417911D01*
X740670Y417838D01*
X740551Y417451D01*
G03X740601Y417251I191J-58D01*
G01X747430Y410421D01*
G03X747632Y410372I141J142D01*
G01X748022Y410498D01*
X748095Y410582D01*
X748104Y410638D01*
G02X749586Y411896I1482J-244D01*
G02X751088Y410394I0J-1502D01*
G02X749830Y408912I-1502J0D01*
G01X749774Y408903D01*
X749690Y408830D01*
X749565Y408440D01*
G03X749614Y408238I190J-61D01*
G01X750185Y407667D01*
G03X750364Y407612I141J141D01*
G01X750686Y407674D01*
G03X750832Y407792I-38J196D01*
G02X752341Y408788I1509J-645D01*
G01X752344D01*
G02X753019Y408642I-2J-1640D01*
G01X753066Y408621D01*
X753166Y408628D01*
X753535Y408865D01*
X753584Y408954D01*
Y409005D01*
G02X755086Y410502I1502J-5D01*
G02Y407498I0J-1502D01*
G01X755084D01*
G02X754528Y407605I1J1502D01*
G01X754481Y407624D01*
X754380Y407612D01*
X754022Y407360D01*
X753978Y407268D01*
X753980Y407217D01*
G02X753982Y407149I-1639J-82D01*
G01Y407147D01*
G02X753979Y407049I-1641J1D01*
G01X753976Y407008D01*
X754004Y406930D01*
X754230Y406691D01*
G03X754375Y406628I146J137D01*
G01X755317D01*
G02X756399Y405949I-2J-1204D01*
G01X756409Y405930D01*
X756584Y405527D01*
X756687Y405462D01*
X756742Y405464D01*
X756850D01*
X756858D01*
X756913Y405462D01*
X757017Y405527D01*
X757175Y405891D01*
G02X757181Y405907I1131J-415D01*
G02X757185Y405917I188J-69D01*
G02X758283Y406628I1099J-494D01*
G01X764484D01*
G02X764814Y406582I0J-1205D01*
G03X765043Y406674I56J192D01*
G02X766344Y407426I1301J-749D01*
G02X767846Y405924I0J-1502D01*
G02X767204Y404693I-1501J0D01*
G03X767128Y404588I115J-163D01*
G01X767095Y404481D01*
G03X767098Y404353I191J-60D01*
G02X767172Y403939I-1131J-416D01*
G01Y403778D01*
G02X767129Y403464I-1205J5D01*
G01X767091Y403322D01*
X767136Y403202D01*
X767186Y403168D01*
G02X767588Y402766I-842J-1244D01*
G01X767622Y402716D01*
X767742Y402671D01*
X768007Y402743D01*
G02X768088Y402762I315J-1162D01*
G02X768979Y402592I236J-1181D01*
G01X769071Y402532D01*
G02X769103Y402506I-109J-167D01*
G01X788479Y383130D01*
G02X788489Y383120I-847J-857D01*
G02X788834Y382277I-860J-844D01*
G01Y305159D01*
G02X788831Y305075I-1205J1D01*
G03X788830Y305060I199J-21D01*
G01Y304964D01*
G02X788815Y304889I-200J1D01*
G01X788778Y304797D01*
G03X788773Y304783I186J-74D01*
G02X788713Y304633I-1146J371D01*
G03X788708Y304622I179J-88D01*
G01X788663Y304512D01*
G02X788617Y304444I-185J76D01*
G01X788532Y304362D01*
G03X788522Y304352I136J-146D01*
G02X788480Y304307I-901J799D01*
G01X785774Y301601D01*
G03X785772Y301599I140J-142D01*
G01X785632Y301454D01*
G02X785564Y301408I-144J139D01*
G01X785186Y301255D01*
G02X785111Y301240I-76J185D01*
G01X782450D01*
G02X782363Y301243I-2J1205D01*
G03X782348Y301244I-21J-199D01*
G01X782158D01*
G02X782052Y301274I-1J200D01*
G01X781884Y301380D01*
G03X781874Y301386I-108J-169D01*
G02X781744Y301468I576J1058D01*
G03X781733Y301476I-123J-158D01*
G01X781562Y301583D01*
G02X781487Y301667I106J170D01*
G01X781404Y301843D01*
G03X781397Y301856I-179J-88D01*
G02X781363Y301922I1054J584D01*
G01X781207Y302246D01*
G02X781169Y302333I1084J525D01*
G01X781164Y302344D01*
X781032Y302338D01*
G02X780969Y302337I-55J1501D01*
G01X780967D01*
G02X780904Y302338I-8J1502D01*
G01X780772Y302344D01*
X780767Y302333D01*
G02X780729Y302246I-1122J438D01*
G01X780573Y301922D01*
G02X780539Y301856I-1088J518D01*
G03X780532Y301843I172J-101D01*
G01X780449Y301667D01*
G02X780374Y301583I-181J86D01*
G01X780203Y301476D01*
G03X780192Y301468I112J-166D01*
G02X780062Y301386I-706J976D01*
G03X780052Y301380I98J-175D01*
G01X779884Y301274D01*
G02X779778Y301244I-105J170D01*
G01X779588D01*
G03X779573Y301243I6J-200D01*
G02X779486Y301240I-85J1202D01*
G01X777358D01*
G02X777274Y301243I1J1205D01*
G03X777259Y301244I-21J-199D01*
G01X776944D01*
G02X776802Y301303I0J200D01*
G01X776577Y301528D01*
G03X776567Y301537I-139J-144D01*
G02X776506Y301594I791J908D01*
G01X769170Y308930D01*
G02X769113Y308991I851J853D01*
G03X769104Y309001I-153J-129D01*
G01X768879Y309226D01*
G02X768820Y309368I141J142D01*
G01Y309683D01*
G03X768819Y309698I-200J-6D01*
G02X768816Y309782I1202J85D01*
G01Y315364D01*
G03X768694Y315548I-200J0D01*
G01X768303Y315714D01*
X768185Y315692D01*
X768142Y315650D01*
G02X767099Y315229I-1043J1081D01*
G02Y318233I0J1502D01*
G02X768142Y317812I0J-1502D01*
G01X768185Y317770D01*
X768303Y317748D01*
X768694Y317914D01*
G03X768816Y318098I-78J184D01*
G01Y322954D01*
Y322977D01*
G03X768702Y323163I-200J5D01*
G02Y325873I647J1355D01*
G03X768816Y326059I-86J181D01*
G01Y364262D01*
G03X768757Y364404I-200J0D01*
G01X756694Y376468D01*
X756586Y376495D01*
X756535Y376479D01*
G02X756086Y376410I-450J1433D01*
G02X754584Y377912I0J1502D01*
G02X754653Y378361I1502J-1D01*
G01X754669Y378412D01*
X754642Y378520D01*
X752803Y380358D01*
Y380363D01*
X752635Y380531D01*
X752579Y380559D01*
X752548Y380564D01*
G02X751302Y381810I237J1483D01*
G01X751297Y381841D01*
X751269Y381897D01*
X751101Y382065D01*
X751096D01*
X750199Y382962D01*
X750093Y382988D01*
X750043Y382973D01*
G02X749606Y382908I-437J1436D01*
G02X748104Y384410I0J1502D01*
G02X748169Y384847I1501J0D01*
G01X748184Y384897D01*
X748158Y385003D01*
X740537Y392625D01*
G03X740395Y392684I-142J-141D01*
G01X735897D01*
X735894Y392686D01*
X735827D01*
G02X733495I-1166J947D01*
G01X733428D01*
X733425Y392684D01*
X725168D01*
G03X725000Y392592I0J-200D01*
G01X724820Y392311D01*
G03X724806Y392121I168J-108D01*
G01Y392120D01*
G02X724942Y391496I-1366J-625D01*
G02X721938I-1502J0D01*
G02X722074Y392120I1502J-1D01*
G01Y392121D01*
G03X722060Y392311I-182J82D01*
G01X721880Y392592D01*
G03X721712Y392684I-168J-108D01*
G01X686964D01*
X686851Y392586D01*
X686841Y392514D01*
G02X685353Y391216I-1488J204D01*
G02X683851Y392718I0J1502D01*
G02X683958Y393275I1503J0D01*
G01X683979Y393327D01*
X683955Y393445D01*
X681169Y396230D01*
G02X681118Y396284I850J854D01*
G03X681109Y396294I-153J-129D01*
G01X680877Y396526D01*
G02X680818Y396668I141J142D01*
G01Y396999D01*
Y397010D01*
G02X680816Y397081I1202J69D01*
G01Y486407D01*
G02X681164Y487254I1204J0D01*
G01X694033Y500123D01*
G02X694043Y500133I857J-847D01*
G02X694886Y500478I844J-860D01*
G01X728792D01*
G03X728948Y500552I1J200D01*
G01X729170Y500827D01*
X729190Y500915D01*
X729180Y500960D01*
G02X729094Y501752I3616J793D01*
G02X730000Y504177I3702J-1D01*
G01X730001Y504178D01*
G03X730031Y504391I-152J130D01*
G01X729879Y504723D01*
G03X729697Y504840I-182J-83D01*
G01X727815D01*
G03X727673Y504781I0J-200D01*
G01X725993Y503100D01*
G02X724362Y502424I-1632J1631D01*
G02X722056Y504731I1J2307D01*
G01Y504732D01*
G02X722731Y506362I2306J0D01*
G01X723811Y507442D01*
G03X723853Y507661I-142J141D01*
G01X723684Y508059D01*
X723581Y508125D01*
X723520Y508124D01*
X723491D01*
G02X722007Y509393I0J1502D01*
G01X722001Y509435D01*
X721956Y509505D01*
X721640Y509715D01*
X721559Y509729D01*
X721518Y509719D01*
G02X721092Y509668I-426J1752D01*
G02X720728Y509706I4J1803D01*
G01X720726D01*
G03X720573Y509675I-40J-196D01*
G01X720301Y509488D01*
X720257Y509418D01*
X720251Y509377D01*
G02X718692Y508046I-1559J248D01*
G02Y511204I0J1579D01*
G02X718959Y511181I-2J-1579D01*
G03X719122Y511225I34J197D01*
G01X719219Y511307D01*
G03X719290Y511460I-129J153D01*
G01Y514870D01*
Y514872D01*
Y514877D01*
G03X719219Y515030I-200J0D01*
G01X719120Y515112D01*
G03X718958Y515156I-129J-153D01*
G02X718692Y515134I-263J1556D01*
G02X717637Y515538I0J1580D01*
G03X717504Y515589I-133J-149D01*
G01X717380D01*
G03X717247Y515538I0J-200D01*
G02X716192Y515134I-1055J1176D01*
G02X714633Y516464I0J1579D01*
G01X714627Y516505D01*
X714583Y516575D01*
X714311Y516762D01*
G03X714158Y516793I-113J-165D01*
G01X714157D01*
G02X713792Y516756I-363J1765D01*
G02X713427Y516793I-2J1802D01*
G01X713426D01*
G03X713273Y516762I-40J-196D01*
G01X713001Y516575D01*
X712957Y516505D01*
X712951Y516464D01*
G02X711392Y515134I-1559J249D01*
G02Y518290I0J1578D01*
G02X711659Y518268I4J-1578D01*
G03X711822Y518312I34J197D01*
G01X711919Y518394D01*
G03X711990Y518547I-129J153D01*
G01Y521957D01*
Y521959D01*
Y521964D01*
G03X711919Y522117I-200J0D01*
G01X711821Y522199D01*
G03X711658Y522243I-129J-153D01*
G02X711392Y522220I-269J1556D01*
G02Y525378I0J1579D01*
G02X712950Y524051I0J-1578D01*
G01Y524050D01*
X712957Y524010D01*
X713000Y523942D01*
X713307Y523731D01*
X713386Y523715D01*
X713426Y523723D01*
G02X713792Y523760I363J-1765D01*
G02X714158Y523723I3J-1802D01*
G01X714198Y523715D01*
X714277Y523731D01*
X714550Y523919D01*
G03X714634Y524051I-113J165D01*
G02X716192Y525378I1558J-251D01*
G02X717247Y524973I-1J-1579D01*
G03X717380Y524922I133J149D01*
G01X717504D01*
G03X717637Y524973I0J200D01*
G02X718692Y525378I1056J-1174D01*
G02X718959Y525355I-2J-1579D01*
G03X719122Y525399I34J197D01*
G01X719219Y525481D01*
G03X719290Y525634I-129J153D01*
G01Y529043D01*
Y529045D01*
Y529050D01*
G03X719219Y529203I-200J0D01*
G01X719121Y529285D01*
G03X718958Y529329I-129J-153D01*
G02X718692Y529306I-269J1556D01*
G02X717637Y529711I1J1579D01*
G03X717504Y529762I-133J-149D01*
G01X717380D01*
G03X717247Y529711I0J-200D01*
G02X716192Y529306I-1056J1174D01*
G02X714633Y530637I0J1579D01*
G01X714627Y530678D01*
X714583Y530748D01*
X714311Y530935D01*
G03X714158Y530966I-113J-165D01*
G01X714157D01*
G02X713792Y530928I-368J1765D01*
G02X713428Y530966I4J1803D01*
G01X713426D01*
G03X713273Y530935I-40J-196D01*
G01X713001Y530748D01*
X712957Y530678D01*
X712951Y530637D01*
G02X711392Y529306I-1559J248D01*
G02Y532464I0J1579D01*
G02X711659Y532441I-2J-1579D01*
G03X711822Y532485I34J197D01*
G01X711919Y532567D01*
G03X711990Y532720I-129J153D01*
G01Y536130D01*
Y536132D01*
Y536137D01*
G03X711919Y536290I-200J0D01*
G01X711820Y536372D01*
G03X711658Y536416I-129J-153D01*
G02X711392Y536394I-263J1556D01*
G02Y539550I0J1578D01*
G02X712950Y538224I0J-1578D01*
G01X712957Y538183D01*
X713000Y538115D01*
X713307Y537904D01*
X713386Y537888D01*
X713426Y537896D01*
G02X713792Y537934I368J-1765D01*
G02X714158Y537896I-2J-1803D01*
G01X714198Y537888D01*
X714277Y537904D01*
X714550Y538092D01*
G03X714634Y538224I-113J165D01*
G02X716192Y539550I1558J-252D01*
G02Y536394I0J-1578D01*
G02X715926Y536416I-3J1578D01*
G03X715764Y536372I-33J-197D01*
G01X715665Y536290D01*
G03X715594Y536137I129J-153D01*
G01Y532732D01*
Y532730D01*
Y532720D01*
G03X715665Y532567I200J0D01*
G01X715762Y532485D01*
G03X715925Y532441I129J153D01*
G02X716192Y532464I269J-1556D01*
G02X717247Y532059I-1J-1579D01*
G03X717380Y532008I133J149D01*
G01X717504D01*
G03X717637Y532059I0J200D01*
G02X718692Y532464I1056J-1174D01*
G02X720250Y531137I0J-1578D01*
G01Y531136D01*
X720257Y531096D01*
X720300Y531028D01*
X720607Y530817D01*
X720686Y530801D01*
X720726Y530809D01*
G02X721092Y530846I363J-1765D01*
G37*
G36*
G01X643761Y459194D02*
X651061D01*
G02Y451790I0J-3702D01*
G01X643761D01*
G02Y459194I0J3702D01*
G37*
G36*
G01X732796Y553722D02*
X740096D01*
G02Y546318I0J-3702D01*
G01X732796D01*
G02Y553722I0J3702D01*
G37*
G36*
G01X832966Y289692D02*
G02X834072Y289207I0J-1504D01*
G03X834219Y289142I148J135D01*
G01X834513D01*
G03X834660Y289207I-1J200D01*
G02X835766Y289692I1106J-1019D01*
G02X837268Y288190I0J-1502D01*
G02X836898Y287203I-1501J0D01*
G01Y287202D01*
X836897D01*
G03X836849Y287072I152J-130D01*
G01Y286808D01*
G03X836897Y286678I200J0D01*
G01X836898Y286677D01*
G02X837268Y285690I-1131J-987D01*
G02X835766Y284188I-1502J0D01*
G02X834660Y284673I0J1504D01*
G03X834513Y284738I-148J-135D01*
G01X834219D01*
G03X834072Y284673I1J-200D01*
G02X832966Y284188I-1106J1019D01*
G02X831979Y284558I0J1501D01*
G01X831978D01*
Y284559D01*
G03X831848Y284607I-130J-152D01*
G01X831584D01*
G03X831454Y284559I0J-200D01*
G01X831453Y284558D01*
G02X830466Y284188I-987J1131D01*
G02X828964Y285690I0J1502D01*
G02X829334Y286677I1501J0D01*
G01Y286678D01*
X829335D01*
G03X829383Y286808I-152J130D01*
G01Y287072D01*
G03X829335Y287202I-200J0D01*
G01X829334Y287203D01*
G02X828964Y288190I1131J987D01*
G02X830466Y289692I1502J0D01*
G02X831453Y289322I0J-1501D01*
G01X831454D01*
Y289321D01*
G03X831584Y289273I130J152D01*
G01X831848D01*
G03X831978Y289321I0J200D01*
G01X831979Y289322D01*
G02X832966Y289692I987J-1131D01*
G37*
G36*
G01X982966D02*
G02X984072Y289207I0J-1504D01*
G03X984219Y289142I148J135D01*
G01X984513D01*
G03X984660Y289207I-1J200D01*
G02X985766Y289692I1106J-1019D01*
G02X987268Y288190I0J-1502D01*
G02X986898Y287203I-1501J0D01*
G01Y287202D01*
X986897D01*
G03X986849Y287072I152J-130D01*
G01Y286808D01*
G03X986897Y286678I200J0D01*
G01X986898Y286677D01*
G02X987268Y285690I-1131J-987D01*
G02X985766Y284188I-1502J0D01*
G02X984660Y284673I0J1504D01*
G03X984513Y284738I-148J-135D01*
G01X984219D01*
G03X984072Y284673I1J-200D01*
G02X982966Y284188I-1106J1019D01*
G02X981979Y284558I0J1501D01*
G01X981978D01*
Y284559D01*
G03X981848Y284607I-130J-152D01*
G01X981584D01*
G03X981454Y284559I0J-200D01*
G01X981453Y284558D01*
G02X980466Y284188I-987J1131D01*
G02X978964Y285690I0J1502D01*
G02X979334Y286677I1501J0D01*
G01Y286678D01*
X979335D01*
G03X979383Y286808I-152J130D01*
G01Y287072D01*
G03X979335Y287202I-200J0D01*
G01X979334Y287203D01*
G02X978964Y288190I1131J987D01*
G02X980466Y289692I1502J0D01*
G02X981453Y289322I0J-1501D01*
G01X981454D01*
Y289321D01*
G03X981584Y289273I130J152D01*
G01X981848D01*
G03X981978Y289321I0J200D01*
G01X981979Y289322D01*
G02X982966Y289692I987J-1131D01*
G37*
G36*
G01X855111Y292098D02*
Y292392D01*
G03X855046Y292539I-200J-1D01*
G02X854561Y293645I1019J1106D01*
G02X856063Y295147I1502J0D01*
G02X857050Y294777I0J-1501D01*
G01X857051D01*
Y294776D01*
G03X857181Y294728I130J152D01*
G01X857445D01*
G03X857575Y294776I0J200D01*
G01X857576Y294777D01*
G02X858563Y295147I987J-1131D01*
G02X860065Y293645I0J-1502D01*
G02X859580Y292539I-1504J0D01*
G03X859515Y292392I135J-148D01*
G01Y292098D01*
G03X859580Y291951I200J1D01*
G02X860065Y290845I-1019J-1106D01*
G02X859695Y289858I-1501J0D01*
G01Y289857D01*
X859694D01*
G03X859646Y289727I152J-130D01*
G01Y289463D01*
G03X859694Y289333I200J0D01*
G01X859695Y289332D01*
G02X860065Y288345I-1131J-987D01*
G02X858563Y286843I-1502J0D01*
G02X857576Y287213I0J1501D01*
G01X857575D01*
Y287214D01*
G03X857445Y287262I-130J-152D01*
G01X857181D01*
G03X857051Y287214I0J-200D01*
G01X857050Y287213D01*
G02X856063Y286843I-987J1131D01*
G02X854561Y288345I0J1502D01*
G02X854931Y289332I1501J0D01*
G01Y289333D01*
X854932D01*
G03X854980Y289463I-152J130D01*
G01Y289727D01*
G03X854932Y289857I-200J0D01*
G01X854931Y289858D01*
G02X854561Y290845I1131J987D01*
G02X855046Y291951I1504J0D01*
G03X855111Y292098I-135J148D01*
G37*
G36*
G01X1005111D02*
Y292392D01*
G03X1005046Y292539I-200J-1D01*
G02X1004561Y293645I1019J1106D01*
G02X1006063Y295147I1502J0D01*
G02X1007050Y294777I0J-1501D01*
G01X1007051D01*
Y294776D01*
G03X1007181Y294728I130J152D01*
G01X1007445D01*
G03X1007575Y294776I0J200D01*
G01X1007576Y294777D01*
G02X1008563Y295147I987J-1131D01*
G02X1010065Y293645I0J-1502D01*
G02X1009580Y292539I-1504J0D01*
G03X1009515Y292392I135J-148D01*
G01Y292098D01*
G03X1009580Y291951I200J1D01*
G02X1010065Y290845I-1019J-1106D01*
G02X1009695Y289858I-1501J0D01*
G01Y289857D01*
X1009694D01*
G03X1009646Y289727I152J-130D01*
G01Y289463D01*
G03X1009694Y289333I200J0D01*
G01X1009695Y289332D01*
G02X1010065Y288345I-1131J-987D01*
G02X1008563Y286843I-1502J0D01*
G02X1007576Y287213I0J1501D01*
G01X1007575D01*
Y287214D01*
G03X1007445Y287262I-130J-152D01*
G01X1007181D01*
G03X1007051Y287214I0J-200D01*
G01X1007050Y287213D01*
G02X1006063Y286843I-987J1131D01*
G02X1004561Y288345I0J1502D01*
G02X1004931Y289332I1501J0D01*
G01Y289333D01*
X1004932D01*
G03X1004980Y289463I-152J130D01*
G01Y289727D01*
G03X1004932Y289857I-200J0D01*
G01X1004931Y289858D01*
G02X1004561Y290845I1131J987D01*
G02X1005046Y291951I1504J0D01*
G03X1005111Y292098I-135J148D01*
G37*
G36*
G01X822452Y292294D02*
G02Y295298I0J1502D01*
G02X823439Y294928I0J-1501D01*
G01X823440D01*
Y294927D01*
G03X823570Y294879I130J152D01*
G01X823834D01*
G03X823964Y294927I0J200D01*
G01X823965Y294928D01*
G02X824952Y295298I987J-1131D01*
G02Y292294I0J-1502D01*
G02X823965Y292664I0J1501D01*
G01X823964D01*
Y292665D01*
G03X823834Y292713I-130J-152D01*
G01X823570D01*
G03X823440Y292665I0J-200D01*
G01X823439Y292664D01*
G02X822452Y292294I-987J1131D01*
G37*
G36*
G01X972452D02*
G02Y295298I0J1502D01*
G02X973439Y294928I0J-1501D01*
G01X973440D01*
Y294927D01*
G03X973570Y294879I130J152D01*
G01X973834D01*
G03X973964Y294927I0J200D01*
G01X973965Y294928D01*
G02X974952Y295298I987J-1131D01*
G02Y292294I0J-1502D01*
G02X973965Y292664I0J1501D01*
G01X973964D01*
Y292665D01*
G03X973834Y292713I-130J-152D01*
G01X973570D01*
G03X973440Y292665I0J-200D01*
G01X973439Y292664D01*
G02X972452Y292294I-987J1131D01*
G37*
G36*
G01X870548Y302644D02*
G02X873552I1502J0D01*
G02X873418Y302024I-1501J0D01*
G01X873400Y301985D01*
Y301897D01*
X873565Y301543D01*
X873630Y301487D01*
X873673Y301475D01*
G02X874764Y300030I-411J-1445D01*
G02X871760I-1502J0D01*
G02X871894Y300650I1501J0D01*
G01X871912Y300689D01*
Y300777D01*
X871747Y301131D01*
X871682Y301187D01*
X871639Y301199D01*
G02X870548Y302644I411J1445D01*
G37*
G36*
G01X897550Y308561D02*
Y311963D01*
G02X899352Y313764I1802J-1D01*
G02X900245Y313527I-1J-1803D01*
G03X900388Y313505I100J173D01*
G01X900506Y313532D01*
G03X900626Y313611I-43J195D01*
G02X901848Y314240I1222J-873D01*
G02Y311236I0J-1502D01*
G02X901616Y311254I0J1502D01*
G03X901455Y311208I-31J-198D01*
G01X901224Y311011D01*
G03X901154Y310859I130J-152D01*
G01Y309739D01*
G03X901223Y309587I200J-1D01*
G01X901487Y309360D01*
X901570Y309336D01*
X901614Y309343D01*
G02X901848Y309360I231J-1561D01*
G02Y306204I0J-1578D01*
G02X900559Y306872I0J1578D01*
G03X900443Y306950I-163J-117D01*
G01X900326Y306979D01*
G03X900185Y306963I-49J-194D01*
G02X899352Y306758I-835J1598D01*
G02X897550Y308561I1J1803D01*
G37*
G36*
G01X1020933Y312865D02*
G02X1023937I1502J0D01*
G02X1023292Y311631I-1503J0D01*
G01X1023262Y311611D01*
X1023220Y311549D01*
X1023150Y311253D01*
G03X1023168Y311112I194J-47D01*
G02X1023350Y310396I-1320J-717D01*
G02X1020346I-1502J0D01*
G02X1020991Y311630I1503J0D01*
G01X1021021Y311650D01*
X1021063Y311712D01*
X1021133Y312008D01*
G03X1021115Y312149I-194J47D01*
G02X1020933Y312865I1320J717D01*
G37*
G36*
G01X409484Y313419D02*
G02Y316423I0J1502D01*
G02X410471Y316053I0J-1501D01*
G01X410472D01*
Y316052D01*
G03X410602Y316004I130J152D01*
G01X410866D01*
G03X410996Y316052I0J200D01*
G01X410997Y316053D01*
G02X411984Y316423I987J-1131D01*
G02Y313419I0J-1502D01*
G02X410997Y313789I0J1501D01*
G01X410996D01*
Y313790D01*
G03X410866Y313838I-130J-152D01*
G01X410602D01*
G03X410472Y313790I0J-200D01*
G01X410471Y313789D01*
G02X409484Y313419I-987J1131D01*
G37*
G36*
G01X935198Y312283D02*
Y315685D01*
G02X937000Y317486I1802J-1D01*
G02X937571Y317393I-1J-1803D01*
G01X937613Y317379D01*
X937701Y317389D01*
X938000Y317571D01*
G03X938093Y317712I-105J170D01*
G02X939653Y319052I1560J-238D01*
G02Y315896I0J-1578D01*
G01X939652D01*
G02X939165Y315973I0J1578D01*
G03X938985Y315944I-62J-190D01*
G01X938884Y315870D01*
G03X938802Y315706I118J-161D01*
G01Y312284D01*
Y312282D01*
G02X938801Y312202I-1802J-17D01*
G01X938986Y312066D01*
G03X939161Y312035I119J161D01*
G02X939606Y312100I448J-1513D01*
G02Y308942I0J-1579D01*
G02X938051Y310249I0J1579D01*
G01Y310251D01*
X938043Y310293D01*
X937995Y310363D01*
X937664Y310566D01*
X937579Y310576D01*
X937538Y310563D01*
G02X937000Y310480I-541J1720D01*
G02X935198Y312283I1J1803D01*
G37*
G36*
G01X1077252Y321942D02*
G02Y325100I0J1579D01*
G02X1078541Y324431I-1J-1577D01*
G03X1078657Y324353I163J117D01*
G01X1078775Y324324D01*
G03X1078915Y324340I49J194D01*
G02X1079746Y324544I833J-1598D01*
G01X1079748D01*
G02X1081550Y322742I0J-1802D01*
G01Y319342D01*
G02X1079748Y317540I-1802J0D01*
G02X1078913Y317744I-2J1803D01*
G03X1078774Y317761I-92J-178D01*
G01X1078656Y317732D01*
G03X1078540Y317653I47J-194D01*
G02X1077252Y316986I-1289J912D01*
G02Y320144I0J1579D01*
G02X1077486Y320126I-4J-1579D01*
G01X1077530Y320119D01*
X1077613Y320143D01*
X1077877Y320370D01*
G03X1077946Y320522I-131J151D01*
G01Y321564D01*
G03X1077877Y321716I-200J1D01*
G01X1077613Y321943D01*
X1077530Y321967D01*
X1077486Y321960D01*
G02X1077252Y321942I-238J1561D01*
G37*
G36*
G01X989222Y308702D02*
G02X988869Y307852I-1202J1D01*
G01X986690Y305674D01*
G03X986688Y305672I140J-142D01*
G01X986549Y305528D01*
G02X986481Y305482I-144J139D01*
G01X986104Y305329D01*
G02X986029Y305314I-76J185D01*
G01X975033D01*
G02X974184Y305667I2J1202D01*
G01X973136Y306714D01*
G02X972785Y307566I851J849D01*
G01X972786D01*
Y321794D01*
G03X972718Y321944I-200J0D01*
G01X972492Y322143D01*
G03X972336Y322191I-132J-150D01*
G01X972335D01*
G02X972147Y322179I-189J1490D01*
G02Y325183I0J1502D01*
G02X973188Y324763I0J-1500D01*
G03X973303Y324709I138J145D01*
G01X973419Y324695D01*
G03X973543Y324720I24J199D01*
G02X974139Y324880I599J-1041D01*
G01X987383D01*
G02X988233Y324527I-1J-1202D01*
G01X988869Y323891D01*
G02X989222Y323041I-849J-851D01*
G01Y315969D01*
G02X988891Y315142I-1202J1D01*
G03X988838Y315031I145J-137D01*
G01X988822Y314918D01*
G03X988844Y314797I198J-26D01*
G02X989019Y314092I-1327J-704D01*
G02X988844Y313387I-1502J-1D01*
G03X988822Y313266I176J-95D01*
G01X988838Y313153D01*
G03X988891Y313042I198J26D01*
G02X989222Y312215I-871J-828D01*
G01Y308702D01*
G37*
G36*
G01X839573Y323748D02*
G02Y326906I0J1579D01*
G02X840873Y326223I0J-1579D01*
G03X840874Y326221I177J87D01*
G03X840999Y326139I164J114D01*
G01X841312Y326077D01*
X841388Y326092D01*
X841421Y326113D01*
G02X842240Y326356I819J-1259D01*
G02Y323352I0J-1502D01*
G02X841038Y323953I0J1502D01*
G03X840909Y324031I-160J-120D01*
G01X840633Y324074D01*
G03X840487Y324041I-32J-197D01*
G01X840486Y324040D01*
G02X839573Y323748I-915J1286D01*
G37*
G36*
G01X916080Y324817D02*
Y328218D01*
G02X916791Y329652I1802J0D01*
G01X916827Y329679D01*
X916868Y329758D01*
X916881Y330113D01*
G03X916813Y330270I-200J7D01*
G02X916280Y331453I1046J1183D01*
G02X919436I1578J0D01*
G01Y331452D01*
G02X918920Y330285I-1578J0D01*
G01X918887Y330255D01*
X918853Y330172D01*
X918873Y329773D01*
X918915Y329695D01*
X918952Y329668D01*
G02X919684Y328219I-1070J-1450D01*
G01Y324817D01*
G02X919016Y323416I-1803J0D01*
G01X918982Y323389D01*
X918944Y323312D01*
X918929Y322924D01*
X918961Y322845D01*
X918993Y322815D01*
G02X919484Y321672I-1087J-1144D01*
G01Y321670D01*
G02X916328I-1578J0D01*
G02X916802Y322798I1579J0D01*
G01X916803Y322799D01*
G03X916862Y322952I-141J142D01*
G01X916846Y323252D01*
G03X916769Y323399I-200J-11D01*
G02X916080Y324817I1115J1418D01*
G37*
G36*
G01X1077855Y330856D02*
G02Y334012I0J1578D01*
G02X1079144Y333344I0J-1578D01*
G03X1079260Y333266I163J117D01*
G01X1079377Y333237D01*
G03X1079518Y333253I49J194D01*
G02X1080351Y333458I835J-1598D01*
G02X1082154Y331655I0J-1803D01*
G01Y328255D01*
G02X1080351Y326452I-1803J0D01*
G02X1079516Y326657I0J1803D01*
G03X1079377Y326674I-92J-178D01*
G01X1079259Y326645D01*
G03X1079143Y326566I47J-194D01*
G02X1077855Y325900I-1288J912D01*
G02Y329056I0J1578D01*
G02X1078089Y329039I3J-1578D01*
G01X1078133Y329032D01*
X1078216Y329056D01*
X1078479Y329283D01*
G03X1078548Y329435I-131J151D01*
G01Y330477D01*
G03X1078479Y330629I-200J1D01*
G01X1078216Y330856D01*
X1078133Y330880D01*
X1078089Y330873D01*
G02X1077855Y330856I-231J1561D01*
G37*
G36*
G01X807988Y333368D02*
G02X810992I1502J0D01*
G01Y333367D01*
G02X810445Y332208I-1502J0D01*
G01X810410Y332179D01*
X810372Y332101D01*
X810368Y331706D01*
X810404Y331625D01*
X810438Y331597D01*
G02X810959Y330459I-982J-1138D01*
G02X807955I-1502J0D01*
G01Y330460D01*
G02X808502Y331619I1502J0D01*
G01X808537Y331648D01*
X808575Y331726D01*
X808579Y332121D01*
X808543Y332202D01*
X808509Y332230D01*
G02X807988Y333368I982J1138D01*
G37*
G36*
G01X400993Y337091D02*
G02Y334087I0J-1502D01*
G02X400882Y334091I-1J1502D01*
G01X400840Y334094D01*
X400764Y334067D01*
X400518Y333842D01*
G03X400453Y333696I135J-148D01*
G02X400442Y333532I-1502J18D01*
G01Y333531D01*
X400437Y333487D01*
X400465Y333403D01*
X400711Y333147D01*
G03X400872Y333086I144J138D01*
G02X400993Y333091I122J-1497D01*
G02X399491Y331589I0J-1502D01*
G02X399502Y331768I1502J-2D01*
G01X399507Y331813D01*
X399479Y331897D01*
X399233Y332153D01*
G03X399072Y332214I-144J-138D01*
G02X398951Y332209I-122J1497D01*
G02Y335213I0J1502D01*
G02X399062Y335209I1J-1502D01*
G01X399104Y335206D01*
X399180Y335233D01*
X399426Y335458D01*
G03X399491Y335604I-135J148D01*
G02X400993Y337091I1502J-15D01*
G37*
G36*
G01X916228Y338136D02*
X919628D01*
G02X920874Y337635I-1J-1803D01*
G01X920875Y337634D01*
G03X921021Y337580I137J146D01*
G01X921309Y337592D01*
G03X921449Y337657I-8J200D01*
G01X921450Y337658D01*
G02X922629Y338188I1180J-1049D01*
G02Y335030I0J-1579D01*
G02X921661Y335362I1J1579D01*
G01X921629Y335387D01*
X921550Y335408D01*
X921225Y335361D01*
G03X921091Y335280I28J-198D01*
G02X919628Y334530I-1463J1052D01*
G01X916228D01*
G02X914804Y335228I1J1803D01*
G01X914779Y335260D01*
X914708Y335299D01*
X914379Y335333D01*
G03X914229Y335287I-21J-199D01*
G02X913206Y334910I-1024J1202D01*
G02Y338068I0J1579D01*
G02X914347Y337579I-1J-1578D01*
G01X914375Y337550D01*
X914450Y337518D01*
X914823Y337517D01*
X914897Y337549D01*
X914926Y337579D01*
G02X916228Y338136I1303J-1246D01*
G37*
G36*
G01X991918Y337954D02*
G02X994922I1502J0D01*
G02X994710Y337185I-1501J0D01*
G01X994691Y337153D01*
X994679Y337081D01*
X994739Y336781D01*
G03X994816Y336660I196J40D01*
G02X995422Y335454I-897J-1206D01*
G02X992418I-1502J0D01*
G02X992630Y336223I1501J0D01*
G01X992649Y336255D01*
X992661Y336327D01*
X992601Y336627D01*
G03X992524Y336748I-196J-40D01*
G02X991918Y337954I897J1206D01*
G37*
G36*
G01X939394Y338238D02*
G02X942550I1578J0D01*
G01Y338237D01*
G02X942169Y337209I-1578J0D01*
G03X942121Y337066I152J-130D01*
G01X942139Y336786D01*
G03X942203Y336652I200J13D01*
G01X942204Y336651D01*
G02X942800Y335313I-1206J-1339D01*
G01Y331913D01*
G02X942171Y330545I-1803J0D01*
G03X942169Y330544I85J-173D01*
G01X942140Y330519D01*
X942105Y330449D01*
X942079Y330127D01*
G03X942126Y329982I200J-15D01*
G02X942502Y328960I-1202J-1022D01*
G01Y328959D01*
G02X939346I-1578J0D01*
G02X939774Y330040I1579J0D01*
G01X939801Y330069D01*
X939829Y330142D01*
X939818Y330505D01*
X939786Y330577D01*
X939757Y330604D01*
G02X939194Y331913I1240J1309D01*
G01Y335313D01*
G02X939767Y336631I1802J0D01*
G01X939795Y336657D01*
X939828Y336728D01*
X939843Y337047D01*
G03X939793Y337189I-200J9D01*
G02X939394Y338238I1179J1049D01*
G37*
G36*
G01X975631Y348114D02*
G02Y345110I0J-1502D01*
G01X975630D01*
G02X975308Y345145I0J1502D01*
G01X975307D01*
G03X975150Y345114I-43J-195D01*
G01X974910Y344947D01*
G03X974826Y344810I114J-164D01*
G02X974813Y344734I-1487J215D01*
G01X974995Y344583D01*
G03X975183Y344545I129J153D01*
G02X975631Y344614I450J-1432D01*
G02X974129Y343112I0J-1502D01*
G01Y343147D01*
X974130Y343193D01*
X974093Y343277D01*
X973816Y343506D01*
G03X973647Y343548I-128J-154D01*
G02X973339Y343516I-308J1470D01*
G01X973338D01*
G02Y346520I0J1502D01*
G01X973339D01*
G02X973661Y346485I0J-1502D01*
G01X973662D01*
G03X973819Y346516I43J195D01*
G01X974059Y346683D01*
G03X974143Y346820I-114J164D01*
G02X975631Y348114I1488J-209D01*
G37*
G36*
G01X939299Y348166D02*
X942699D01*
G02X944376Y347023I0J-1802D01*
G03X944489Y346910I186J73D01*
G01X944800Y346787D01*
X944883Y346790D01*
X944920Y346808D01*
G02X945599Y346962I680J-1425D01*
G02Y343804I0J-1579D01*
G02X944195Y344662I0J1578D01*
G01X944176Y344699D01*
X944112Y344751D01*
X943790Y344842D01*
G03X943633Y344821I-54J-192D01*
G01X943632D01*
G02X942699Y344560I-934J1542D01*
G01X939299D01*
G02X938415Y344792I1J1803D01*
G01X938414D01*
G03X938258Y344809I-98J-174D01*
G01X937942Y344713D01*
X937880Y344661D01*
X937862Y344624D01*
G02X936453Y343758I-1409J713D01*
G02Y346914I0J1578D01*
G02X937083Y346784I3J-1579D01*
G01X937120Y346767D01*
X937202D01*
X937507Y346895D01*
G03X937616Y347006I-77J185D01*
G01Y347007D01*
G02X939299Y348166I1684J-644D01*
G37*
G36*
G01X827802Y348036D02*
G02X830960I1579J0D01*
G02X830435Y346861I-1577J0D01*
G01X830402Y346831D01*
X830368Y346753D01*
X830374Y346405D01*
G03X830445Y346256I200J4D01*
G01X830446Y346255D01*
G02X830987Y345101I-960J-1154D01*
G02X827983I-1502J0D01*
G02X828445Y346185I1503J0D01*
G01X828476Y346215D01*
X828508Y346296D01*
X828488Y346686D01*
X828448Y346762D01*
X828413Y346789D01*
G02X827802Y348036I967J1247D01*
G37*
G36*
G01X870656Y359962D02*
G02X873660I1502J0D01*
G02X873654Y359831I-1502J3D01*
G01X873651Y359793D01*
X873672Y359721D01*
X873886Y359446D01*
X873952Y359408D01*
X873988Y359402D01*
G02X875312Y357844I-255J-1558D01*
G02X872154I-1579J0D01*
G02X872168Y358047I1579J-7D01*
G01Y358049D01*
X872173Y358086D01*
X872155Y358159D01*
X871974Y358411D01*
G03X871852Y358491I-163J-116D01*
G02X870656Y359962I307J1471D01*
G37*
G36*
G01X946196Y352192D02*
G02X943192I-1502J0D01*
G01Y352194D01*
G02X943372Y352906I1502J-1D01*
G01X943397Y352952D01*
X943395Y353057D01*
X943192Y353398D01*
G03X943020Y353496I-172J-102D01*
G01X942656D01*
G02X942514Y353555I0J200D01*
G01X938757Y357311D01*
G02X938698Y357453I141J142D01*
G01Y360417D01*
G03X938640Y360559I-200J1D01*
G01X938556Y360643D01*
G03X938424Y360702I-142J-141D01*
G02Y363702I75J1500D01*
G03X938556Y363761I-10J200D01*
G01X938640Y363845D01*
G03X938698Y363987I-142J141D01*
G01Y371632D01*
G02X938757Y371774I200J0D01*
G01X940126Y373143D01*
G02X940268Y373202I142J-141D01*
G01X957002D01*
G02X957144Y373143I0J-200D01*
G01X960819Y369468D01*
G02X960878Y369326I-141J-142D01*
G01Y355228D01*
G02X960819Y355086I-200J0D01*
G01X959287Y353555D01*
G02X959145Y353496I-142J141D01*
G01X946368D01*
G03X946196Y353398I0J-200D01*
G01X945993Y353057D01*
X945991Y352952D01*
X946016Y352906D01*
G02X946196Y352194I-1322J-713D01*
G01Y352192D01*
G37*
G36*
G01X743336Y379065D02*
X743337D01*
G02X743851Y370691I0J-4203D01*
G03X743703Y370594I24J-198D01*
G01X743518Y370281D01*
X743512Y370188D01*
X743529Y370145D01*
G02X743798Y368760I-3433J-1385D01*
G02X740096Y365058I-3702J0D01*
G01X732796D01*
G02Y372462I0J3702D01*
G01X739191D01*
G03X739361Y372556I0J200D01*
G01X739569Y372886D01*
X739574Y372989D01*
X739552Y373035D01*
G02X743336Y379065I3784J1828D01*
G37*
G36*
G01X647411D02*
X647412D01*
G02X651144Y372931I-1J-4203D01*
G01X651121Y372886D01*
X651122Y372787D01*
X651307Y372452D01*
G03X651466Y372349I175J96D01*
G02X654762Y368760I-306J-3589D01*
G01Y368758D01*
G02X651161Y365158I-3601J1D01*
G01X643661D01*
G02X640060Y368760I1J3602D01*
G02X643356Y372349I3602J0D01*
G03X643515Y372452I-16J199D01*
G01X643675Y372743D01*
G03X643678Y372931I-175J97D01*
G02X647411Y379065I3733J1931D01*
G37*
G36*
G01X568436Y378317D02*
G02X571440I1502J0D01*
G01Y378315D01*
G02X571136Y377410I-1502J1D01*
G01X571109Y377375D01*
X571090Y377286D01*
X571174Y376941D01*
G03X571282Y376808I194J47D01*
G02X572000Y376079I-647J-1356D01*
G01X572019Y376038D01*
X572086Y375981D01*
X572430Y375890D01*
G03X572597Y375921I50J193D01*
G01X572598D01*
G02X573479Y376207I882J-1216D01*
G02Y373203I0J-1502D01*
G02X572113Y374079I0J1503D01*
G01X572094Y374120D01*
X572027Y374177D01*
X571683Y374268D01*
G03X571516Y374237I-50J-193D01*
G01X571515D01*
G02X570634Y373951I-882J1216D01*
G02X569132Y375453I0J1502D01*
G01Y375455D01*
G02X569436Y376360I1502J-1D01*
G01X569463Y376395D01*
X569482Y376484D01*
X569398Y376829D01*
G03X569290Y376962I-194J-47D01*
G02X568436Y378317I648J1355D01*
G37*
G36*
G01X858586Y383498D02*
G02X860088Y385000I0J1502D01*
G02X860086Y384920I-1502J-2D01*
G01X860084Y384877D01*
X860114Y384798D01*
X860384Y384528D01*
X860463Y384498D01*
X860506Y384500D01*
G02X860586Y384502I78J-1500D01*
G02X859084Y383000I0J-1502D01*
G02X859086Y383080I1502J2D01*
G01X859088Y383123D01*
X859058Y383202D01*
X858788Y383472D01*
X858709Y383502D01*
X858666Y383500D01*
G02X858586Y383498I-78J1500D01*
G37*
G36*
G01X404919Y387151D02*
G02X407923I1502J0D01*
G02X407553Y386164I-1501J0D01*
G01Y386163D01*
X407552D01*
G03X407504Y386033I152J-130D01*
G01Y385769D01*
G03X407552Y385639I200J0D01*
G01X407553Y385638D01*
G02Y383664I-1131J-987D01*
G01Y383663D01*
X407552D01*
G03X407504Y383533I152J-130D01*
G01Y383269D01*
G03X407552Y383139I200J0D01*
G01X407553Y383138D01*
G02X407923Y382151I-1131J-987D01*
G02X404919I-1502J0D01*
G02X405289Y383138I1501J0D01*
G01Y383139D01*
X405290D01*
G03X405338Y383269I-152J130D01*
G01Y383533D01*
G03X405290Y383663I-200J0D01*
G01X405289Y383664D01*
G02Y385638I1131J987D01*
G01Y385639D01*
X405290D01*
G03X405338Y385769I-152J130D01*
G01Y386033D01*
G03X405290Y386163I-200J0D01*
G01X405289Y386164D01*
G02X404919Y387151I1131J987D01*
G37*
G36*
G01X417495Y387210D02*
G02X420499I1502J0D01*
G02X420129Y386223I-1501J0D01*
G01Y386222D01*
X420128D01*
G03X420080Y386092I152J-130D01*
G01Y385828D01*
G03X420128Y385698I200J0D01*
G01X420129Y385697D01*
G02Y383723I-1131J-987D01*
G01Y383722D01*
X420128D01*
G03X420080Y383592I152J-130D01*
G01Y383328D01*
G03X420128Y383198I200J0D01*
G01X420129Y383197D01*
G02X420499Y382210I-1131J-987D01*
G02X417495I-1502J0D01*
G02X417865Y383197I1501J0D01*
G01Y383198D01*
X417866D01*
G03X417914Y383328I-152J130D01*
G01Y383592D01*
G03X417866Y383722I-200J0D01*
G01X417865Y383723D01*
G02Y385697I1131J987D01*
G01Y385698D01*
X417866D01*
G03X417914Y385828I-152J130D01*
G01Y386092D01*
G03X417866Y386222I-200J0D01*
G01X417865Y386223D01*
G02X417495Y387210I1131J987D01*
G37*
G36*
G01X400000Y386750D02*
X399706D01*
G03X399559Y386685I1J-200D01*
G02X398453Y386200I-1106J1019D01*
G02Y389204I0J1502D01*
G02X399559Y388719I0J-1504D01*
G03X399706Y388654I148J135D01*
G01X400000D01*
G03X400147Y388719I-1J200D01*
G02X401253Y389204I1106J-1019D01*
G02Y386200I0J-1502D01*
G02X400147Y386685I0J1504D01*
G03X400000Y386750I-148J-135D01*
G37*
G36*
G01X390438Y388817D02*
G02X391940Y390319I1502J0D01*
G02X392795Y390052I0J-1502D01*
G01X392829Y390029D01*
X392910Y390012D01*
X393277Y390092D01*
X393344Y390140D01*
X393365Y390175D01*
G02X394653Y390904I1288J-773D01*
G02Y387900I0J-1502D01*
G02X393798Y388167I0J1502D01*
G01X393764Y388190D01*
X393683Y388207D01*
X393316Y388127D01*
X393249Y388079D01*
X393228Y388044D01*
G02X393072Y387831I-1285J777D01*
G03X393071Y387829I173J-88D01*
G03X393023Y387699I152J-130D01*
G01Y387435D01*
G03X393071Y387305I200J0D01*
G01X393072Y387304D01*
G02Y385330I-1131J-987D01*
G01Y385329D01*
X393071D01*
G03X393023Y385199I152J-130D01*
G01Y384935D01*
G03X393071Y384805I200J0D01*
G01X393072Y384804D01*
G02X393442Y383817I-1131J-987D01*
G02X390438I-1502J0D01*
G02X390808Y384804I1501J0D01*
G01Y384805D01*
X390809D01*
G03X390857Y384935I-152J130D01*
G01Y385199D01*
G03X390809Y385329I-200J0D01*
G01X390808Y385330D01*
G02Y387304I1131J987D01*
G01Y387305D01*
X390809D01*
G03X390857Y387435I-152J130D01*
G01Y387699D01*
G03X390809Y387829I-200J0D01*
G01X390808Y387830D01*
G02X390438Y388817I1131J987D01*
G37*
G36*
G01X604688Y396011D02*
X604806Y395982D01*
G03X604945Y395999I47J195D01*
G02X605779Y396204I835J-1598D01*
G02X606613Y395999I-1J-1803D01*
G03X606752Y395982I92J178D01*
G01X606870Y396011D01*
G03X606986Y396090I-47J194D01*
G02X608275Y396758I1289J-910D01*
G02Y393600I0J-1579D01*
G02X608041Y393618I4J1579D01*
G01X607997Y393625D01*
X607914Y393601D01*
X607651Y393374D01*
G03X607582Y393222I131J-151D01*
G01Y392180D01*
G03X607651Y392028I200J-1D01*
G01X607914Y391801D01*
X607997Y391777D01*
X608041Y391784D01*
G02X608275Y391802I238J-1561D01*
G02Y388644I0J-1579D01*
G02X606986Y389312I0J1578D01*
G03X606870Y389391I-163J-115D01*
G01X606752Y389420D01*
G03X606613Y389403I-47J-195D01*
G02X605779Y389198I-835J1598D01*
G02X604945Y389403I1J1803D01*
G03X604806Y389420I-92J-178D01*
G01X604688Y389391D01*
G03X604572Y389312I47J-194D01*
G02X603283Y388644I-1289J910D01*
G02Y391802I0J1579D01*
G02X603517Y391784I-4J-1579D01*
G01X603561Y391777D01*
X603644Y391801D01*
X603907Y392028D01*
G03X603976Y392180I-131J151D01*
G01Y393222D01*
G03X603907Y393374I-200J1D01*
G01X603644Y393601D01*
X603561Y393625D01*
X603517Y393618D01*
G02X603283Y393600I-238J1561D01*
G02Y396758I0J1579D01*
G02X604572Y396090I0J-1578D01*
G03X604688Y396011I163J115D01*
G37*
G36*
G01X1061774D02*
X1061892Y395982D01*
G03X1062031Y395999I47J195D01*
G02X1062865Y396204I835J-1598D01*
G02X1063699Y395999I-1J-1803D01*
G03X1063838Y395982I92J178D01*
G01X1063956Y396011D01*
G03X1064072Y396090I-47J194D01*
G02X1065361Y396758I1289J-910D01*
G02Y393600I0J-1579D01*
G02X1065127Y393618I4J1579D01*
G01X1065083Y393625D01*
X1065000Y393601D01*
X1064737Y393374D01*
G03X1064668Y393222I131J-151D01*
G01Y392180D01*
G03X1064737Y392028I200J-1D01*
G01X1065000Y391801D01*
X1065083Y391777D01*
X1065127Y391784D01*
G02X1065361Y391802I238J-1561D01*
G02Y388644I0J-1579D01*
G02X1064072Y389312I0J1578D01*
G03X1063956Y389391I-163J-115D01*
G01X1063838Y389420D01*
G03X1063699Y389403I-47J-195D01*
G02X1062865Y389198I-835J1598D01*
G02X1062031Y389403I1J1803D01*
G03X1061892Y389420I-92J-178D01*
G01X1061774Y389391D01*
G03X1061658Y389312I47J-194D01*
G02X1060369Y388644I-1289J910D01*
G02Y391802I0J1579D01*
G02X1060603Y391784I-4J-1579D01*
G01X1060647Y391777D01*
X1060730Y391801D01*
X1060993Y392028D01*
G03X1061062Y392180I-131J151D01*
G01Y393222D01*
G03X1060993Y393374I-200J1D01*
G01X1060730Y393601D01*
X1060647Y393625D01*
X1060603Y393618D01*
G02X1060369Y393600I-238J1561D01*
G02Y396758I0J1579D01*
G02X1061658Y396090I0J-1578D01*
G03X1061774Y396011I163J115D01*
G37*
G36*
G01X383364Y396776D02*
G02Y399780I0J1502D01*
G02X384351Y399410I0J-1501D01*
G01X384352D01*
Y399409D01*
G03X384482Y399361I130J152D01*
G01X384746D01*
G03X384876Y399409I0J200D01*
G01X384877Y399410D01*
G02X385864Y399780I987J-1131D01*
G02Y396776I0J-1502D01*
G02X384877Y397146I0J1501D01*
G01X384876D01*
Y397147D01*
G03X384746Y397195I-130J-152D01*
G01X384482D01*
G03X384352Y397147I0J-200D01*
G01X384351Y397146D01*
G02X383364Y396776I-987J1131D01*
G37*
G36*
G01X405341Y401661D02*
G02X408345I1502J0D01*
G02X407975Y400674I-1501J0D01*
G01Y400673D01*
X407974D01*
G03X407926Y400543I152J-130D01*
G01Y400279D01*
G03X407974Y400149I200J0D01*
G01X407975Y400148D01*
G02Y398174I-1131J-987D01*
G01Y398173D01*
X407974D01*
G03X407926Y398043I152J-130D01*
G01Y397779D01*
G03X407974Y397649I200J0D01*
G01X407975Y397648D01*
G02X408345Y396661I-1131J-987D01*
G02X405341I-1502J0D01*
G02X405711Y397648I1501J0D01*
G01Y397649D01*
X405712D01*
G03X405760Y397779I-152J130D01*
G01Y398043D01*
G03X405712Y398173I-200J0D01*
G01X405711Y398174D01*
G02Y400148I1131J987D01*
G01Y400149D01*
X405712D01*
G03X405760Y400279I-152J130D01*
G01Y400543D01*
G03X405712Y400673I-200J0D01*
G01X405711Y400674D01*
G02X405341Y401661I1131J987D01*
G37*
G36*
G01X417374D02*
G02X420378I1502J0D01*
G02X420008Y400674I-1501J0D01*
G01Y400673D01*
X420007D01*
G03X419959Y400543I152J-130D01*
G01Y400279D01*
G03X420007Y400149I200J0D01*
G01X420008Y400148D01*
G02Y398174I-1131J-987D01*
G01Y398173D01*
X420007D01*
G03X419959Y398043I152J-130D01*
G01Y397779D01*
G03X420007Y397649I200J0D01*
G01X420008Y397648D01*
G02X420378Y396661I-1131J-987D01*
G02X417374I-1502J0D01*
G02X417744Y397648I1501J0D01*
G01Y397649D01*
X417745D01*
G03X417793Y397779I-152J130D01*
G01Y398043D01*
G03X417745Y398173I-200J0D01*
G01X417744Y398174D01*
G02Y400148I1131J987D01*
G01Y400149D01*
X417745D01*
G03X417793Y400279I-152J130D01*
G01Y400543D01*
G03X417745Y400673I-200J0D01*
G01X417744Y400674D01*
G02X417374Y401661I1131J987D01*
G37*
G36*
G01X381591Y400479D02*
G02Y403483I0J1502D01*
G02X382578Y403113I0J-1501D01*
G01X382579D01*
Y403112D01*
G03X382709Y403064I130J152D01*
G01X382973D01*
G03X383103Y403112I0J200D01*
G01X383104Y403113D01*
G02X384091Y403483I987J-1131D01*
G02Y400479I0J-1502D01*
G02X383104Y400849I0J1501D01*
G01X383103D01*
Y400850D01*
G03X382973Y400898I-130J-152D01*
G01X382709D01*
G03X382579Y400850I0J-200D01*
G01X382578Y400849D01*
G02X381591Y400479I-987J1131D01*
G37*
G36*
G01X596686Y403123D02*
X596804Y403094D01*
G03X596943Y403111I47J195D01*
G02X597777Y403316I835J-1598D01*
G02X598611Y403111I-1J-1803D01*
G03X598750Y403094I92J178D01*
G01X598868Y403123D01*
G03X598984Y403202I-47J194D01*
G02X600273Y403870I1289J-910D01*
G02Y400712I0J-1579D01*
G02X600039Y400730I4J1579D01*
G01X599995Y400737D01*
X599912Y400713D01*
X599649Y400486D01*
G03X599580Y400334I131J-151D01*
G01Y399292D01*
G03X599649Y399140I200J-1D01*
G01X599912Y398913D01*
X599995Y398889D01*
X600039Y398896D01*
G02X600273Y398914I238J-1561D01*
G02Y395756I0J-1579D01*
G02X598984Y396424I0J1578D01*
G03X598868Y396503I-163J-115D01*
G01X598750Y396532D01*
G03X598611Y396515I-47J-195D01*
G02X597777Y396310I-835J1598D01*
G02X596943Y396515I1J1803D01*
G03X596804Y396532I-92J-178D01*
G01X596686Y396503D01*
G03X596570Y396424I47J-194D01*
G02X595281Y395756I-1289J910D01*
G02Y398914I0J1579D01*
G02X595515Y398896I-4J-1579D01*
G01X595559Y398889D01*
X595642Y398913D01*
X595905Y399140D01*
G03X595974Y399292I-131J151D01*
G01Y400334D01*
G03X595905Y400486I-200J1D01*
G01X595642Y400713D01*
X595559Y400737D01*
X595515Y400730D01*
G02X595281Y400712I-238J1561D01*
G02Y403870I0J1579D01*
G02X596570Y403202I0J-1578D01*
G03X596686Y403123I163J115D01*
G37*
G36*
G01X1053772D02*
X1053890Y403094D01*
G03X1054029Y403111I47J195D01*
G02X1054863Y403316I835J-1598D01*
G02X1055697Y403111I-1J-1803D01*
G03X1055836Y403094I92J178D01*
G01X1055954Y403123D01*
G03X1056070Y403202I-47J194D01*
G02X1057359Y403870I1289J-910D01*
G02Y400712I0J-1579D01*
G02X1057125Y400730I4J1579D01*
G01X1057081Y400737D01*
X1056998Y400713D01*
X1056735Y400486D01*
G03X1056666Y400334I131J-151D01*
G01Y399292D01*
G03X1056735Y399140I200J-1D01*
G01X1056998Y398913D01*
X1057081Y398889D01*
X1057125Y398896D01*
G02X1057359Y398914I238J-1561D01*
G02Y395756I0J-1579D01*
G02X1056070Y396424I0J1578D01*
G03X1055954Y396503I-163J-115D01*
G01X1055836Y396532D01*
G03X1055697Y396515I-47J-195D01*
G02X1054863Y396310I-835J1598D01*
G02X1054029Y396515I1J1803D01*
G03X1053890Y396532I-92J-178D01*
G01X1053772Y396503D01*
G03X1053656Y396424I47J-194D01*
G02X1052367Y395756I-1289J910D01*
G02Y398914I0J1579D01*
G02X1052601Y398896I-4J-1579D01*
G01X1052645Y398889D01*
X1052728Y398913D01*
X1052991Y399140D01*
G03X1053060Y399292I-131J151D01*
G01Y400334D01*
G03X1052991Y400486I-200J1D01*
G01X1052728Y400713D01*
X1052645Y400737D01*
X1052601Y400730D01*
G02X1052367Y400712I-238J1561D01*
G02Y403870I0J1579D01*
G02X1053656Y403202I0J-1578D01*
G03X1053772Y403123I163J115D01*
G37*
G36*
G01X399518Y401140D02*
G02Y404144I0J1502D01*
G02X400505Y403774I0J-1501D01*
G01X400506D01*
Y403773D01*
G03X400636Y403725I130J152D01*
G01X400900D01*
G03X401030Y403773I0J200D01*
G01X401031Y403774D01*
G02X402018Y404144I987J-1131D01*
G02Y401140I0J-1502D01*
G02X401031Y401510I0J1501D01*
G01X401030D01*
Y401511D01*
G03X400900Y401559I-130J-152D01*
G01X400636D01*
G03X400506Y401511I0J-200D01*
G01X400505Y401510D01*
G02X399518Y401140I-987J1131D01*
G37*
G36*
G01X900245Y403492D02*
G02X903249I1502J0D01*
G02X902879Y402505I-1501J0D01*
G01Y402504D01*
X902878D01*
G03X902830Y402374I152J-130D01*
G01Y402110D01*
G03X902878Y401980I200J0D01*
G01X902879Y401979D01*
G02Y400005I-1131J-987D01*
G01Y400004D01*
X902878D01*
G03X902830Y399874I152J-130D01*
G01Y399610D01*
G03X902878Y399480I200J0D01*
G01X902879Y399479D01*
G02X903249Y398492I-1131J-987D01*
G02X900245I-1502J0D01*
G02X900615Y399479I1501J0D01*
G01Y399480D01*
X900616D01*
G03X900664Y399610I-152J130D01*
G01Y399874D01*
G03X900616Y400004I-200J0D01*
G01X900615Y400005D01*
G02Y401979I1131J987D01*
G01Y401980D01*
X900616D01*
G03X900664Y402110I-152J130D01*
G01Y402374D01*
G03X900616Y402504I-200J0D01*
G01X900615Y402505D01*
G02X900245Y403492I1131J987D01*
G37*
G36*
G01X912821Y403551D02*
G02X915825I1502J0D01*
G02X915455Y402564I-1501J0D01*
G01Y402563D01*
X915454D01*
G03X915406Y402433I152J-130D01*
G01Y402169D01*
G03X915454Y402039I200J0D01*
G01X915455Y402038D01*
G02Y400064I-1131J-987D01*
G01Y400063D01*
X915454D01*
G03X915406Y399933I152J-130D01*
G01Y399669D01*
G03X915454Y399539I200J0D01*
G01X915455Y399538D01*
G02X915825Y398551I-1131J-987D01*
G02X912821I-1502J0D01*
G02X913191Y399538I1501J0D01*
G01Y399539D01*
X913192D01*
G03X913240Y399669I-152J130D01*
G01Y399933D01*
G03X913192Y400063I-200J0D01*
G01X913191Y400064D01*
G02Y402038I1131J987D01*
G01Y402039D01*
X913192D01*
G03X913240Y402169I-152J130D01*
G01Y402433D01*
G03X913192Y402563I-200J0D01*
G01X913191Y402564D01*
G02X912821Y403551I1131J987D01*
G37*
G36*
G01X895326Y403091D02*
X895032D01*
G03X894885Y403026I1J-200D01*
G02X893779Y402541I-1106J1019D01*
G02Y405545I0J1502D01*
G02X894885Y405060I0J-1504D01*
G03X895032Y404995I148J135D01*
G01X895326D01*
G03X895473Y405060I-1J200D01*
G02X896579Y405545I1106J-1019D01*
G02Y402541I0J-1502D01*
G02X895473Y403026I0J1504D01*
G03X895326Y403091I-148J-135D01*
G37*
G36*
G01X885764Y405158D02*
G02X887266Y406660I1502J0D01*
G02X888121Y406393I0J-1502D01*
G01X888155Y406370D01*
X888236Y406353D01*
X888603Y406433D01*
X888670Y406481D01*
X888691Y406516D01*
G02X889979Y407245I1288J-773D01*
G02Y404241I0J-1502D01*
G02X889124Y404508I0J1502D01*
G01X889090Y404531D01*
X889009Y404548D01*
X888642Y404468D01*
X888575Y404420D01*
X888554Y404385D01*
G02X888398Y404172I-1285J777D01*
G03X888397Y404170I173J-88D01*
G03X888349Y404040I152J-130D01*
G01Y403776D01*
G03X888397Y403646I200J0D01*
G01X888398Y403645D01*
G02Y401671I-1131J-987D01*
G01Y401670D01*
X888397D01*
G03X888349Y401540I152J-130D01*
G01Y401276D01*
G03X888397Y401146I200J0D01*
G01X888398Y401145D01*
G02X888768Y400158I-1131J-987D01*
G02X885764I-1502J0D01*
G02X886134Y401145I1501J0D01*
G01Y401146D01*
X886135D01*
G03X886183Y401276I-152J130D01*
G01Y401540D01*
G03X886135Y401670I-200J0D01*
G01X886134Y401671D01*
G02Y403645I1131J987D01*
G01Y403646D01*
X886135D01*
G03X886183Y403776I-152J130D01*
G01Y404040D01*
G03X886135Y404170I-200J0D01*
G01X886134Y404171D01*
G02X885764Y405158I1131J987D01*
G37*
G36*
G01X970219Y407762D02*
G02X971721Y406260I1502J0D01*
G02X971553Y406270I5J1502D01*
G01X971551D01*
X971505Y406275D01*
X971420Y406244D01*
X971166Y405985D01*
G03X971111Y405818I143J-140D01*
G02X971125Y405614I-1488J-205D01*
G02X969623Y407116I-1502J0D01*
G02X969791Y407106I-5J-1502D01*
G01X969793D01*
X969839Y407101D01*
X969924Y407132D01*
X970178Y407391D01*
G03X970233Y407558I-143J140D01*
G02X970219Y407762I1488J205D01*
G37*
G36*
G01X429890Y409056D02*
X430184D01*
G03X430331Y409121I-1J200D01*
G02X432543I1106J-1017D01*
G03X432690Y409056I148J135D01*
G01X432984D01*
G03X433131Y409121I-1J200D01*
G02X434237Y409606I1106J-1019D01*
G02Y406602I0J-1502D01*
G02X433131Y407087I0J1504D01*
G03X432984Y407152I-148J-135D01*
G01X432690D01*
G03X432543Y407087I1J-200D01*
G02X430331I-1106J1017D01*
G03X430184Y407152I-148J-135D01*
G01X429890D01*
G03X429743Y407087I1J-200D01*
G02X428637Y406602I-1106J1019D01*
G02Y409606I0J1502D01*
G02X429743Y409121I0J-1504D01*
G03X429890Y409056I148J135D01*
G37*
G36*
G01X412755Y409372D02*
X412756Y409371D01*
G03X412886Y409323I130J152D01*
G01X413150D01*
G03X413280Y409371I0J200D01*
G01X413281Y409372D01*
G02X414268Y409742I987J-1131D01*
G02Y406738I0J-1502D01*
G02X413281Y407108I0J1501D01*
G01X413280D01*
Y407109D01*
G03X413150Y407157I-130J-152D01*
G01X412886D01*
G03X412756Y407109I0J-200D01*
G01X412755Y407108D01*
G02X410781I-987J1131D01*
G01X410780D01*
Y407109D01*
G03X410650Y407157I-130J-152D01*
G01X410386D01*
G03X410256Y407109I0J-200D01*
G01X410255Y407108D01*
G02X409268Y406738I-987J1131D01*
G02Y409742I0J1502D01*
G02X410255Y409372I0J-1501D01*
G01X410256D01*
Y409371D01*
G03X410386Y409323I130J152D01*
G01X410650D01*
G03X410780Y409371I0J200D01*
G01X410781Y409372D01*
G02X412755I987J-1131D01*
G37*
G36*
G01X605779Y410376D02*
G02X606613Y410172I1J-1802D01*
G03X606752Y410155I92J178D01*
G01X606870Y410184D01*
G03X606986Y410263I-47J194D01*
G02X608275Y410930I1289J-912D01*
G02Y407774I0J-1578D01*
G02X608041Y407791I-3J1578D01*
G01X607997Y407798D01*
X607914Y407774D01*
X607651Y407547D01*
G03X607582Y407395I131J-151D01*
G01Y406353D01*
G03X607651Y406201I200J-1D01*
G01X607914Y405974D01*
X607997Y405950D01*
X608041Y405957D01*
G02X608275Y405974I231J-1561D01*
G02Y402818I0J-1578D01*
G02X606986Y403485I0J1579D01*
G03X606870Y403564I-163J-115D01*
G01X606752Y403593D01*
G03X606613Y403576I-47J-195D01*
G02X605779Y403372I-833J1598D01*
G02X604945Y403576I-1J1802D01*
G03X604806Y403593I-92J-178D01*
G01X604688Y403564D01*
G03X604572Y403485I47J-194D01*
G02X603283Y402818I-1289J912D01*
G02Y405974I0J1578D01*
G02X603517Y405957I3J-1578D01*
G01X603561Y405950D01*
X603644Y405974D01*
X603907Y406201D01*
G03X603976Y406353I-131J151D01*
G01Y407395D01*
G03X603907Y407547I-200J1D01*
G01X603644Y407774D01*
X603561Y407798D01*
X603517Y407791D01*
G02X603283Y407774I-231J1561D01*
G02Y410930I0J1578D01*
G02X604572Y410263I0J-1579D01*
G03X604688Y410184I163J115D01*
G01X604806Y410155D01*
G03X604945Y410172I47J195D01*
G02X605779Y410376I833J-1598D01*
G37*
G36*
G01X1062865D02*
G02X1063699Y410172I1J-1802D01*
G03X1063838Y410155I92J178D01*
G01X1063956Y410184D01*
G03X1064072Y410263I-47J194D01*
G02X1065361Y410930I1289J-912D01*
G02Y407774I0J-1578D01*
G02X1065127Y407791I-3J1578D01*
G01X1065083Y407798D01*
X1065000Y407774D01*
X1064737Y407547D01*
G03X1064668Y407395I131J-151D01*
G01Y406353D01*
G03X1064737Y406201I200J-1D01*
G01X1065000Y405974D01*
X1065083Y405950D01*
X1065127Y405957D01*
G02X1065361Y405974I231J-1561D01*
G02Y402818I0J-1578D01*
G02X1064072Y403485I0J1579D01*
G03X1063956Y403564I-163J-115D01*
G01X1063838Y403593D01*
G03X1063699Y403576I-47J-195D01*
G02X1062865Y403372I-833J1598D01*
G02X1062031Y403576I-1J1802D01*
G03X1061892Y403593I-92J-178D01*
G01X1061774Y403564D01*
G03X1061658Y403485I47J-194D01*
G02X1060369Y402818I-1289J912D01*
G02Y405974I0J1578D01*
G02X1060603Y405957I3J-1578D01*
G01X1060647Y405950D01*
X1060730Y405974D01*
X1060993Y406201D01*
G03X1061062Y406353I-131J151D01*
G01Y407395D01*
G03X1060993Y407547I-200J1D01*
G01X1060730Y407774D01*
X1060647Y407798D01*
X1060603Y407791D01*
G02X1060369Y407774I-231J1561D01*
G02Y410930I0J1578D01*
G02X1061658Y410263I0J-1579D01*
G03X1061774Y410184I163J115D01*
G01X1061892Y410155D01*
G03X1062031Y410172I47J195D01*
G02X1062865Y410376I833J-1598D01*
G37*
G36*
G01X395421Y408357D02*
Y408651D01*
G03X395356Y408798I-200J-1D01*
G02X394871Y409904I1019J1106D01*
G02X397875I1502J0D01*
G02X397390Y408798I-1504J0D01*
G03X397325Y408651I135J-148D01*
G01Y408357D01*
G03X397390Y408210I200J1D01*
G02X397875Y407104I-1019J-1106D01*
G02X394871I-1502J0D01*
G02X395356Y408210I1504J0D01*
G03X395421Y408357I-135J148D01*
G37*
G36*
G01X878690Y410117D02*
G02Y413121I0J1502D01*
G02X879677Y412751I0J-1501D01*
G01X879678D01*
Y412750D01*
G03X879808Y412702I130J152D01*
G01X880072D01*
G03X880202Y412750I0J200D01*
G01X880203Y412751D01*
G02X881190Y413121I987J-1131D01*
G02Y410117I0J-1502D01*
G02X880203Y410487I0J1501D01*
G01X880202D01*
Y410488D01*
G03X880072Y410536I-130J-152D01*
G01X879808D01*
G03X879678Y410488I0J-200D01*
G01X879677Y410487D01*
G02X878690Y410117I-987J1131D01*
G37*
G36*
G01X384432Y414743D02*
X384433Y414742D01*
G03X384563Y414694I130J152D01*
G01X384827D01*
G03X384957Y414742I0J200D01*
G01X384958Y414743D01*
G02X385945Y415113I987J-1131D01*
G02Y412109I0J-1502D01*
G02X384958Y412479I0J1501D01*
G01X384957D01*
Y412480D01*
G03X384827Y412528I-130J-152D01*
G01X384563D01*
G03X384433Y412480I0J-200D01*
G01X384432Y412479D01*
G02X382458I-987J1131D01*
G01X382457D01*
Y412480D01*
G03X382327Y412528I-130J-152D01*
G01X382063D01*
G03X381933Y412480I0J-200D01*
G01X381932Y412479D01*
G02X379958I-987J1131D01*
G01X379957D01*
Y412480D01*
G03X379827Y412528I-130J-152D01*
G01X379563D01*
G03X379433Y412480I0J-200D01*
G01X379432Y412479D01*
G02X378445Y412109I-987J1131D01*
G02Y415113I0J1502D01*
G02X379432Y414743I0J-1501D01*
G01X379433D01*
Y414742D01*
G03X379563Y414694I130J152D01*
G01X379827D01*
G03X379957Y414742I0J200D01*
G01X379958Y414743D01*
G02X381932I987J-1131D01*
G01X381933D01*
Y414742D01*
G03X382063Y414694I130J152D01*
G01X382327D01*
G03X382457Y414742I0J200D01*
G01X382458Y414743D01*
G02X384432I987J-1131D01*
G37*
G36*
G01X400180D02*
X400181Y414742D01*
G03X400311Y414694I130J152D01*
G01X400575D01*
G03X400705Y414742I0J200D01*
G01X400706Y414743D01*
G02X401693Y415113I987J-1131D01*
G02Y412109I0J-1502D01*
G02X400706Y412479I0J1501D01*
G01X400705D01*
Y412480D01*
G03X400575Y412528I-130J-152D01*
G01X400311D01*
G03X400181Y412480I0J-200D01*
G01X400180Y412479D01*
G02X398206I-987J1131D01*
G01X398205D01*
Y412480D01*
G03X398075Y412528I-130J-152D01*
G01X397811D01*
G03X397681Y412480I0J-200D01*
G01X397680Y412479D01*
G02X396693Y412109I-987J1131D01*
G02X395587Y412594I0J1504D01*
G03X395440Y412659I-148J-135D01*
G01X395146D01*
G03X394999Y412594I1J-200D01*
G02X393893Y412109I-1106J1019D01*
G02Y415113I0J1502D01*
G02X394999Y414628I0J-1504D01*
G03X395146Y414563I148J135D01*
G01X395440D01*
G03X395587Y414628I-1J200D01*
G02X396693Y415113I1106J-1019D01*
G02X397680Y414743I0J-1501D01*
G01X397681D01*
Y414742D01*
G03X397811Y414694I130J152D01*
G01X398075D01*
G03X398205Y414742I0J200D01*
G01X398206Y414743D01*
G02X400180I987J-1131D01*
G37*
G36*
G01X887770Y413788D02*
G02Y416792I0J1502D01*
G02X888757Y416422I0J-1501D01*
G01X888758D01*
Y416421D01*
G03X888888Y416373I130J152D01*
G01X889152D01*
G03X889282Y416421I0J200D01*
G01X889283Y416422D01*
G02X890270Y416792I987J-1131D01*
G02Y413788I0J-1502D01*
G02X889283Y414158I0J1501D01*
G01X889282D01*
Y414159D01*
G03X889152Y414207I-130J-152D01*
G01X888888D01*
G03X888758Y414159I0J-200D01*
G01X888757Y414158D01*
G02X887770Y413788I-987J1131D01*
G37*
G36*
G01X876917Y413820D02*
G02Y416824I0J1502D01*
G02X877904Y416454I0J-1501D01*
G01X877905D01*
Y416453D01*
G03X878035Y416405I130J152D01*
G01X878299D01*
G03X878429Y416453I0J200D01*
G01X878430Y416454D01*
G02X879417Y416824I987J-1131D01*
G02Y413820I0J-1502D01*
G02X878430Y414190I0J1501D01*
G01X878429D01*
Y414191D01*
G03X878299Y414239I-130J-152D01*
G01X878035D01*
G03X877905Y414191I0J-200D01*
G01X877904Y414190D01*
G02X876917Y413820I-987J1131D01*
G37*
G36*
G01X594286Y417297D02*
X594404Y417268D01*
G03X594543Y417285I47J195D01*
G02X595377Y417490I835J-1598D01*
G02X596211Y417285I-1J-1803D01*
G03X596350Y417268I92J178D01*
G01X596468Y417297D01*
G03X596584Y417376I-47J194D01*
G02X597873Y418044I1289J-910D01*
G02Y414886I0J-1579D01*
G02X597639Y414904I4J1579D01*
G01X597595Y414911D01*
X597512Y414887D01*
X597249Y414660D01*
G03X597180Y414508I131J-151D01*
G01Y413466D01*
G03X597249Y413314I200J-1D01*
G01X597512Y413087D01*
X597595Y413063D01*
X597639Y413070D01*
G02X597873Y413088I238J-1561D01*
G02Y409930I0J-1579D01*
G02X596584Y410598I0J1578D01*
G03X596468Y410677I-163J-115D01*
G01X596350Y410706D01*
G03X596211Y410689I-47J-195D01*
G02X595377Y410484I-835J1598D01*
G02X594543Y410689I1J1803D01*
G03X594404Y410706I-92J-178D01*
G01X594286Y410677D01*
G03X594170Y410598I47J-194D01*
G02X592881Y409930I-1289J910D01*
G02Y413088I0J1579D01*
G02X593115Y413070I-4J-1579D01*
G01X593159Y413063D01*
X593242Y413087D01*
X593505Y413314D01*
G03X593574Y413466I-131J151D01*
G01Y414508D01*
G03X593505Y414660I-200J1D01*
G01X593242Y414887D01*
X593159Y414911D01*
X593115Y414904D01*
G02X592881Y414886I-238J1561D01*
G02Y418044I0J1579D01*
G02X594170Y417376I0J-1578D01*
G03X594286Y417297I163J115D01*
G37*
G36*
G01X1051372D02*
X1051490Y417268D01*
G03X1051629Y417285I47J195D01*
G02X1052463Y417490I835J-1598D01*
G02X1053297Y417285I-1J-1803D01*
G03X1053436Y417268I92J178D01*
G01X1053554Y417297D01*
G03X1053670Y417376I-47J194D01*
G02X1054959Y418044I1289J-910D01*
G02Y414886I0J-1579D01*
G02X1054725Y414904I4J1579D01*
G01X1054681Y414911D01*
X1054598Y414887D01*
X1054335Y414660D01*
G03X1054266Y414508I131J-151D01*
G01Y413466D01*
G03X1054335Y413314I200J-1D01*
G01X1054598Y413087D01*
X1054681Y413063D01*
X1054725Y413070D01*
G02X1054959Y413088I238J-1561D01*
G02Y409930I0J-1579D01*
G02X1053670Y410598I0J1578D01*
G03X1053554Y410677I-163J-115D01*
G01X1053436Y410706D01*
G03X1053297Y410689I-47J-195D01*
G02X1052463Y410484I-835J1598D01*
G02X1051629Y410689I1J1803D01*
G03X1051490Y410706I-92J-178D01*
G01X1051372Y410677D01*
G03X1051256Y410598I47J-194D01*
G02X1049967Y409930I-1289J910D01*
G02Y413088I0J1579D01*
G02X1050201Y413070I-4J-1579D01*
G01X1050245Y413063D01*
X1050328Y413087D01*
X1050591Y413314D01*
G03X1050660Y413466I-131J151D01*
G01Y414508D01*
G03X1050591Y414660I-200J1D01*
G01X1050328Y414887D01*
X1050245Y414911D01*
X1050201Y414904D01*
G02X1049967Y414886I-238J1561D01*
G02Y418044I0J1579D01*
G02X1051256Y417376I0J-1578D01*
G03X1051372Y417297I163J115D01*
G37*
G36*
G01X900667Y418002D02*
G02X903671I1502J0D01*
G02X903301Y417015I-1501J0D01*
G01Y417014D01*
X903300D01*
G03X903252Y416884I152J-130D01*
G01Y416620D01*
G03X903300Y416490I200J0D01*
G01X903301Y416489D01*
G02Y414515I-1131J-987D01*
G01Y414514D01*
X903300D01*
G03X903252Y414384I152J-130D01*
G01Y414120D01*
G03X903300Y413990I200J0D01*
G01X903301Y413989D01*
G02X903671Y413002I-1131J-987D01*
G02X900667I-1502J0D01*
G02X901037Y413989I1501J0D01*
G01Y413990D01*
X901038D01*
G03X901086Y414120I-152J130D01*
G01Y414384D01*
G03X901038Y414514I-200J0D01*
G01X901037Y414515D01*
G02Y416489I1131J987D01*
G01Y416490D01*
X901038D01*
G03X901086Y416620I-152J130D01*
G01Y416884D01*
G03X901038Y417014I-200J0D01*
G01X901037Y417015D01*
G02X900667Y418002I1131J987D01*
G37*
G36*
G01X912700D02*
G02X915704I1502J0D01*
G02X915334Y417015I-1501J0D01*
G01Y417014D01*
X915333D01*
G03X915285Y416884I152J-130D01*
G01Y416620D01*
G03X915333Y416490I200J0D01*
G01X915334Y416489D01*
G02Y414515I-1131J-987D01*
G01Y414514D01*
X915333D01*
G03X915285Y414384I152J-130D01*
G01Y414120D01*
G03X915333Y413990I200J0D01*
G01X915334Y413989D01*
G02X915704Y413002I-1131J-987D01*
G02X912700I-1502J0D01*
G02X913070Y413989I1501J0D01*
G01Y413990D01*
X913071D01*
G03X913119Y414120I-152J130D01*
G01Y414384D01*
G03X913071Y414514I-200J0D01*
G01X913070Y414515D01*
G02Y416489I1131J987D01*
G01Y416490D01*
X913071D01*
G03X913119Y416620I-152J130D01*
G01Y416884D01*
G03X913071Y417014I-200J0D01*
G01X913070Y417015D01*
G02X912700Y418002I1131J987D01*
G37*
G36*
G01X894844Y417481D02*
G02Y420485I0J1502D01*
G02X895831Y420115I0J-1501D01*
G01X895832D01*
Y420114D01*
G03X895962Y420066I130J152D01*
G01X896226D01*
G03X896356Y420114I0J200D01*
G01X896357Y420115D01*
G02X897344Y420485I987J-1131D01*
G02Y417481I0J-1502D01*
G02X896357Y417851I0J1501D01*
G01X896356D01*
Y417852D01*
G03X896226Y417900I-130J-152D01*
G01X895962D01*
G03X895832Y417852I0J-200D01*
G01X895831Y417851D01*
G02X894844Y417481I-987J1131D01*
G37*
G36*
G01X429607Y421327D02*
X429901D01*
G03X430048Y421392I-1J200D01*
G02X432260I1106J-1017D01*
G03X432407Y421327I148J135D01*
G01X432701D01*
G03X432848Y421392I-1J200D01*
G02X433954Y421877I1106J-1019D01*
G02Y418873I0J-1502D01*
G02X432848Y419358I0J1504D01*
G03X432701Y419423I-148J-135D01*
G01X432407D01*
G03X432260Y419358I1J-200D01*
G02X430048I-1106J1017D01*
G03X429901Y419423I-148J-135D01*
G01X429607D01*
G03X429460Y419358I1J-200D01*
G02X428354Y418873I-1106J1019D01*
G02Y421877I0J1502D01*
G02X429460Y421392I0J-1504D01*
G03X429607Y421327I148J135D01*
G37*
G36*
G01X412873Y421525D02*
X412874Y421524D01*
G03X413004Y421476I130J152D01*
G01X413268D01*
G03X413398Y421524I0J200D01*
G01X413399Y421525D01*
G02X414386Y421895I987J-1131D01*
G02Y418891I0J-1502D01*
G02X413399Y419261I0J1501D01*
G01X413398D01*
Y419262D01*
G03X413268Y419310I-130J-152D01*
G01X413004D01*
G03X412874Y419262I0J-200D01*
G01X412873Y419261D01*
G02X410899I-987J1131D01*
G01X410898D01*
Y419262D01*
G03X410768Y419310I-130J-152D01*
G01X410504D01*
G03X410374Y419262I0J-200D01*
G01X410373Y419261D01*
G02X409386Y418891I-987J1131D01*
G02Y421895I0J1502D01*
G02X410373Y421525I0J-1501D01*
G01X410374D01*
Y421524D01*
G03X410504Y421476I130J152D01*
G01X410768D01*
G03X410898Y421524I0J200D01*
G01X410899Y421525D01*
G02X412873I987J-1131D01*
G37*
G36*
G01X783084Y421000D02*
G02X786088I1502J0D01*
G02X785718Y420013I-1501J0D01*
G01Y420012D01*
X785717D01*
G03X785669Y419882I152J-130D01*
G01Y419618D01*
G03X785717Y419488I200J0D01*
G01X785718Y419487D01*
G02Y417513I-1131J-987D01*
G01Y417512D01*
X785717D01*
G03X785669Y417382I152J-130D01*
G01Y417118D01*
G03X785717Y416988I200J0D01*
G01X785718Y416987D01*
G02Y415013I-1131J-987D01*
G01Y415012D01*
X785717D01*
G03X785669Y414882I152J-130D01*
G01Y414618D01*
G03X785717Y414488I200J0D01*
G01X785718Y414487D01*
G02X786088Y413500I-1131J-987D01*
G02X783084I-1502J0D01*
G02X783454Y414487I1501J0D01*
G01Y414488D01*
X783455D01*
G03X783503Y414618I-152J130D01*
G01Y414882D01*
G03X783455Y415012I-200J0D01*
G01X783454Y415013D01*
G02Y416987I1131J987D01*
G01Y416988D01*
X783455D01*
G03X783503Y417118I-152J130D01*
G01Y417382D01*
G03X783455Y417512I-200J0D01*
G01X783454Y417513D01*
G02Y419487I1131J987D01*
G01Y419488D01*
X783455D01*
G03X783503Y419618I-152J130D01*
G01Y419882D01*
G03X783455Y420012I-200J0D01*
G01X783454Y420013D01*
G02X783084Y421000I1131J987D01*
G37*
G36*
G01X890747Y421698D02*
Y421992D01*
G03X890682Y422139I-200J-1D01*
G02X890197Y423245I1019J1106D01*
G02X893201I1502J0D01*
G02X892716Y422139I-1504J0D01*
G03X892651Y421992I135J-148D01*
G01Y421698D01*
G03X892716Y421551I200J1D01*
G02X893201Y420445I-1019J-1106D01*
G02X890197I-1502J0D01*
G02X890682Y421551I1504J0D01*
G03X890747Y421698I-135J148D01*
G37*
G36*
G01X604688Y424357D02*
X604806Y424328D01*
G03X604945Y424345I47J195D01*
G02X605779Y424550I835J-1598D01*
G02X606613Y424345I-1J-1803D01*
G03X606752Y424328I92J178D01*
G01X606870Y424357D01*
G03X606986Y424436I-47J194D01*
G02X608275Y425104I1289J-910D01*
G02Y421946I0J-1579D01*
G02X608041Y421964I4J1579D01*
G01X607997Y421971D01*
X607914Y421947D01*
X607651Y421720D01*
G03X607582Y421568I131J-151D01*
G01Y420526D01*
G03X607651Y420374I200J-1D01*
G01X607914Y420147D01*
X607997Y420123D01*
X608041Y420130D01*
G02X608275Y420148I238J-1561D01*
G02Y416990I0J-1579D01*
G02X606986Y417658I0J1578D01*
G03X606870Y417737I-163J-115D01*
G01X606752Y417766D01*
G03X606613Y417749I-47J-195D01*
G02X605779Y417544I-835J1598D01*
G02X604945Y417749I1J1803D01*
G03X604806Y417766I-92J-178D01*
G01X604688Y417737D01*
G03X604572Y417658I47J-194D01*
G02X603283Y416990I-1289J910D01*
G02Y420148I0J1579D01*
G02X603517Y420130I-4J-1579D01*
G01X603561Y420123D01*
X603644Y420147D01*
X603907Y420374D01*
G03X603976Y420526I-131J151D01*
G01Y421568D01*
G03X603907Y421720I-200J1D01*
G01X603644Y421947D01*
X603561Y421971D01*
X603517Y421964D01*
G02X603283Y421946I-238J1561D01*
G02Y425104I0J1579D01*
G02X604572Y424436I0J-1578D01*
G03X604688Y424357I163J115D01*
G37*
G36*
G01X1061774D02*
X1061892Y424328D01*
G03X1062031Y424345I47J195D01*
G02X1062865Y424550I835J-1598D01*
G02X1063699Y424345I-1J-1803D01*
G03X1063838Y424328I92J178D01*
G01X1063956Y424357D01*
G03X1064072Y424436I-47J194D01*
G02X1065361Y425104I1289J-910D01*
G02Y421946I0J-1579D01*
G02X1065127Y421964I4J1579D01*
G01X1065083Y421971D01*
X1065000Y421947D01*
X1064737Y421720D01*
G03X1064668Y421568I131J-151D01*
G01Y420526D01*
G03X1064737Y420374I200J-1D01*
G01X1065000Y420147D01*
X1065083Y420123D01*
X1065127Y420130D01*
G02X1065361Y420148I238J-1561D01*
G02Y416990I0J-1579D01*
G02X1064072Y417658I0J1578D01*
G03X1063956Y417737I-163J-115D01*
G01X1063838Y417766D01*
G03X1063699Y417749I-47J-195D01*
G02X1062865Y417544I-835J1598D01*
G02X1062031Y417749I1J1803D01*
G03X1061892Y417766I-92J-178D01*
G01X1061774Y417737D01*
G03X1061658Y417658I47J-194D01*
G02X1060369Y416990I-1289J910D01*
G02Y420148I0J1579D01*
G02X1060603Y420130I-4J-1579D01*
G01X1060647Y420123D01*
X1060730Y420147D01*
X1060993Y420374D01*
G03X1061062Y420526I-131J151D01*
G01Y421568D01*
G03X1060993Y421720I-200J1D01*
G01X1060730Y421947D01*
X1060647Y421971D01*
X1060603Y421964D01*
G02X1060369Y421946I-238J1561D01*
G02Y425104I0J1579D01*
G02X1061658Y424436I0J-1578D01*
G03X1061774Y424357I163J115D01*
G37*
G36*
G01X400120Y425076D02*
X400121Y425075D01*
G03X400251Y425027I130J152D01*
G01X400515D01*
G03X400645Y425075I0J200D01*
G01X400646Y425076D01*
G02X401633Y425446I987J-1131D01*
G02Y422442I0J-1502D01*
G02X400646Y422812I0J1501D01*
G01X400645D01*
Y422813D01*
G03X400515Y422861I-130J-152D01*
G01X400251D01*
G03X400121Y422813I0J-200D01*
G01X400120Y422812D01*
G02X398146I-987J1131D01*
G01X398145D01*
Y422813D01*
G03X398015Y422861I-130J-152D01*
G01X397751D01*
G03X397621Y422813I0J-200D01*
G01X397620Y422812D01*
G02X396633Y422442I-987J1131D01*
G02X395527Y422927I0J1504D01*
G03X395380Y422992I-148J-135D01*
G01X395086D01*
G03X394939Y422927I1J-200D01*
G02X393833Y422442I-1106J1019D01*
G02Y425446I0J1502D01*
G02X394939Y424961I0J-1504D01*
G03X395086Y424896I148J135D01*
G01X395380D01*
G03X395527Y424961I-1J200D01*
G02X396633Y425446I1106J-1019D01*
G02X397620Y425076I0J-1501D01*
G01X397621D01*
Y425075D01*
G03X397751Y425027I130J152D01*
G01X398015D01*
G03X398145Y425075I0J200D01*
G01X398146Y425076D01*
G02X400120I987J-1131D01*
G37*
G36*
G01X384197Y425199D02*
X384198Y425198D01*
G03X384328Y425150I130J152D01*
G01X384592D01*
G03X384722Y425198I0J200D01*
G01X384723Y425199D01*
G02X385710Y425569I987J-1131D01*
G02Y422565I0J-1502D01*
G02X384723Y422935I0J1501D01*
G01X384722D01*
Y422936D01*
G03X384592Y422984I-130J-152D01*
G01X384328D01*
G03X384198Y422936I0J-200D01*
G01X384197Y422935D01*
G02X382223I-987J1131D01*
G01X382222D01*
Y422936D01*
G03X382092Y422984I-130J-152D01*
G01X381828D01*
G03X381698Y422936I0J-200D01*
G01X381697Y422935D01*
G02X379723I-987J1131D01*
G01X379722D01*
Y422936D01*
G03X379592Y422984I-130J-152D01*
G01X379328D01*
G03X379198Y422936I0J-200D01*
G01X379197Y422935D01*
G02X378210Y422565I-987J1131D01*
G02Y425569I0J1502D01*
G02X379197Y425199I0J-1501D01*
G01X379198D01*
Y425198D01*
G03X379328Y425150I130J152D01*
G01X379592D01*
G03X379722Y425198I0J200D01*
G01X379723Y425199D01*
G02X381697I987J-1131D01*
G01X381698D01*
Y425198D01*
G03X381828Y425150I130J152D01*
G01X382092D01*
G03X382222Y425198I0J200D01*
G01X382223Y425199D01*
G02X384197I987J-1131D01*
G37*
G36*
G01X923216Y425397D02*
X923510D01*
G03X923657Y425462I-1J200D01*
G02X925869I1106J-1017D01*
G03X926016Y425397I148J135D01*
G01X926310D01*
G03X926457Y425462I-1J200D01*
G02X927563Y425947I1106J-1019D01*
G02Y422943I0J-1502D01*
G02X926457Y423428I0J1504D01*
G03X926310Y423493I-148J-135D01*
G01X926016D01*
G03X925869Y423428I1J-200D01*
G02X923657I-1106J1017D01*
G03X923510Y423493I-148J-135D01*
G01X923216D01*
G03X923069Y423428I1J-200D01*
G02X921963Y422943I-1106J1019D01*
G02Y425947I0J1502D01*
G02X923069Y425462I0J-1504D01*
G03X923216Y425397I148J135D01*
G37*
G36*
G01X906081Y425713D02*
X906082Y425712D01*
G03X906212Y425664I130J152D01*
G01X906476D01*
G03X906606Y425712I0J200D01*
G01X906607Y425713D01*
G02X907594Y426083I987J-1131D01*
G02Y423079I0J-1502D01*
G02X906607Y423449I0J1501D01*
G01X906606D01*
Y423450D01*
G03X906476Y423498I-130J-152D01*
G01X906212D01*
G03X906082Y423450I0J-200D01*
G01X906081Y423449D01*
G02X904107I-987J1131D01*
G01X904106D01*
Y423450D01*
G03X903976Y423498I-130J-152D01*
G01X903712D01*
G03X903582Y423450I0J-200D01*
G01X903581Y423449D01*
G02X902594Y423079I-987J1131D01*
G02Y426083I0J1502D01*
G02X903581Y425713I0J-1501D01*
G01X903582D01*
Y425712D01*
G03X903712Y425664I130J152D01*
G01X903976D01*
G03X904106Y425712I0J200D01*
G01X904107Y425713D01*
G02X906081I987J-1131D01*
G37*
G36*
G01X410345Y426740D02*
G02X413349I1502J0D01*
G02X412979Y425753I-1501J0D01*
G01Y425752D01*
X412978D01*
G03X412930Y425622I152J-130D01*
G01Y425358D01*
G03X412978Y425228I200J0D01*
G01X412979Y425227D01*
G02X413349Y424240I-1131J-987D01*
G02X410345I-1502J0D01*
G02X410715Y425227I1501J0D01*
G01Y425228D01*
X410716D01*
G03X410764Y425358I-152J130D01*
G01Y425622D01*
G03X410716Y425752I-200J0D01*
G01X410715Y425753D01*
G02X410345Y426740I1131J987D01*
G37*
G36*
G01X879758Y428084D02*
X879759Y428083D01*
G03X879889Y428035I130J152D01*
G01X880153D01*
G03X880283Y428083I0J200D01*
G01X880284Y428084D01*
G02X881271Y428454I987J-1131D01*
G02Y425450I0J-1502D01*
G02X880284Y425820I0J1501D01*
G01X880283D01*
Y425821D01*
G03X880153Y425869I-130J-152D01*
G01X879889D01*
G03X879759Y425821I0J-200D01*
G01X879758Y425820D01*
G02X877784I-987J1131D01*
G01X877783D01*
Y425821D01*
G03X877653Y425869I-130J-152D01*
G01X877389D01*
G03X877259Y425821I0J-200D01*
G01X877258Y425820D01*
G02X875284I-987J1131D01*
G01X875283D01*
Y425821D01*
G03X875153Y425869I-130J-152D01*
G01X874889D01*
G03X874759Y425821I0J-200D01*
G01X874758Y425820D01*
G02X873771Y425450I-987J1131D01*
G02Y428454I0J1502D01*
G02X874758Y428084I0J-1501D01*
G01X874759D01*
Y428083D01*
G03X874889Y428035I130J152D01*
G01X875153D01*
G03X875283Y428083I0J200D01*
G01X875284Y428084D01*
G02X877258I987J-1131D01*
G01X877259D01*
Y428083D01*
G03X877389Y428035I130J152D01*
G01X877653D01*
G03X877783Y428083I0J200D01*
G01X877784Y428084D01*
G02X879758I987J-1131D01*
G37*
G36*
G01X895506D02*
X895507Y428083D01*
G03X895637Y428035I130J152D01*
G01X895901D01*
G03X896031Y428083I0J200D01*
G01X896032Y428084D01*
G02X897019Y428454I987J-1131D01*
G02Y425450I0J-1502D01*
G02X896032Y425820I0J1501D01*
G01X896031D01*
Y425821D01*
G03X895901Y425869I-130J-152D01*
G01X895637D01*
G03X895507Y425821I0J-200D01*
G01X895506Y425820D01*
G02X893532I-987J1131D01*
G01X893531D01*
Y425821D01*
G03X893401Y425869I-130J-152D01*
G01X893137D01*
G03X893007Y425821I0J-200D01*
G01X893006Y425820D01*
G02X892019Y425450I-987J1131D01*
G02X890913Y425935I0J1504D01*
G03X890766Y426000I-148J-135D01*
G01X890472D01*
G03X890325Y425935I1J-200D01*
G02X889219Y425450I-1106J1019D01*
G02Y428454I0J1502D01*
G02X890325Y427969I0J-1504D01*
G03X890472Y427904I148J135D01*
G01X890766D01*
G03X890913Y427969I-1J200D01*
G02X892019Y428454I1106J-1019D01*
G02X893006Y428084I0J-1501D01*
G01X893007D01*
Y428083D01*
G03X893137Y428035I130J152D01*
G01X893401D01*
G03X893531Y428083I0J200D01*
G01X893532Y428084D01*
G02X895506I987J-1131D01*
G37*
G36*
G01X420713Y427439D02*
G02X423717I1502J0D01*
G02X423347Y426452I-1501J0D01*
G01Y426451D01*
X423346D01*
G03X423298Y426321I152J-130D01*
G01Y426057D01*
G03X423346Y425927I200J0D01*
G01X423347Y425926D01*
G02X423717Y424939I-1131J-987D01*
G02X420713I-1502J0D01*
G02X421083Y425926I1501J0D01*
G01Y425927D01*
X421084D01*
G03X421132Y426057I-152J130D01*
G01Y426321D01*
G03X421084Y426451I-200J0D01*
G01X421083Y426452D01*
G02X420713Y427439I1131J987D01*
G37*
G36*
G01X595377Y431662D02*
G02X596211Y431458I1J-1802D01*
G03X596350Y431441I92J178D01*
G01X596468Y431470D01*
G03X596584Y431549I-47J194D01*
G02X597873Y432216I1289J-912D01*
G02Y429060I0J-1578D01*
G02X597639Y429077I-3J1578D01*
G01X597595Y429084D01*
X597512Y429060D01*
X597249Y428833D01*
G03X597180Y428681I131J-151D01*
G01Y427639D01*
G03X597249Y427487I200J-1D01*
G01X597512Y427260D01*
X597595Y427236D01*
X597639Y427243D01*
G02X597873Y427260I231J-1561D01*
G02Y424104I0J-1578D01*
G02X596584Y424771I0J1579D01*
G03X596468Y424850I-163J-115D01*
G01X596350Y424879D01*
G03X596211Y424862I-47J-195D01*
G02X595377Y424658I-833J1598D01*
G02X594543Y424862I-1J1802D01*
G03X594404Y424879I-92J-178D01*
G01X594286Y424850D01*
G03X594170Y424771I47J-194D01*
G02X592881Y424104I-1289J912D01*
G02Y427260I0J1578D01*
G02X593115Y427243I3J-1578D01*
G01X593159Y427236D01*
X593242Y427260D01*
X593505Y427487D01*
G03X593574Y427639I-131J151D01*
G01Y428681D01*
G03X593505Y428833I-200J1D01*
G01X593242Y429060D01*
X593159Y429084D01*
X593115Y429077D01*
G02X592881Y429060I-231J1561D01*
G02Y432216I0J1578D01*
G02X594170Y431549I0J-1579D01*
G03X594286Y431470I163J115D01*
G01X594404Y431441D01*
G03X594543Y431458I47J195D01*
G02X595377Y431662I833J-1598D01*
G37*
G36*
G01X1052463D02*
G02X1053297Y431458I1J-1802D01*
G03X1053436Y431441I92J178D01*
G01X1053554Y431470D01*
G03X1053670Y431549I-47J194D01*
G02X1054959Y432216I1289J-912D01*
G02Y429060I0J-1578D01*
G02X1054725Y429077I-3J1578D01*
G01X1054681Y429084D01*
X1054598Y429060D01*
X1054335Y428833D01*
G03X1054266Y428681I131J-151D01*
G01Y427639D01*
G03X1054335Y427487I200J-1D01*
G01X1054598Y427260D01*
X1054681Y427236D01*
X1054725Y427243D01*
G02X1054959Y427260I231J-1561D01*
G02Y424104I0J-1578D01*
G02X1053670Y424771I0J1579D01*
G03X1053554Y424850I-163J-115D01*
G01X1053436Y424879D01*
G03X1053297Y424862I-47J-195D01*
G02X1052463Y424658I-833J1598D01*
G02X1051629Y424862I-1J1802D01*
G03X1051490Y424879I-92J-178D01*
G01X1051372Y424850D01*
G03X1051256Y424771I47J-194D01*
G02X1049967Y424104I-1289J912D01*
G02Y427260I0J1578D01*
G02X1050201Y427243I3J-1578D01*
G01X1050245Y427236D01*
X1050328Y427260D01*
X1050591Y427487D01*
G03X1050660Y427639I-131J151D01*
G01Y428681D01*
G03X1050591Y428833I-200J1D01*
G01X1050328Y429060D01*
X1050245Y429084D01*
X1050201Y429077D01*
G02X1049967Y429060I-231J1561D01*
G02Y432216I0J1578D01*
G02X1051256Y431549I0J-1579D01*
G03X1051372Y431470I163J115D01*
G01X1051490Y431441D01*
G03X1051629Y431458I47J195D01*
G02X1052463Y431662I833J-1598D01*
G37*
G36*
G01X739900Y433570D02*
G02X742904I1502J0D01*
G02X742406Y432453I-1502J0D01*
G01X742374Y432425D01*
X742340Y432348D01*
X742338Y432010D01*
G03X742402Y431862I200J-1D01*
G02X742883Y430760I-1022J-1102D01*
G02X739879I-1502J0D01*
G02X740377Y431877I1502J0D01*
G01X740409Y431905D01*
X740443Y431982D01*
X740445Y432320D01*
G03X740381Y432468I-200J1D01*
G02X739900Y433570I1022J1102D01*
G37*
G36*
G01X823601Y435558D02*
G02X826605I1502J0D01*
G02X826199Y434531I-1502J0D01*
G01X826173Y434504D01*
X826145Y434433D01*
Y434083D01*
X826173Y434012D01*
X826199Y433985D01*
G02Y431931I-1096J-1027D01*
G01X826173Y431904D01*
X826145Y431833D01*
Y431483D01*
X826173Y431412D01*
X826199Y431385D01*
G02X826605Y430358I-1096J-1027D01*
G02X823601I-1502J0D01*
G02X824007Y431385I1502J0D01*
G01X824033Y431412D01*
X824061Y431483D01*
Y431833D01*
X824033Y431904D01*
X824007Y431931D01*
G02Y433985I1096J1027D01*
G01X824033Y434012D01*
X824061Y434083D01*
Y434433D01*
X824033Y434504D01*
X824007Y434531D01*
G02X823601Y435558I1096J1027D01*
G37*
G36*
G01X829876Y435686D02*
G02X832880I1502J0D01*
G02X832474Y434659I-1502J0D01*
G01X832448Y434632D01*
X832420Y434561D01*
Y434211D01*
X832448Y434140D01*
X832474Y434113D01*
G02Y432059I-1096J-1027D01*
G01X832448Y432032D01*
X832420Y431961D01*
Y431611D01*
X832448Y431540D01*
X832474Y431513D01*
G02X832880Y430486I-1096J-1027D01*
G02X829876I-1502J0D01*
G02X830282Y431513I1502J0D01*
G01X830308Y431540D01*
X830336Y431611D01*
Y431961D01*
X830308Y432032D01*
X830282Y432059D01*
G02Y434113I1096J1027D01*
G01X830308Y434140D01*
X830336Y434211D01*
Y434561D01*
X830308Y434632D01*
X830282Y434659D01*
G02X829876Y435686I1096J1027D01*
G37*
G36*
G01X922933Y437668D02*
X923227D01*
G03X923374Y437733I-1J200D01*
G02X925586I1106J-1017D01*
G03X925733Y437668I148J135D01*
G01X926027D01*
G03X926174Y437733I-1J200D01*
G02X927280Y438218I1106J-1019D01*
G02Y435214I0J-1502D01*
G02X926174Y435699I0J1504D01*
G03X926027Y435764I-148J-135D01*
G01X925733D01*
G03X925586Y435699I1J-200D01*
G02X923374I-1106J1017D01*
G03X923227Y435764I-148J-135D01*
G01X922933D01*
G03X922786Y435699I1J-200D01*
G02X921680Y435214I-1106J1019D01*
G02Y438218I0J1502D01*
G02X922786Y437733I0J-1504D01*
G03X922933Y437668I148J135D01*
G37*
G36*
G01X906199Y437866D02*
X906200Y437865D01*
G03X906330Y437817I130J152D01*
G01X906594D01*
G03X906724Y437865I0J200D01*
G01X906725Y437866D01*
G02X907712Y438236I987J-1131D01*
G02Y435232I0J-1502D01*
G02X906725Y435602I0J1501D01*
G01X906724D01*
Y435603D01*
G03X906594Y435651I-130J-152D01*
G01X906330D01*
G03X906200Y435603I0J-200D01*
G01X906199Y435602D01*
G02X904225I-987J1131D01*
G01X904224D01*
Y435603D01*
G03X904094Y435651I-130J-152D01*
G01X903830D01*
G03X903700Y435603I0J-200D01*
G01X903699Y435602D01*
G02X902712Y435232I-987J1131D01*
G02Y438236I0J1502D01*
G02X903699Y437866I0J-1501D01*
G01X903700D01*
Y437865D01*
G03X903830Y437817I130J152D01*
G01X904094D01*
G03X904224Y437865I0J200D01*
G01X904225Y437866D01*
G02X906199I987J-1131D01*
G37*
G36*
G01X887096Y435762D02*
G02Y438766I0J1502D01*
G02X888083Y438396I0J-1501D01*
G01X888084D01*
Y438395D01*
G03X888214Y438347I130J152D01*
G01X888478D01*
G03X888608Y438395I0J200D01*
G01X888609Y438396D01*
G02X889596Y438766I987J-1131D01*
G02Y435762I0J-1502D01*
G02X888609Y436132I0J1501D01*
G01X888608D01*
Y436133D01*
G03X888478Y436181I-130J-152D01*
G01X888214D01*
G03X888084Y436133I0J-200D01*
G01X888083Y436132D01*
G02X887096Y435762I-987J1131D01*
G37*
G36*
G01X879523Y438540D02*
X879524Y438539D01*
G03X879654Y438491I130J152D01*
G01X879918D01*
G03X880048Y438539I0J200D01*
G01X880049Y438540D01*
G02X881036Y438910I987J-1131D01*
G02Y435906I0J-1502D01*
G02X880049Y436276I0J1501D01*
G01X880048D01*
Y436277D01*
G03X879918Y436325I-130J-152D01*
G01X879654D01*
G03X879524Y436277I0J-200D01*
G01X879523Y436276D01*
G02X877549I-987J1131D01*
G01X877548D01*
Y436277D01*
G03X877418Y436325I-130J-152D01*
G01X877154D01*
G03X877024Y436277I0J-200D01*
G01X877023Y436276D01*
G02X875049I-987J1131D01*
G01X875048D01*
Y436277D01*
G03X874918Y436325I-130J-152D01*
G01X874654D01*
G03X874524Y436277I0J-200D01*
G01X874523Y436276D01*
G02X873536Y435906I-987J1131D01*
G02Y438910I0J1502D01*
G02X874523Y438540I0J-1501D01*
G01X874524D01*
Y438539D01*
G03X874654Y438491I130J152D01*
G01X874918D01*
G03X875048Y438539I0J200D01*
G01X875049Y438540D01*
G02X877023I987J-1131D01*
G01X877024D01*
Y438539D01*
G03X877154Y438491I130J152D01*
G01X877418D01*
G03X877548Y438539I0J200D01*
G01X877549Y438540D01*
G02X879523I987J-1131D01*
G37*
G36*
G01X896388Y436112D02*
G02Y439116I0J1502D01*
G02X897375Y438746I0J-1501D01*
G01X897376D01*
Y438745D01*
G03X897506Y438697I130J152D01*
G01X897770D01*
G03X897900Y438745I0J200D01*
G01X897901Y438746D01*
G02X898888Y439116I987J-1131D01*
G02Y436112I0J-1502D01*
G02X897901Y436482I0J1501D01*
G01X897900D01*
Y436483D01*
G03X897770Y436531I-130J-152D01*
G01X897506D01*
G03X897376Y436483I0J-200D01*
G01X897375Y436482D01*
G02X896388Y436112I-987J1131D01*
G37*
G36*
G01X604688Y438531D02*
X604806Y438502D01*
G03X604945Y438519I47J195D01*
G02X605779Y438724I835J-1598D01*
G02X606613Y438519I-1J-1803D01*
G03X606752Y438502I92J178D01*
G01X606870Y438531D01*
G03X606986Y438610I-47J194D01*
G02X608275Y439278I1289J-910D01*
G02Y436120I0J-1579D01*
G02X608041Y436138I4J1579D01*
G01X607997Y436145D01*
X607914Y436121D01*
X607651Y435894D01*
G03X607582Y435742I131J-151D01*
G01Y434700D01*
G03X607651Y434548I200J-1D01*
G01X607914Y434321D01*
X607997Y434297D01*
X608041Y434304D01*
G02X608275Y434322I238J-1561D01*
G02Y431164I0J-1579D01*
G02X606986Y431832I0J1578D01*
G03X606870Y431911I-163J-115D01*
G01X606752Y431940D01*
G03X606613Y431923I-47J-195D01*
G02X605779Y431718I-835J1598D01*
G02X604945Y431923I1J1803D01*
G03X604806Y431940I-92J-178D01*
G01X604688Y431911D01*
G03X604572Y431832I47J-194D01*
G02X603283Y431164I-1289J910D01*
G02Y434322I0J1579D01*
G02X603517Y434304I-4J-1579D01*
G01X603561Y434297D01*
X603644Y434321D01*
X603907Y434548D01*
G03X603976Y434700I-131J151D01*
G01Y435742D01*
G03X603907Y435894I-200J1D01*
G01X603644Y436121D01*
X603561Y436145D01*
X603517Y436138D01*
G02X603283Y436120I-238J1561D01*
G02Y439278I0J1579D01*
G02X604572Y438610I0J-1578D01*
G03X604688Y438531I163J115D01*
G37*
G36*
G01X1061774D02*
X1061892Y438502D01*
G03X1062031Y438519I47J195D01*
G02X1062865Y438724I835J-1598D01*
G02X1063699Y438519I-1J-1803D01*
G03X1063838Y438502I92J178D01*
G01X1063956Y438531D01*
G03X1064072Y438610I-47J194D01*
G02X1065361Y439278I1289J-910D01*
G02Y436120I0J-1579D01*
G02X1065127Y436138I4J1579D01*
G01X1065083Y436145D01*
X1065000Y436121D01*
X1064737Y435894D01*
G03X1064668Y435742I131J-151D01*
G01Y434700D01*
G03X1064737Y434548I200J-1D01*
G01X1065000Y434321D01*
X1065083Y434297D01*
X1065127Y434304D01*
G02X1065361Y434322I238J-1561D01*
G02Y431164I0J-1579D01*
G02X1064072Y431832I0J1578D01*
G03X1063956Y431911I-163J-115D01*
G01X1063838Y431940D01*
G03X1063699Y431923I-47J-195D01*
G02X1062865Y431718I-835J1598D01*
G02X1062031Y431923I1J1803D01*
G03X1061892Y431940I-92J-178D01*
G01X1061774Y431911D01*
G03X1061658Y431832I47J-194D01*
G02X1060369Y431164I-1289J910D01*
G02Y434322I0J1579D01*
G02X1060603Y434304I-4J-1579D01*
G01X1060647Y434297D01*
X1060730Y434321D01*
X1060993Y434548D01*
G03X1061062Y434700I-131J151D01*
G01Y435742D01*
G03X1060993Y435894I-200J1D01*
G01X1060730Y436121D01*
X1060647Y436145D01*
X1060603Y436138D01*
G02X1060369Y436120I-238J1561D01*
G02Y439278I0J1579D01*
G02X1061658Y438610I0J-1578D01*
G03X1061774Y438531I163J115D01*
G37*
G36*
G01X748037Y440869D02*
G02X749539Y442371I1502J0D01*
G02X750645Y441886I0J-1504D01*
G03X750792Y441821I148J135D01*
G01X751086D01*
G03X751233Y441886I-1J200D01*
G02X752339Y442371I1106J-1019D01*
G02X753841Y440869I0J-1502D01*
G02X753435Y439842I-1502J0D01*
G01X753409Y439815D01*
X753381Y439744D01*
Y439394D01*
X753409Y439323D01*
X753435Y439296D01*
G02Y437242I-1096J-1027D01*
G01X753409Y437215D01*
X753381Y437144D01*
Y436794D01*
X753409Y436723D01*
X753435Y436696D01*
G02Y434642I-1096J-1027D01*
G01X753409Y434615D01*
X753381Y434544D01*
Y434194D01*
X753409Y434123D01*
X753435Y434096D01*
G02Y432042I-1096J-1027D01*
G01X753409Y432015D01*
X753381Y431944D01*
Y431594D01*
X753409Y431523D01*
X753435Y431496D01*
G02X753841Y430469I-1096J-1027D01*
G02X752339Y428967I-1502J0D01*
G02X751233Y429452I0J1504D01*
G03X751086Y429517I-148J-135D01*
G01X750792D01*
G03X750645Y429452I1J-200D01*
G02X749539Y428967I-1106J1019D01*
G02X748037Y430469I0J1502D01*
G02X748443Y431496I1502J0D01*
G01X748469Y431523D01*
X748497Y431594D01*
Y431944D01*
X748469Y432015D01*
X748443Y432042D01*
G02Y434096I1096J1027D01*
G01X748469Y434123D01*
X748497Y434194D01*
Y434544D01*
X748469Y434615D01*
X748443Y434642D01*
G02Y436696I1096J1027D01*
G01X748469Y436723D01*
X748497Y436794D01*
Y437144D01*
X748469Y437215D01*
X748443Y437242D01*
G02Y439296I1096J1027D01*
G01X748469Y439323D01*
X748497Y439394D01*
Y439744D01*
X748469Y439815D01*
X748443Y439842D01*
G02X748037Y440869I1096J1027D01*
G37*
G36*
G01X366967Y440571D02*
Y440865D01*
G03X366902Y441012I-200J-1D01*
G02X366417Y442118I1019J1106D01*
G02X369421I1502J0D01*
G02X368936Y441012I-1504J0D01*
G03X368871Y440865I135J-148D01*
G01Y440571D01*
G03X368936Y440424I200J1D01*
G02X369421Y439318I-1019J-1106D01*
G02X366417I-1502J0D01*
G02X366902Y440424I1504J0D01*
G03X366967Y440571I-135J148D01*
G37*
G36*
G01X374967D02*
Y440865D01*
G03X374902Y441012I-200J-1D01*
G02X374417Y442118I1019J1106D01*
G02X377421I1502J0D01*
G02X376936Y441012I-1504J0D01*
G03X376871Y440865I135J-148D01*
G01Y440571D01*
G03X376936Y440424I200J1D01*
G02X377421Y439318I-1019J-1106D01*
G02X374417I-1502J0D01*
G02X374902Y440424I1504J0D01*
G03X374967Y440571I-135J148D01*
G37*
G36*
G01X905671Y443081D02*
G02X908675I1502J0D01*
G02X908305Y442094I-1501J0D01*
G01Y442093D01*
X908304D01*
G03X908256Y441963I152J-130D01*
G01Y441699D01*
G03X908304Y441569I200J0D01*
G01X908305Y441568D01*
G02X908675Y440581I-1131J-987D01*
G02X905671I-1502J0D01*
G02X906041Y441568I1501J0D01*
G01Y441569D01*
X906042D01*
G03X906090Y441699I-152J130D01*
G01Y441963D01*
G03X906042Y442093I-200J0D01*
G01X906041Y442094D01*
G02X905671Y443081I1131J987D01*
G37*
G36*
G01X411172Y442174D02*
Y442468D01*
G03X411107Y442615I-200J-1D01*
G02X410622Y443721I1019J1106D01*
G02X412124Y445223I1502J0D01*
G02X413230Y444738I0J-1504D01*
G03X413377Y444673I148J135D01*
G01X413671D01*
G03X413818Y444738I-1J200D01*
G02X414924Y445223I1106J-1019D01*
G02X416426Y443721I0J-1502D01*
G02X415941Y442615I-1504J0D01*
G03X415876Y442468I135J-148D01*
G01Y442174D01*
G03X415941Y442027I200J1D01*
G02Y439815I-1017J-1106D01*
G03X415876Y439668I135J-148D01*
G01Y439374D01*
G03X415941Y439227I200J1D01*
G02Y437015I-1017J-1106D01*
G03X415876Y436868I135J-148D01*
G01Y436574D01*
G03X415941Y436427I200J1D01*
G02X416426Y435321I-1019J-1106D01*
G02X414924Y433819I-1502J0D01*
G02X413818Y434304I0J1504D01*
G03X413671Y434369I-148J-135D01*
G01X413377D01*
G03X413230Y434304I1J-200D01*
G02X412124Y433819I-1106J1019D01*
G02X410622Y435321I0J1502D01*
G02X411107Y436427I1504J0D01*
G03X411172Y436574I-135J148D01*
G01Y436868D01*
G03X411107Y437015I-200J-1D01*
G02Y439227I1017J1106D01*
G03X411172Y439374I-135J148D01*
G01Y439668D01*
G03X411107Y439815I-200J-1D01*
G02Y442027I1017J1106D01*
G03X411172Y442174I-135J148D01*
G37*
G36*
G01X916039Y443780D02*
G02X919043I1502J0D01*
G02X918673Y442793I-1501J0D01*
G01Y442792D01*
X918672D01*
G03X918624Y442662I152J-130D01*
G01Y442398D01*
G03X918672Y442268I200J0D01*
G01X918673Y442267D01*
G02X919043Y441280I-1131J-987D01*
G02X916039I-1502J0D01*
G02X916409Y442267I1501J0D01*
G01Y442268D01*
X916410D01*
G03X916458Y442398I-152J130D01*
G01Y442662D01*
G03X916410Y442792I-200J0D01*
G01X916409Y442793D01*
G02X916039Y443780I1131J987D01*
G37*
G36*
G01X384632Y442346D02*
Y442640D01*
G03X384567Y442787I-200J-1D01*
G02X384082Y443893I1019J1106D01*
G02X387086I1502J0D01*
G02X386601Y442787I-1504J0D01*
G03X386536Y442640I135J-148D01*
G01Y442346D01*
G03X386601Y442199I200J1D01*
G02Y439987I-1017J-1106D01*
G03X386536Y439840I135J-148D01*
G01Y439546D01*
G03X386601Y439399I200J1D01*
G02X387086Y438293I-1019J-1106D01*
G02X384082I-1502J0D01*
G02X384567Y439399I1504J0D01*
G03X384632Y439546I-135J148D01*
G01Y439840D01*
G03X384567Y439987I-200J-1D01*
G02Y442199I1017J1106D01*
G03X384632Y442346I-135J148D01*
G37*
G36*
G01X394625D02*
Y442640D01*
G03X394560Y442787I-200J-1D01*
G02X394075Y443893I1019J1106D01*
G02X397079I1502J0D01*
G02X396594Y442787I-1504J0D01*
G03X396529Y442640I135J-148D01*
G01Y442346D01*
G03X396594Y442199I200J1D01*
G02Y439987I-1017J-1106D01*
G03X396529Y439840I135J-148D01*
G01Y439546D01*
G03X396594Y439399I200J1D01*
G02X397079Y438293I-1019J-1106D01*
G02X394075I-1502J0D01*
G02X394560Y439399I1504J0D01*
G03X394625Y439546I-135J148D01*
G01Y439840D01*
G03X394560Y439987I-200J-1D01*
G02Y442199I1017J1106D01*
G03X394625Y442346I-135J148D01*
G37*
G36*
G01X594286Y445643D02*
X594404Y445614D01*
G03X594543Y445631I47J195D01*
G02X595377Y445836I835J-1598D01*
G02X596211Y445631I-1J-1803D01*
G03X596350Y445614I92J178D01*
G01X596468Y445643D01*
G03X596584Y445722I-47J194D01*
G02X597873Y446390I1289J-910D01*
G02Y443232I0J-1579D01*
G02X597639Y443250I4J1579D01*
G01X597595Y443257D01*
X597512Y443233D01*
X597249Y443006D01*
G03X597180Y442854I131J-151D01*
G01Y441812D01*
G03X597249Y441660I200J-1D01*
G01X597512Y441433D01*
X597595Y441409D01*
X597639Y441416D01*
G02X597873Y441434I238J-1561D01*
G02Y438276I0J-1579D01*
G02X596584Y438944I0J1578D01*
G03X596468Y439023I-163J-115D01*
G01X596350Y439052D01*
G03X596211Y439035I-47J-195D01*
G02X595377Y438830I-835J1598D01*
G02X594543Y439035I1J1803D01*
G03X594404Y439052I-92J-178D01*
G01X594286Y439023D01*
G03X594170Y438944I47J-194D01*
G02X592881Y438276I-1289J910D01*
G02Y441434I0J1579D01*
G02X593115Y441416I-4J-1579D01*
G01X593159Y441409D01*
X593242Y441433D01*
X593505Y441660D01*
G03X593574Y441812I-131J151D01*
G01Y442854D01*
G03X593505Y443006I-200J1D01*
G01X593242Y443233D01*
X593159Y443257D01*
X593115Y443250D01*
G02X592881Y443232I-238J1561D01*
G02Y446390I0J1579D01*
G02X594170Y445722I0J-1578D01*
G03X594286Y445643I163J115D01*
G37*
G36*
G01X1051372D02*
X1051490Y445614D01*
G03X1051629Y445631I47J195D01*
G02X1052463Y445836I835J-1598D01*
G02X1053297Y445631I-1J-1803D01*
G03X1053436Y445614I92J178D01*
G01X1053554Y445643D01*
G03X1053670Y445722I-47J194D01*
G02X1054959Y446390I1289J-910D01*
G02Y443232I0J-1579D01*
G02X1054725Y443250I4J1579D01*
G01X1054681Y443257D01*
X1054598Y443233D01*
X1054335Y443006D01*
G03X1054266Y442854I131J-151D01*
G01Y441812D01*
G03X1054335Y441660I200J-1D01*
G01X1054598Y441433D01*
X1054681Y441409D01*
X1054725Y441416D01*
G02X1054959Y441434I238J-1561D01*
G02Y438276I0J-1579D01*
G02X1053670Y438944I0J1578D01*
G03X1053554Y439023I-163J-115D01*
G01X1053436Y439052D01*
G03X1053297Y439035I-47J-195D01*
G02X1052463Y438830I-835J1598D01*
G02X1051629Y439035I1J1803D01*
G03X1051490Y439052I-92J-178D01*
G01X1051372Y439023D01*
G03X1051256Y438944I47J-194D01*
G02X1049967Y438276I-1289J910D01*
G02Y441434I0J1579D01*
G02X1050201Y441416I-4J-1579D01*
G01X1050245Y441409D01*
X1050328Y441433D01*
X1050591Y441660D01*
G03X1050660Y441812I-131J151D01*
G01Y442854D01*
G03X1050591Y443006I-200J1D01*
G01X1050328Y443233D01*
X1050245Y443257D01*
X1050201Y443250D01*
G02X1049967Y443232I-238J1561D01*
G02Y446390I0J1579D01*
G02X1051256Y445722I0J-1578D01*
G03X1051372Y445643I163J115D01*
G37*
G36*
G01X665167Y447424D02*
G02Y444268I0J-1578D01*
G02X664900Y444290I-4J1578D01*
G03X664737Y444246I-34J-197D01*
G01X664641Y444164D01*
G03X664570Y444010I129J-153D01*
G01Y440602D01*
Y440595D01*
G03X664641Y440441I200J-1D01*
G01X664737Y440359D01*
G03X664900Y440315I129J153D01*
G02X665167Y440338I269J-1556D01*
G02X666222Y439933I-1J-1579D01*
G03X666355Y439882I133J149D01*
G01X666479D01*
G03X666612Y439933I0J200D01*
G02X667667Y440338I1056J-1174D01*
G02X669226Y439009I0J-1579D01*
G01X669232Y438968D01*
X669276Y438898D01*
X669548Y438711D01*
G03X669701Y438680I113J165D01*
G01X669702D01*
G02X670067Y438718I368J-1765D01*
G02X670431Y438680I-4J-1803D01*
G01X670433D01*
G03X670586Y438711I40J196D01*
G01X670858Y438898D01*
X670902Y438968D01*
X670908Y439009D01*
G02X672467Y440338I1559J-250D01*
G02Y437180I0J-1579D01*
G02X672200Y437203I2J1579D01*
G03X672037Y437159I-34J-197D01*
G01X671941Y437077D01*
G03X671870Y436923I129J-153D01*
G01Y433515D01*
Y433508D01*
G03X671941Y433354I200J-1D01*
G01X672037Y433272D01*
G03X672200Y433228I129J153D01*
G02X672467Y433250I263J-1556D01*
G02Y430094I0J-1578D01*
G02X670908Y431422I0J1579D01*
G01X670902Y431463D01*
X670859Y431531D01*
X670586Y431719D01*
G03X670433Y431750I-113J-165D01*
G01X670432D01*
G02X670067Y431712I-368J1765D01*
G02X669703Y431750I4J1803D01*
G01X669701D01*
G03X669548Y431719I-40J-196D01*
G01X669275Y431531D01*
X669232Y431463D01*
X669226Y431422D01*
G02X667667Y430094I-1559J251D01*
G02X666612Y430498I0J1580D01*
G03X666479Y430549I-133J-149D01*
G01X666355D01*
G03X666222Y430498I0J-200D01*
G02X665167Y430094I-1055J1176D01*
G02X664900Y430116I-4J1578D01*
G03X664737Y430072I-34J-197D01*
G01X664641Y429990D01*
G03X664570Y429836I129J-153D01*
G01Y426428D01*
Y426421D01*
G03X664641Y426267I200J-1D01*
G01X664737Y426185D01*
G03X664900Y426141I129J153D01*
G02X665167Y426164I269J-1556D01*
G02X666222Y425759I-1J-1579D01*
G03X666355Y425708I133J149D01*
G01X666479D01*
G03X666612Y425759I0J200D01*
G02X667667Y426164I1056J-1174D01*
G02X669226Y424835I0J-1579D01*
G01X669232Y424794D01*
X669276Y424724D01*
X669548Y424537D01*
G03X669701Y424506I113J165D01*
G01X669702D01*
G02X670067Y424544I368J-1765D01*
G02X670431Y424506I-4J-1803D01*
G01X670433D01*
G03X670586Y424537I40J196D01*
G01X670858Y424724D01*
X670902Y424794D01*
X670908Y424835D01*
G02X672467Y426164I1559J-250D01*
G02Y423006I0J-1579D01*
G02X672200Y423029I2J1579D01*
G03X672037Y422985I-34J-197D01*
G01X671941Y422903D01*
G03X671870Y422749I129J-153D01*
G01Y419341D01*
Y419334D01*
G03X671941Y419180I200J-1D01*
G01X672037Y419098D01*
G03X672200Y419054I129J153D01*
G02X672467Y419076I263J-1556D01*
G02Y415920I0J-1578D01*
G02X670908Y417248I0J1579D01*
G01X670902Y417289D01*
X670859Y417357D01*
X670586Y417545D01*
G03X670433Y417576I-113J-165D01*
G01X670432D01*
G02X670067Y417538I-368J1765D01*
G02X669703Y417576I4J1803D01*
G01X669701D01*
G03X669548Y417545I-40J-196D01*
G01X669275Y417357D01*
X669232Y417289D01*
X669226Y417248D01*
G02X667667Y415920I-1559J251D01*
G02X666611Y416325I0J1579D01*
G03X666478Y416376I-133J-149D01*
G01X666355D01*
G03X666222Y416325I0J-200D01*
G02X665167Y415920I-1056J1174D01*
G02X664900Y415943I2J1579D01*
G03X664737Y415899I-34J-197D01*
G01X664641Y415817D01*
G03X664570Y415663I129J-153D01*
G01Y412255D01*
Y412248D01*
G03X664641Y412094I200J-1D01*
G01X664737Y412012D01*
G03X664900Y411968I129J153D01*
G02X665167Y411990I263J-1556D01*
G02X666222Y411586I0J-1580D01*
G03X666355Y411535I133J149D01*
G01X666479D01*
G03X666612Y411586I0J200D01*
G02X667667Y411990I1055J-1176D01*
G02X669226Y410662I0J-1579D01*
G01X669232Y410621D01*
X669276Y410551D01*
X669548Y410364D01*
G03X669701Y410333I113J165D01*
G01X669702D01*
G02X670067Y410370I363J-1765D01*
G02X670432Y410333I2J-1802D01*
G01X670433D01*
G03X670586Y410364I40J196D01*
G01X670858Y410551D01*
X670902Y410621D01*
X670908Y410662D01*
G02X672467Y411990I1559J-251D01*
G02Y408834I0J-1578D01*
G02X672200Y408856I-4J1578D01*
G03X672037Y408812I-34J-197D01*
G01X671941Y408730D01*
G03X671870Y408576I129J-153D01*
G01Y405168D01*
Y405161D01*
G03X671941Y405007I200J-1D01*
G01X672037Y404925D01*
G03X672200Y404881I129J153D01*
G02X672467Y404904I269J-1556D01*
G02Y401746I0J-1579D01*
G02X670908Y403075I0J1579D01*
G01X670902Y403116D01*
X670859Y403184D01*
X670586Y403372D01*
G03X670433Y403403I-113J-165D01*
G01X670432D01*
G02X670067Y403366I-363J1765D01*
G02X669702Y403403I-2J1802D01*
G01X669701D01*
G03X669548Y403372I-40J-196D01*
G01X669275Y403184D01*
X669232Y403116D01*
X669226Y403075D01*
G02X667667Y401746I-1559J250D01*
G02X666611Y402152I1J1579D01*
G03X666478Y402203I-133J-149D01*
G01X666355D01*
G03X666222Y402152I0J-200D01*
G02X665167Y401748I-1055J1176D01*
G02X664900Y401770I-4J1578D01*
G03X664737Y401726I-34J-197D01*
G01X664641Y401644D01*
G03X664570Y401490I129J-153D01*
G01Y398082D01*
Y398075D01*
G03X664641Y397921I200J-1D01*
G01X664737Y397839D01*
G03X664900Y397795I129J153D01*
G02X665167Y397818I269J-1556D01*
G02X666222Y397413I-1J-1579D01*
G03X666355Y397362I133J149D01*
G01X666479D01*
G03X666612Y397413I0J200D01*
G02X667667Y397818I1056J-1174D01*
G02X669226Y396489I0J-1579D01*
G01X669232Y396448D01*
X669276Y396378D01*
X669548Y396191D01*
G03X669701Y396160I113J165D01*
G01X669702D01*
G02X670067Y396198I368J-1765D01*
G02X670431Y396160I-4J-1803D01*
G01X670433D01*
G03X670586Y396191I40J196D01*
G01X670858Y396378D01*
X670902Y396448D01*
X670908Y396489D01*
G02X672467Y397818I1559J-250D01*
G02Y394660I0J-1579D01*
G02X672200Y394683I2J1579D01*
G03X672037Y394639I-34J-197D01*
G01X671941Y394557D01*
G03X671870Y394403I129J-153D01*
G01Y390995D01*
Y390988D01*
G03X671941Y390834I200J-1D01*
G01X672037Y390752D01*
G03X672200Y390708I129J153D01*
G02X672467Y390730I263J-1556D01*
G02Y387574I0J-1578D01*
G02X670908Y388902I0J1579D01*
G01X670902Y388943D01*
X670859Y389011D01*
X670586Y389199D01*
G03X670433Y389230I-113J-165D01*
G01X670432D01*
G02X670067Y389192I-368J1765D01*
G02X669703Y389230I4J1803D01*
G01X669701D01*
G03X669548Y389199I-40J-196D01*
G01X669275Y389011D01*
X669232Y388943D01*
X669226Y388902D01*
G02X667667Y387574I-1559J251D01*
G02Y390730I0J1578D01*
G02X667934Y390708I4J-1578D01*
G03X668097Y390752I34J197D01*
G01X668193Y390834D01*
G03X668264Y390988I-129J153D01*
G01Y394395D01*
Y394403D01*
G03X668193Y394557I-200J1D01*
G01X668097Y394639D01*
G03X667934Y394683I-129J-153D01*
G02X667667Y394660I-269J1556D01*
G02X666612Y395065I1J1579D01*
G03X666479Y395116I-133J-149D01*
G01X666355D01*
G03X666222Y395065I0J-200D01*
G02X665167Y394660I-1056J1174D01*
G02X663608Y395989I0J1579D01*
G01X663602Y396030D01*
X663559Y396098D01*
X663286Y396286D01*
G03X663133Y396317I-113J-165D01*
G01X663132D01*
G02X662767Y396280I-363J1765D01*
G02X662339Y396331I-2J1802D01*
G01X662298Y396341D01*
X662217Y396327D01*
X661936Y396140D01*
G03X661849Y396006I110J-167D01*
G01Y396005D01*
G02X660366Y394738I-1483J234D01*
G02Y397742I0J1502D01*
G02X660635Y397718I2J-1502D01*
G03X660801Y397763I36J197D01*
G01X660897Y397845D01*
G03X660966Y398006I-131J151D01*
G02X660964Y398082I1801J85D01*
G01Y401482D01*
G02X660966Y401560I1803J-7D01*
G03X660897Y401721I-200J10D01*
G01X660801Y401804D01*
G03X660634Y401849I-130J-152D01*
G02X660366Y401825I-267J1478D01*
G02Y404829I0J1502D01*
G02X661850Y403560I0J-1502D01*
G01X661856Y403518D01*
X661901Y403448D01*
X662218Y403237D01*
X662299Y403223D01*
X662340Y403233D01*
G02X662767Y403284I426J-1751D01*
G02X663132Y403247I2J-1802D01*
G01X663133D01*
G03X663286Y403278I40J196D01*
G01X663558Y403465D01*
X663602Y403535D01*
X663608Y403576D01*
G02X665167Y404904I1559J-251D01*
G02X666223Y404499I0J-1579D01*
G03X666356Y404448I133J149D01*
G01X666479D01*
G03X666612Y404499I0J200D01*
G02X667667Y404904I1056J-1174D01*
G02X667934Y404881I-2J-1579D01*
G03X668097Y404925I34J197D01*
G01X668193Y405007D01*
G03X668264Y405161I-129J153D01*
G01Y408568D01*
Y408576D01*
G03X668193Y408730I-200J1D01*
G01X668097Y408812D01*
G03X667934Y408856I-129J-153D01*
G02X667667Y408834I-263J1556D01*
G02X666612Y409238I0J1580D01*
G03X666479Y409289I-133J-149D01*
G01X666355D01*
G03X666222Y409238I0J-200D01*
G02X665167Y408834I-1055J1176D01*
G02X663608Y410162I0J1579D01*
G01X663602Y410203D01*
X663559Y410271D01*
X663286Y410459D01*
G03X663133Y410490I-113J-165D01*
G01X663132D01*
G02X662767Y410452I-368J1765D01*
G02X662339Y410504I2J1803D01*
G01X662298Y410514D01*
X662217Y410500D01*
X661936Y410313D01*
G03X661849Y410179I110J-167D01*
G01Y410178D01*
G02X660366Y408911I-1483J234D01*
G02Y411915I0J1502D01*
G02X660635Y411891I2J-1502D01*
G03X660801Y411936I36J197D01*
G01X660897Y412018D01*
G03X660966Y412179I-131J151D01*
G02X660964Y412255I1801J85D01*
G01Y415655D01*
G02X660966Y415733I1803J-7D01*
G03X660897Y415894I-200J10D01*
G01X660801Y415977D01*
G03X660634Y416022I-130J-152D01*
G02X660366Y415998I-267J1478D01*
G02Y419002I0J1502D01*
G02X661850Y417733I0J-1502D01*
G01X661856Y417691D01*
X661901Y417621D01*
X662218Y417410D01*
X662299Y417396D01*
X662340Y417406D01*
G02X662767Y417458I430J-1751D01*
G02X663131Y417420I-4J-1803D01*
G01X663133D01*
G03X663286Y417451I40J196D01*
G01X663558Y417638D01*
X663602Y417708D01*
X663608Y417749D01*
G02X665167Y419078I1559J-250D01*
G02X666223Y418672I-1J-1579D01*
G03X666356Y418621I133J149D01*
G01X666479D01*
G03X666612Y418672I0J200D01*
G02X667667Y419076I1055J-1176D01*
G02X667934Y419054I4J-1578D01*
G03X668097Y419098I34J197D01*
G01X668193Y419180D01*
G03X668264Y419334I-129J153D01*
G01Y422741D01*
Y422749D01*
G03X668193Y422903I-200J1D01*
G01X668097Y422985D01*
G03X667934Y423029I-129J-153D01*
G02X667667Y423006I-269J1556D01*
G02X666612Y423411I1J1579D01*
G03X666479Y423462I-133J-149D01*
G01X666355D01*
G03X666222Y423411I0J-200D01*
G02X665167Y423006I-1056J1174D01*
G02X663608Y424335I0J1579D01*
G01X663602Y424376D01*
X663559Y424444D01*
X663286Y424632D01*
G03X663133Y424663I-113J-165D01*
G01X663132D01*
G02X662767Y424626I-363J1765D01*
G02X662339Y424677I-2J1802D01*
G01X662298Y424687D01*
X662217Y424673D01*
X661936Y424486D01*
G03X661849Y424352I110J-167D01*
G01Y424351D01*
G02X660366Y423084I-1483J234D01*
G02Y426088I0J1502D01*
G02X660635Y426064I2J-1502D01*
G03X660801Y426109I36J197D01*
G01X660897Y426191D01*
G03X660966Y426352I-131J151D01*
G02X660964Y426428I1801J85D01*
G01Y429828D01*
G02X660966Y429906I1803J-7D01*
G03X660897Y430067I-200J10D01*
G01X660801Y430150D01*
G03X660634Y430195I-130J-152D01*
G02X660366Y430171I-267J1478D01*
G02Y433175I0J1502D01*
G02X661850Y431906I0J-1502D01*
G01X661856Y431864D01*
X661901Y431794D01*
X662218Y431583D01*
X662299Y431569D01*
X662340Y431579D01*
G02X662767Y431630I426J-1751D01*
G02X663132Y431593I2J-1802D01*
G01X663133D01*
G03X663286Y431624I40J196D01*
G01X663558Y431811D01*
X663602Y431881D01*
X663608Y431922D01*
G02X665167Y433250I1559J-251D01*
G02X666222Y432846I0J-1580D01*
G03X666355Y432795I133J149D01*
G01X666479D01*
G03X666612Y432846I0J200D01*
G02X667667Y433250I1055J-1176D01*
G02X667934Y433228I4J-1578D01*
G03X668097Y433272I34J197D01*
G01X668193Y433354D01*
G03X668264Y433508I-129J153D01*
G01Y436915D01*
Y436923D01*
G03X668193Y437077I-200J1D01*
G01X668097Y437159D01*
G03X667934Y437203I-129J-153D01*
G02X667667Y437180I-269J1556D01*
G02X666612Y437585I1J1579D01*
G03X666479Y437636I-133J-149D01*
G01X666355D01*
G03X666222Y437585I0J-200D01*
G02X665167Y437180I-1056J1174D01*
G02X663608Y438509I0J1579D01*
G01X663602Y438550D01*
X663559Y438618D01*
X663286Y438806D01*
G03X663133Y438837I-113J-165D01*
G01X663132D01*
G02X662767Y438800I-363J1765D01*
G02X662339Y438851I-2J1802D01*
G01X662298Y438861D01*
X662217Y438847D01*
X661936Y438660D01*
G03X661849Y438526I110J-167D01*
G01Y438525D01*
G02X660366Y437258I-1483J234D01*
G02Y440262I0J1502D01*
G02X660635Y440238I2J-1502D01*
G03X660801Y440283I36J197D01*
G01X660897Y440365D01*
G03X660966Y440526I-131J151D01*
G02X660964Y440602I1801J85D01*
G01Y444002D01*
G02X660966Y444080I1803J-7D01*
G03X660897Y444241I-200J10D01*
G01X660801Y444324D01*
G03X660634Y444369I-130J-152D01*
G02X660366Y444345I-267J1478D01*
G02Y447349I0J1502D01*
G02X661850Y446080I0J-1502D01*
G01X661856Y446038D01*
X661901Y445968D01*
X662218Y445757D01*
X662299Y445743D01*
X662340Y445753D01*
G02X662767Y445804I426J-1751D01*
G02X663132Y445767I2J-1802D01*
G01X663133D01*
G03X663286Y445798I40J196D01*
G01X663558Y445985D01*
X663602Y446055D01*
X663608Y446096D01*
G02X665167Y447424I1559J-251D01*
G37*
G36*
G01X374967Y447571D02*
Y447865D01*
G03X374902Y448012I-200J-1D01*
G02X374417Y449118I1019J1106D01*
G02X377421I1502J0D01*
G02X376936Y448012I-1504J0D01*
G03X376871Y447865I135J-148D01*
G01Y447571D01*
G03X376936Y447424I200J1D01*
G02X377421Y446318I-1019J-1106D01*
G02X374417I-1502J0D01*
G02X374902Y447424I1504J0D01*
G03X374967Y447571I-135J148D01*
G37*
G36*
G01X384632Y454094D02*
Y454388D01*
G03X384567Y454535I-200J-1D01*
G02X384082Y455641I1019J1106D01*
G02X387086I1502J0D01*
G02X386601Y454535I-1504J0D01*
G03X386536Y454388I135J-148D01*
G01Y454094D01*
G03X386601Y453947I200J1D01*
G02Y451735I-1017J-1106D01*
G03X386536Y451588I135J-148D01*
G01Y451294D01*
G03X386601Y451147I200J1D01*
G02X387086Y450041I-1019J-1106D01*
G02X384082I-1502J0D01*
G02X384567Y451147I1504J0D01*
G03X384632Y451294I-135J148D01*
G01Y451588D01*
G03X384567Y451735I-200J-1D01*
G02Y453947I1017J1106D01*
G03X384632Y454094I-135J148D01*
G37*
G36*
G01X394625D02*
Y454388D01*
G03X394560Y454535I-200J-1D01*
G02X394075Y455641I1019J1106D01*
G02X397079I1502J0D01*
G02X396594Y454535I-1504J0D01*
G03X396529Y454388I135J-148D01*
G01Y454094D01*
G03X396594Y453947I200J1D01*
G02Y451735I-1017J-1106D01*
G03X396529Y451588I135J-148D01*
G01Y451294D01*
G03X396594Y451147I200J1D01*
G02X397079Y450041I-1019J-1106D01*
G02X394075I-1502J0D01*
G02X394560Y451147I1504J0D01*
G03X394625Y451294I-135J148D01*
G01Y451588D01*
G03X394560Y451735I-200J-1D01*
G02Y453947I1017J1106D01*
G03X394625Y454094I-135J148D01*
G37*
G36*
G01X604009Y457759D02*
X603715D01*
G03X603568Y457694I1J-200D01*
G02X602462Y457209I-1106J1019D01*
G02Y460213I0J1502D01*
G02X603568Y459728I0J-1504D01*
G03X603715Y459663I148J135D01*
G01X604009D01*
G03X604156Y459728I-1J200D01*
G02X605262Y460213I1106J-1019D01*
G02X606764Y458711I0J-1502D01*
G02X606504Y457867I-1502J1D01*
G01Y457866D01*
X606479Y457830D01*
X606465Y457746D01*
X606569Y457365D01*
X606625Y457299D01*
X606665Y457280D01*
G02X607528Y455921I-639J-1359D01*
G01Y455918D01*
G02X607504Y455652I-1502J1D01*
G01X607496Y455610D01*
X607517Y455527D01*
X607756Y455224D01*
X607832Y455184D01*
X607875Y455182D01*
G02X609291Y453682I-86J-1500D01*
G02X606287I-1502J0D01*
G01Y453685D01*
G02X606311Y453951I1502J-1D01*
G01X606319Y453993D01*
X606298Y454076D01*
X606059Y454379D01*
X605983Y454419D01*
X605940Y454421D01*
G02X604524Y455921I86J1500D01*
G02X604784Y456765I1502J-1D01*
G01Y456766D01*
X604809Y456802D01*
X604823Y456886D01*
X604719Y457267D01*
X604663Y457333D01*
X604623Y457352D01*
G02X604156Y457694I637J1360D01*
G03X604009Y457759I-148J-135D01*
G37*
G36*
G01X906498Y458515D02*
Y458809D01*
G03X906433Y458956I-200J-1D01*
G02X905948Y460062I1019J1106D01*
G02X907450Y461564I1502J0D01*
G02X908556Y461079I0J-1504D01*
G03X908703Y461014I148J135D01*
G01X908997D01*
G03X909144Y461079I-1J200D01*
G02X910250Y461564I1106J-1019D01*
G02X911752Y460062I0J-1502D01*
G02X911267Y458956I-1504J0D01*
G03X911202Y458809I135J-148D01*
G01Y458515D01*
G03X911267Y458368I200J1D01*
G02Y456156I-1017J-1106D01*
G03X911202Y456009I135J-148D01*
G01Y455715D01*
G03X911267Y455568I200J1D01*
G02Y453356I-1017J-1106D01*
G03X911202Y453209I135J-148D01*
G01Y452915D01*
G03X911267Y452768I200J1D01*
G02X911752Y451662I-1019J-1106D01*
G02X910250Y450160I-1502J0D01*
G02X909144Y450645I0J1504D01*
G03X908997Y450710I-148J-135D01*
G01X908703D01*
G03X908556Y450645I1J-200D01*
G02X907450Y450160I-1106J1019D01*
G02X905948Y451662I0J1502D01*
G02X906433Y452768I1504J0D01*
G03X906498Y452915I-135J148D01*
G01Y453209D01*
G03X906433Y453356I-200J-1D01*
G02Y455568I1017J1106D01*
G03X906498Y455715I-135J148D01*
G01Y456009D01*
G03X906433Y456156I-200J-1D01*
G02Y458368I1017J1106D01*
G03X906498Y458515I-135J148D01*
G37*
G36*
G01X879958Y458687D02*
Y458981D01*
G03X879893Y459128I-200J-1D01*
G02X879408Y460234I1019J1106D01*
G02X882412I1502J0D01*
G02X881927Y459128I-1504J0D01*
G03X881862Y458981I135J-148D01*
G01Y458687D01*
G03X881927Y458540I200J1D01*
G02Y456328I-1017J-1106D01*
G03X881862Y456181I135J-148D01*
G01Y455887D01*
G03X881927Y455740I200J1D01*
G02X882412Y454634I-1019J-1106D01*
G02X879408I-1502J0D01*
G02X879893Y455740I1504J0D01*
G03X879958Y455887I-135J148D01*
G01Y456181D01*
G03X879893Y456328I-200J-1D01*
G02Y458540I1017J1106D01*
G03X879958Y458687I-135J148D01*
G37*
G36*
G01X889951D02*
Y458981D01*
G03X889886Y459128I-200J-1D01*
G02X889401Y460234I1019J1106D01*
G02X892405I1502J0D01*
G02X891920Y459128I-1504J0D01*
G03X891855Y458981I135J-148D01*
G01Y458687D01*
G03X891920Y458540I200J1D01*
G02Y456328I-1017J-1106D01*
G03X891855Y456181I135J-148D01*
G01Y455887D01*
G03X891920Y455740I200J1D01*
G02X892405Y454634I-1019J-1106D01*
G02X889401I-1502J0D01*
G02X889886Y455740I1504J0D01*
G03X889951Y455887I-135J148D01*
G01Y456181D01*
G03X889886Y456328I-200J-1D01*
G02Y458540I1017J1106D01*
G03X889951Y458687I-135J148D01*
G37*
G36*
G01X463783Y459589D02*
X463469D01*
G03X463311Y459512I0J-200D01*
G02X462126Y458933I-1185J923D01*
G02Y461937I0J1502D01*
G02X463311Y461358I0J-1502D01*
G03X463469Y461281I158J123D01*
G01X463783D01*
G03X463941Y461358I0J200D01*
G02X465126Y461937I1185J-923D01*
G02Y458933I0J-1502D01*
G02X463941Y459512I0J1502D01*
G03X463783Y459589I-158J-123D01*
G37*
G36*
G01X853930Y460244D02*
Y460538D01*
G03X853865Y460685I-200J-1D01*
G02X853380Y461791I1019J1106D01*
G02X856384I1502J0D01*
G02X855899Y460685I-1504J0D01*
G03X855834Y460538I135J-148D01*
G01Y460244D01*
G03X855899Y460097I200J1D01*
G02X856384Y458991I-1019J-1106D01*
G02X853380I-1502J0D01*
G02X853865Y460097I1504J0D01*
G03X853930Y460244I-135J148D01*
G37*
G36*
G01X861930D02*
Y460538D01*
G03X861865Y460685I-200J-1D01*
G02X861380Y461791I1019J1106D01*
G02X864384I1502J0D01*
G02X863899Y460685I-1504J0D01*
G03X863834Y460538I135J-148D01*
G01Y460244D01*
G03X863899Y460097I200J1D01*
G02X864384Y458991I-1019J-1106D01*
G02X861380I-1502J0D01*
G02X861865Y460097I1504J0D01*
G03X861930Y460244I-135J148D01*
G37*
G36*
G01X869930D02*
Y460538D01*
G03X869865Y460685I-200J-1D01*
G02X869380Y461791I1019J1106D01*
G02X872384I1502J0D01*
G02X871899Y460685I-1504J0D01*
G03X871834Y460538I135J-148D01*
G01Y460244D01*
G03X871899Y460097I200J1D01*
G02X872384Y458991I-1019J-1106D01*
G02X869380I-1502J0D01*
G02X869865Y460097I1504J0D01*
G03X869930Y460244I-135J148D01*
G37*
G36*
G01X983801Y464652D02*
G02X985303Y466154I1502J0D01*
G02X986290Y465784I0J-1501D01*
G01X986291D01*
Y465783D01*
G03X986421Y465735I130J152D01*
G01X986685D01*
G03X986815Y465783I0J200D01*
G01X986816Y465784D01*
G02X987803Y466154I987J-1131D01*
G02X989305Y464652I0J-1502D01*
G02X988935Y463665I-1501J0D01*
G01Y463664D01*
X988934D01*
G03X988886Y463534I152J-130D01*
G01Y463270D01*
G03X988934Y463140I200J0D01*
G01X988935Y463139D01*
G02Y461165I-1131J-987D01*
G01Y461164D01*
X988934D01*
G03X988886Y461034I152J-130D01*
G01Y460770D01*
G03X988934Y460640I200J0D01*
G01X988935Y460639D01*
G02X989305Y459652I-1131J-987D01*
G02X987803Y458150I-1502J0D01*
G02X986816Y458520I0J1501D01*
G01X986815D01*
Y458521D01*
G03X986685Y458569I-130J-152D01*
G01X986421D01*
G03X986291Y458521I0J-200D01*
G01X986290Y458520D01*
G02X985303Y458150I-987J1131D01*
G02X983801Y459652I0J1502D01*
G02X984171Y460639I1501J0D01*
G01Y460640D01*
X984172D01*
G03X984220Y460770I-152J130D01*
G01Y461034D01*
G03X984172Y461164I-200J0D01*
G01X984171Y461165D01*
G02Y463139I1131J987D01*
G01Y463140D01*
X984172D01*
G03X984220Y463270I-152J130D01*
G01Y463534D01*
G03X984172Y463664I-200J0D01*
G01X984171Y463665D01*
G02X983801Y464652I1131J987D01*
G37*
G36*
G01X368330Y466541D02*
Y466835D01*
G03X368265Y466982I-200J-1D01*
G02X367780Y468088I1019J1106D01*
G02X370784I1502J0D01*
G02X370299Y466982I-1504J0D01*
G03X370234Y466835I135J-148D01*
G01Y466541D01*
G03X370299Y466394I200J1D01*
G02X370784Y465288I-1019J-1106D01*
G02X367780I-1502J0D01*
G02X368265Y466394I1504J0D01*
G03X368330Y466541I-135J148D01*
G37*
G36*
G01X853930Y467244D02*
Y467538D01*
G03X853865Y467685I-200J-1D01*
G02X853380Y468791I1019J1106D01*
G02X856384I1502J0D01*
G02X855899Y467685I-1504J0D01*
G03X855834Y467538I135J-148D01*
G01Y467244D01*
G03X855899Y467097I200J1D01*
G02X856384Y465991I-1019J-1106D01*
G02X853380I-1502J0D01*
G02X853865Y467097I1504J0D01*
G03X853930Y467244I-135J148D01*
G37*
G36*
G01X861930D02*
Y467538D01*
G03X861865Y467685I-200J-1D01*
G02X861380Y468791I1019J1106D01*
G02X864384I1502J0D01*
G02X863899Y467685I-1504J0D01*
G03X863834Y467538I135J-148D01*
G01Y467244D01*
G03X863899Y467097I200J1D01*
G02X864384Y465991I-1019J-1106D01*
G02X861380I-1502J0D01*
G02X861865Y467097I1504J0D01*
G03X861930Y467244I-135J148D01*
G37*
G36*
G01X869930D02*
Y467538D01*
G03X869865Y467685I-200J-1D01*
G02X869380Y468791I1019J1106D01*
G02X872384I1502J0D01*
G02X871899Y467685I-1504J0D01*
G03X871834Y467538I135J-148D01*
G01Y467244D01*
G03X871899Y467097I200J1D01*
G02X872384Y465991I-1019J-1106D01*
G02X869380I-1502J0D01*
G02X869865Y467097I1504J0D01*
G03X869930Y467244I-135J148D01*
G37*
G36*
G01X373546Y468499D02*
G02Y471503I0J1502D01*
G02X374533Y471133I0J-1501D01*
G01X374534D01*
Y471132D01*
G03X374664Y471084I130J152D01*
G01X374928D01*
G03X375058Y471132I0J200D01*
G01X375059Y471133D01*
G02X376046Y471503I987J-1131D01*
G02Y468499I0J-1502D01*
G02X375059Y468869I0J1501D01*
G01X375058D01*
Y468870D01*
G03X374928Y468918I-130J-152D01*
G01X374664D01*
G03X374534Y468870I0J-200D01*
G01X374533Y468869D01*
G02X373546Y468499I-987J1131D01*
G37*
G36*
G01X879958Y470435D02*
Y470729D01*
G03X879893Y470876I-200J-1D01*
G02X879408Y471982I1019J1106D01*
G02X882412I1502J0D01*
G02X881927Y470876I-1504J0D01*
G03X881862Y470729I135J-148D01*
G01Y470435D01*
G03X881927Y470288I200J1D01*
G02Y468076I-1017J-1106D01*
G03X881862Y467929I135J-148D01*
G01Y467635D01*
G03X881927Y467488I200J1D01*
G02X882412Y466382I-1019J-1106D01*
G02X879408I-1502J0D01*
G02X879893Y467488I1504J0D01*
G03X879958Y467635I-135J148D01*
G01Y467929D01*
G03X879893Y468076I-200J-1D01*
G02Y470288I1017J1106D01*
G03X879958Y470435I-135J148D01*
G37*
G36*
G01X889951D02*
Y470729D01*
G03X889886Y470876I-200J-1D01*
G02X889401Y471982I1019J1106D01*
G02X892405I1502J0D01*
G02X891920Y470876I-1504J0D01*
G03X891855Y470729I135J-148D01*
G01Y470435D01*
G03X891920Y470288I200J1D01*
G02Y468076I-1017J-1106D01*
G03X891855Y467929I135J-148D01*
G01Y467635D01*
G03X891920Y467488I200J1D01*
G02X892405Y466382I-1019J-1106D01*
G02X889401I-1502J0D01*
G02X889886Y467488I1504J0D01*
G03X889951Y467635I-135J148D01*
G01Y467929D01*
G03X889886Y468076I-200J-1D01*
G02Y470288I1017J1106D01*
G03X889951Y470435I-135J148D01*
G37*
G36*
G01X594286Y474397D02*
X594404Y474368D01*
G03X594543Y474385I47J195D01*
G02X595377Y474590I835J-1598D01*
G02X596211Y474385I-1J-1803D01*
G03X596350Y474368I92J178D01*
G01X596468Y474397D01*
G03X596584Y474476I-47J194D01*
G02X597873Y475144I1289J-910D01*
G02Y471986I0J-1579D01*
G02X597639Y472004I4J1579D01*
G01X597595Y472011D01*
X597512Y471987D01*
X597249Y471760D01*
G03X597180Y471608I131J-151D01*
G01Y470566D01*
G03X597249Y470414I200J-1D01*
G01X597512Y470187D01*
X597595Y470163D01*
X597639Y470170D01*
G02X597873Y470188I238J-1561D01*
G02Y467030I0J-1579D01*
G02X596584Y467698I0J1578D01*
G03X596468Y467777I-163J-115D01*
G01X596350Y467806D01*
G03X596211Y467789I-47J-195D01*
G02X595377Y467584I-835J1598D01*
G02X594543Y467789I1J1803D01*
G03X594404Y467806I-92J-178D01*
G01X594286Y467777D01*
G03X594170Y467698I47J-194D01*
G02X592881Y467030I-1289J910D01*
G02Y470188I0J1579D01*
G02X593115Y470170I-4J-1579D01*
G01X593159Y470163D01*
X593242Y470187D01*
X593505Y470414D01*
G03X593574Y470566I-131J151D01*
G01Y471608D01*
G03X593505Y471760I-200J1D01*
G01X593242Y471987D01*
X593159Y472011D01*
X593115Y472004D01*
G02X592881Y471986I-238J1561D01*
G02Y475144I0J1579D01*
G02X594170Y474476I0J-1578D01*
G03X594286Y474397I163J115D01*
G37*
G36*
G01X1051372D02*
X1051490Y474368D01*
G03X1051629Y474385I47J195D01*
G02X1052463Y474590I835J-1598D01*
G02X1053297Y474385I-1J-1803D01*
G03X1053436Y474368I92J178D01*
G01X1053554Y474397D01*
G03X1053670Y474476I-47J194D01*
G02X1054959Y475144I1289J-910D01*
G02Y471986I0J-1579D01*
G02X1054725Y472004I4J1579D01*
G01X1054681Y472011D01*
X1054598Y471987D01*
X1054335Y471760D01*
G03X1054266Y471608I131J-151D01*
G01Y470566D01*
G03X1054335Y470414I200J-1D01*
G01X1054598Y470187D01*
X1054681Y470163D01*
X1054725Y470170D01*
G02X1054959Y470188I238J-1561D01*
G02Y467030I0J-1579D01*
G02X1053670Y467698I0J1578D01*
G03X1053554Y467777I-163J-115D01*
G01X1053436Y467806D01*
G03X1053297Y467789I-47J-195D01*
G02X1052463Y467584I-835J1598D01*
G02X1051629Y467789I1J1803D01*
G03X1051490Y467806I-92J-178D01*
G01X1051372Y467777D01*
G03X1051256Y467698I47J-194D01*
G02X1049967Y467030I-1289J910D01*
G02Y470188I0J1579D01*
G02X1050201Y470170I-4J-1579D01*
G01X1050245Y470163D01*
X1050328Y470187D01*
X1050591Y470414D01*
G03X1050660Y470566I-131J151D01*
G01Y471608D01*
G03X1050591Y471760I-200J1D01*
G01X1050328Y471987D01*
X1050245Y472011D01*
X1050201Y472004D01*
G02X1049967Y471986I-238J1561D01*
G02Y475144I0J1579D01*
G02X1051256Y474476I0J-1578D01*
G03X1051372Y474397I163J115D01*
G37*
G36*
G01X823544Y476563D02*
G02X825046Y475061I0J-1502D01*
G02X824676Y474074I-1501J0D01*
G01Y474073D01*
X824675D01*
G03X824627Y473943I152J-130D01*
G01Y473679D01*
G03X824675Y473549I200J0D01*
G01X824676Y473548D01*
G02X825046Y472561I-1131J-987D01*
G02X823544Y471059I-1502J0D01*
G02X822859Y471225I1J1502D01*
G01X822857D01*
G03X822680Y471227I-91J-178D01*
G01X822349Y471068D01*
X822292Y470994D01*
X822283Y470948D01*
G02X820810Y469741I-1473J295D01*
G02X819308Y471243I0J1502D01*
G02X819678Y472230I1501J0D01*
G01Y472231D01*
X819679D01*
G03X819727Y472361I-152J130D01*
G01Y472625D01*
G03X819679Y472755I-200J0D01*
G01X819678Y472756D01*
G02X819308Y473743I1131J987D01*
G02X820810Y475245I1502J0D01*
G02X821495Y475079I-1J-1502D01*
G01X821497D01*
G03X821674Y475077I91J178D01*
G01X822005Y475236D01*
X822062Y475310D01*
X822071Y475356D01*
G02X823544Y476563I1473J-295D01*
G37*
G36*
G01X809254Y476071D02*
G02X812258I1502J0D01*
G02X811888Y475084I-1501J0D01*
G01Y475083D01*
X811887D01*
G03X811839Y474953I152J-130D01*
G01Y474689D01*
G03X811887Y474559I200J0D01*
G01X811888Y474558D01*
G02Y472584I-1131J-987D01*
G01Y472583D01*
X811887D01*
G03X811839Y472453I152J-130D01*
G01Y472189D01*
G03X811887Y472059I200J0D01*
G01X811888Y472058D01*
G02Y470084I-1131J-987D01*
G01Y470083D01*
X811887D01*
G03X811839Y469953I152J-130D01*
G01Y469689D01*
G03X811887Y469559I200J0D01*
G01X811888Y469558D01*
G02X812258Y468571I-1131J-987D01*
G02X809254I-1502J0D01*
G02X809624Y469558I1501J0D01*
G01Y469559D01*
X809625D01*
G03X809673Y469689I-152J130D01*
G01Y469953D01*
G03X809625Y470083I-200J0D01*
G01X809624Y470084D01*
G02Y472058I1131J987D01*
G01Y472059D01*
X809625D01*
G03X809673Y472189I-152J130D01*
G01Y472453D01*
G03X809625Y472583I-200J0D01*
G01X809624Y472584D01*
G02Y474558I1131J987D01*
G01Y474559D01*
X809625D01*
G03X809673Y474689I-152J130D01*
G01Y474953D01*
G03X809625Y475083I-200J0D01*
G01X809624Y475084D01*
G02X809254Y476071I1131J987D01*
G37*
G36*
G01X366420Y481488D02*
G02X367922Y479986I0J-1502D01*
G02X367552Y478999I-1501J0D01*
G01Y478998D01*
X367551D01*
G03X367503Y478868I152J-130D01*
G01Y478604D01*
G03X367551Y478474I200J0D01*
G01X367552Y478473D01*
G02X367922Y477486I-1131J-987D01*
G02X366420Y475984I-1502J0D01*
G02X365735Y476150I1J1502D01*
G01X365733D01*
G03X365556Y476152I-91J-178D01*
G01X365225Y475993D01*
X365168Y475919D01*
X365159Y475873D01*
G02X363686Y474666I-1473J295D01*
G02X362184Y476168I0J1502D01*
G02X362554Y477155I1501J0D01*
G01Y477156D01*
X362555D01*
G03X362603Y477286I-152J130D01*
G01Y477550D01*
G03X362555Y477680I-200J0D01*
G01X362554Y477681D01*
G02X362184Y478668I1131J987D01*
G02X363686Y480170I1502J0D01*
G02X364371Y480004I-1J-1502D01*
G01X364373D01*
G03X364550Y480002I91J178D01*
G01X364881Y480161D01*
X364938Y480235D01*
X364947Y480281D01*
G02X366420Y481488I1473J-295D01*
G37*
G36*
G01X832405Y481712D02*
X832406Y481711D01*
G03X832536Y481663I130J152D01*
G01X832800D01*
G03X832930Y481711I0J200D01*
G01X832931Y481712D01*
G02X833918Y482082I987J-1131D01*
G02Y479078I0J-1502D01*
G02X832931Y479448I0J1501D01*
G01X832930D01*
Y479449D01*
G03X832800Y479497I-130J-152D01*
G01X832536D01*
G03X832406Y479449I0J-200D01*
G01X832405Y479448D01*
G02X830431I-987J1131D01*
G01X830430D01*
Y479449D01*
G03X830300Y479497I-130J-152D01*
G01X830036D01*
G03X829906Y479449I0J-200D01*
G01X829905Y479448D01*
G02X828918Y479078I-987J1131D01*
G02Y482082I0J1502D01*
G02X829905Y481712I0J-1501D01*
G01X829906D01*
Y481711D01*
G03X830036Y481663I130J152D01*
G01X830300D01*
G03X830430Y481711I0J200D01*
G01X830431Y481712D01*
G02X832405I987J-1131D01*
G37*
G36*
G01X984197Y480705D02*
G02X985699Y482207I1502J0D01*
G02X986805Y481722I0J-1504D01*
G03X986952Y481657I148J135D01*
G01X987246D01*
G03X987393Y481722I-1J200D01*
G02X988499Y482207I1106J-1019D01*
G02Y479203I0J-1502D01*
G02X987393Y479688I0J1504D01*
G03X987246Y479753I-148J-135D01*
G01X986952D01*
G03X986805Y479688I1J-200D01*
G02X985823Y479208I-1105J1017D01*
G01X985780Y479205D01*
X985706Y479164D01*
X985500Y478892D01*
G03X985463Y478733I159J-121D01*
G02X985491Y478446I-1474J-289D01*
G02X985121Y477459I-1501J0D01*
G01Y477458D01*
X985120D01*
G03X985072Y477328I152J-130D01*
G01Y477064D01*
G03X985120Y476934I200J0D01*
G01X985121Y476933D01*
G02X985491Y475946I-1131J-987D01*
G02X982487I-1502J0D01*
G02X982857Y476933I1501J0D01*
G01Y476934D01*
X982858D01*
G03X982906Y477064I-152J130D01*
G01Y477328D01*
G03X982858Y477458I-200J0D01*
G01X982857Y477459D01*
G02X982487Y478446I1131J987D01*
G02X983865Y479943I1502J0D01*
G01X983908Y479946D01*
X983982Y479987D01*
X984188Y480259D01*
G03X984225Y480418I-159J121D01*
G02X984197Y480705I1474J289D01*
G37*
G36*
G01X604688Y481509D02*
X604806Y481480D01*
G03X604945Y481497I47J195D01*
G02X605779Y481702I835J-1598D01*
G02X606613Y481497I-1J-1803D01*
G03X606752Y481480I92J178D01*
G01X606870Y481509D01*
G03X606986Y481588I-47J194D01*
G02X608275Y482256I1289J-910D01*
G02Y479098I0J-1579D01*
G02X608041Y479116I4J1579D01*
G01X607997Y479123D01*
X607914Y479099D01*
X607651Y478872D01*
G03X607582Y478720I131J-151D01*
G01Y477678D01*
G03X607651Y477526I200J-1D01*
G01X607914Y477299D01*
X607997Y477275D01*
X608041Y477282D01*
G02X608275Y477300I238J-1561D01*
G02Y474142I0J-1579D01*
G02X606986Y474810I0J1578D01*
G03X606870Y474889I-163J-115D01*
G01X606752Y474918D01*
G03X606613Y474901I-47J-195D01*
G02X605779Y474696I-835J1598D01*
G02X604945Y474901I1J1803D01*
G03X604806Y474918I-92J-178D01*
G01X604688Y474889D01*
G03X604572Y474810I47J-194D01*
G02X603283Y474142I-1289J910D01*
G02Y477300I0J1579D01*
G02X603517Y477282I-4J-1579D01*
G01X603561Y477275D01*
X603644Y477299D01*
X603907Y477526D01*
G03X603976Y477678I-131J151D01*
G01Y478720D01*
G03X603907Y478872I-200J1D01*
G01X603644Y479099D01*
X603561Y479123D01*
X603517Y479116D01*
G02X603283Y479098I-238J1561D01*
G02Y482256I0J1579D01*
G02X604572Y481588I0J-1578D01*
G03X604688Y481509I163J115D01*
G37*
G36*
G01X1061774D02*
X1061892Y481480D01*
G03X1062031Y481497I47J195D01*
G02X1062865Y481702I835J-1598D01*
G02X1063699Y481497I-1J-1803D01*
G03X1063838Y481480I92J178D01*
G01X1063956Y481509D01*
G03X1064072Y481588I-47J194D01*
G02X1065361Y482256I1289J-910D01*
G02Y479098I0J-1579D01*
G02X1065127Y479116I4J1579D01*
G01X1065083Y479123D01*
X1065000Y479099D01*
X1064737Y478872D01*
G03X1064668Y478720I131J-151D01*
G01Y477678D01*
G03X1064737Y477526I200J-1D01*
G01X1065000Y477299D01*
X1065083Y477275D01*
X1065127Y477282D01*
G02X1065361Y477300I238J-1561D01*
G02Y474142I0J-1579D01*
G02X1064072Y474810I0J1578D01*
G03X1063956Y474889I-163J-115D01*
G01X1063838Y474918D01*
G03X1063699Y474901I-47J-195D01*
G02X1062865Y474696I-835J1598D01*
G02X1062031Y474901I1J1803D01*
G03X1061892Y474918I-92J-178D01*
G01X1061774Y474889D01*
G03X1061658Y474810I47J-194D01*
G02X1060369Y474142I-1289J910D01*
G02Y477300I0J1579D01*
G02X1060603Y477282I-4J-1579D01*
G01X1060647Y477275D01*
X1060730Y477299D01*
X1060993Y477526D01*
G03X1061062Y477678I-131J151D01*
G01Y478720D01*
G03X1060993Y478872I-200J1D01*
G01X1060730Y479099D01*
X1060647Y479123D01*
X1060603Y479116D01*
G02X1060369Y479098I-238J1561D01*
G02Y482256I0J1579D01*
G02X1061658Y481588I0J-1578D01*
G03X1061774Y481509I163J115D01*
G37*
G36*
G01X991254Y482339D02*
Y482633D01*
G03X991189Y482780I-200J-1D01*
G02X990704Y483886I1019J1106D01*
G02X993708I1502J0D01*
G02X993223Y482780I-1504J0D01*
G03X993158Y482633I135J-148D01*
G01Y482339D01*
G03X993223Y482192I200J1D01*
G02X993708Y481086I-1019J-1106D01*
G02X993338Y480099I-1501J0D01*
G01Y480098D01*
X993337D01*
G03X993289Y479968I152J-130D01*
G01Y479704D01*
G03X993337Y479574I200J0D01*
G01X993338Y479573D01*
G02Y477599I-1131J-987D01*
G01Y477598D01*
X993337D01*
G03X993289Y477468I152J-130D01*
G01Y477204D01*
G03X993337Y477074I200J0D01*
G01X993338Y477073D01*
G02X993708Y476086I-1131J-987D01*
G02X990704I-1502J0D01*
G02X991074Y477073I1501J0D01*
G01Y477074D01*
X991075D01*
G03X991123Y477204I-152J130D01*
G01Y477468D01*
G03X991075Y477598I-200J0D01*
G01X991074Y477599D01*
G02Y479573I1131J987D01*
G01Y479574D01*
X991075D01*
G03X991123Y479704I-152J130D01*
G01Y479968D01*
G03X991075Y480098I-200J0D01*
G01X991074Y480099D01*
G02X990704Y481086I1131J987D01*
G02X991189Y482192I1504J0D01*
G03X991254Y482339I-135J148D01*
G37*
G36*
G01X979042Y484634D02*
G02X982046I1502J0D01*
G02X981676Y483647I-1501J0D01*
G01Y483646D01*
X981675D01*
G03X981627Y483516I152J-130D01*
G01Y483252D01*
G03X981675Y483122I200J0D01*
G01X981676Y483121D01*
G02X982046Y482134I-1131J-987D01*
G02X979042I-1502J0D01*
G02X979412Y483121I1501J0D01*
G01Y483122D01*
X979413D01*
G03X979461Y483252I-152J130D01*
G01Y483516D01*
G03X979413Y483646I-200J0D01*
G01X979412Y483647D01*
G02X979042Y484634I1131J987D01*
G37*
G36*
G01X968899Y486270D02*
X968900Y486269D01*
G03X969030Y486221I130J152D01*
G01X969294D01*
G03X969424Y486269I0J200D01*
G01X969425Y486270D01*
G02X970412Y486640I987J-1131D01*
G02X971914Y485138I0J-1502D01*
G02X971647Y484283I-1502J0D01*
G01X971624Y484249D01*
X971607Y484168D01*
X971687Y483801D01*
X971735Y483734D01*
X971770Y483713D01*
G02X972499Y482425I-773J-1288D01*
G02X969495I-1502J0D01*
G02X969762Y483280I1502J0D01*
G01X969785Y483314D01*
X969802Y483395D01*
X969722Y483762D01*
X969674Y483829D01*
X969639Y483850D01*
G02X969426Y484006I777J1285D01*
G03X969424Y484007I-88J-173D01*
G03X969294Y484055I-130J-152D01*
G01X969030D01*
G03X968900Y484007I0J-200D01*
G01X968899Y484006D01*
G02X966925I-987J1131D01*
G01X966924D01*
Y484007D01*
G03X966794Y484055I-130J-152D01*
G01X966530D01*
G03X966400Y484007I0J-200D01*
G01X966399Y484006D01*
G02X965412Y483636I-987J1131D01*
G02X964291Y484139I0J1501D01*
G01X964262Y484172D01*
X964185Y484206D01*
X963840Y484204D01*
G03X963692Y484138I0J-200D01*
G01X963691Y484137D01*
G02X962563Y483626I-1129J991D01*
G02Y486630I0J1502D01*
G02X963684Y486127I0J-1501D01*
G01X963713Y486094D01*
X963790Y486060D01*
X964135Y486062D01*
G03X964283Y486128I0J200D01*
G01X964284Y486129D01*
G02X965412Y486640I1129J-991D01*
G02X966399Y486270I0J-1501D01*
G01X966400D01*
Y486269D01*
G03X966530Y486221I130J152D01*
G01X966794D01*
G03X966924Y486269I0J200D01*
G01X966925Y486270D01*
G02X968899I987J-1131D01*
G37*
G36*
G01X375319Y486712D02*
X375320Y486711D01*
G03X375450Y486663I130J152D01*
G01X375714D01*
G03X375844Y486711I0J200D01*
G01X375845Y486712D01*
G02X376832Y487082I987J-1131D01*
G02Y484078I0J-1502D01*
G02X375845Y484448I0J1501D01*
G01X375844D01*
Y484449D01*
G03X375714Y484497I-130J-152D01*
G01X375450D01*
G03X375320Y484449I0J-200D01*
G01X375319Y484448D01*
G02X373345I-987J1131D01*
G01X373344D01*
Y484449D01*
G03X373214Y484497I-130J-152D01*
G01X372950D01*
G03X372820Y484449I0J-200D01*
G01X372819Y484448D01*
G02X371832Y484078I-987J1131D01*
G02Y487082I0J1502D01*
G02X372819Y486712I0J-1501D01*
G01X372820D01*
Y486711D01*
G03X372950Y486663I130J152D01*
G01X373214D01*
G03X373344Y486711I0J200D01*
G01X373345Y486712D01*
G02X375319I987J-1131D01*
G37*
G36*
G01X595377Y488762D02*
G02X596211Y488558I1J-1802D01*
G03X596350Y488541I92J178D01*
G01X596468Y488570D01*
G03X596584Y488649I-47J194D01*
G02X597873Y489316I1289J-912D01*
G02Y486160I0J-1578D01*
G02X597639Y486177I-3J1578D01*
G01X597595Y486184D01*
X597512Y486160D01*
X597249Y485933D01*
G03X597180Y485781I131J-151D01*
G01Y484739D01*
G03X597249Y484587I200J-1D01*
G01X597512Y484360D01*
X597595Y484336D01*
X597639Y484343D01*
G02X597873Y484360I231J-1561D01*
G02Y481204I0J-1578D01*
G02X596584Y481871I0J1579D01*
G03X596468Y481950I-163J-115D01*
G01X596350Y481979D01*
G03X596211Y481962I-47J-195D01*
G02X595377Y481758I-833J1598D01*
G02X594543Y481962I-1J1802D01*
G03X594404Y481979I-92J-178D01*
G01X594286Y481950D01*
G03X594170Y481871I47J-194D01*
G02X592881Y481204I-1289J912D01*
G02Y484360I0J1578D01*
G02X593115Y484343I3J-1578D01*
G01X593159Y484336D01*
X593242Y484360D01*
X593505Y484587D01*
G03X593574Y484739I-131J151D01*
G01Y485781D01*
G03X593505Y485933I-200J1D01*
G01X593242Y486160D01*
X593159Y486184D01*
X593115Y486177D01*
G02X592881Y486160I-231J1561D01*
G02Y489316I0J1578D01*
G02X594170Y488649I0J-1579D01*
G03X594286Y488570I163J115D01*
G01X594404Y488541D01*
G03X594543Y488558I47J195D01*
G02X595377Y488762I833J-1598D01*
G37*
G36*
G01X1052463D02*
G02X1053297Y488558I1J-1802D01*
G03X1053436Y488541I92J178D01*
G01X1053554Y488570D01*
G03X1053670Y488649I-47J194D01*
G02X1054959Y489316I1289J-912D01*
G02Y486160I0J-1578D01*
G02X1054725Y486177I-3J1578D01*
G01X1054681Y486184D01*
X1054598Y486160D01*
X1054335Y485933D01*
G03X1054266Y485781I131J-151D01*
G01Y484739D01*
G03X1054335Y484587I200J-1D01*
G01X1054598Y484360D01*
X1054681Y484336D01*
X1054725Y484343D01*
G02X1054959Y484360I231J-1561D01*
G02Y481204I0J-1578D01*
G02X1053670Y481871I0J1579D01*
G03X1053554Y481950I-163J-115D01*
G01X1053436Y481979D01*
G03X1053297Y481962I-47J-195D01*
G02X1052463Y481758I-833J1598D01*
G02X1051629Y481962I-1J1802D01*
G03X1051490Y481979I-92J-178D01*
G01X1051372Y481950D01*
G03X1051256Y481871I47J-194D01*
G02X1049967Y481204I-1289J912D01*
G02Y484360I0J1578D01*
G02X1050201Y484343I3J-1578D01*
G01X1050245Y484336D01*
X1050328Y484360D01*
X1050591Y484587D01*
G03X1050660Y484739I-131J151D01*
G01Y485781D01*
G03X1050591Y485933I-200J1D01*
G01X1050328Y486160D01*
X1050245Y486184D01*
X1050201Y486177D01*
G02X1049967Y486160I-231J1561D01*
G02Y489316I0J1578D01*
G02X1051256Y488649I0J-1579D01*
G03X1051372Y488570I163J115D01*
G01X1051490Y488541D01*
G03X1051629Y488558I47J195D01*
G02X1052463Y488762I833J-1598D01*
G37*
G36*
G01X363830Y490070D02*
G02X366834I1502J0D01*
G02X366464Y489083I-1501J0D01*
G01Y489082D01*
X366463D01*
G03X366415Y488952I152J-130D01*
G01Y488688D01*
G03X366463Y488558I200J0D01*
G01X366464Y488557D01*
G02X366834Y487570I-1131J-987D01*
G02X363830I-1502J0D01*
G02X364200Y488557I1501J0D01*
G01Y488558D01*
X364201D01*
G03X364249Y488688I-152J130D01*
G01Y488952D01*
G03X364201Y489082I-200J0D01*
G01X364200Y489083D01*
G02X363830Y490070I1131J987D01*
G37*
G36*
G01X832341Y489089D02*
Y489383D01*
G03X832276Y489530I-200J-1D01*
G02X831791Y490636I1019J1106D01*
G02X834795I1502J0D01*
G02X834310Y489530I-1504J0D01*
G03X834245Y489383I135J-148D01*
G01Y489089D01*
G03X834310Y488942I200J1D01*
G02X834795Y487836I-1019J-1106D01*
G02X831791I-1502J0D01*
G02X832276Y488942I1504J0D01*
G03X832341Y489089I-135J148D01*
G37*
G36*
G01X948321Y491982D02*
G02X949823Y493484I1502J0D01*
G02X951257Y492429I0J-1502D01*
G01Y492427D01*
G03X951306Y492347I190J62D01*
G01X953083Y490570D01*
G02X953466Y489646I-923J-924D01*
G01Y483343D01*
G03X953537Y483190I200J0D01*
G01X953804Y482964D01*
X953888Y482941D01*
X953932Y482948D01*
G02X954182Y482969I250J-1481D01*
G02Y479965I0J-1502D01*
G02X953932Y479986I0J1502D01*
G01X953888Y479993D01*
X953804Y479970D01*
X953537Y479744D01*
G03X953466Y479591I129J-153D01*
G01Y477700D01*
G03X953525Y477558I200J0D01*
G01X956181Y474902D01*
G03X956261Y474853I142J141D01*
G01X956262D01*
G02X957318Y473419I-446J-1434D01*
G02X955816Y471917I-1502J0D01*
G02X954382Y472972I0J1502D01*
G01Y472974D01*
G03X954333Y473054I-190J-62D01*
G01X951235Y476152D01*
G02X950887Y476778I924J924D01*
G01Y476780D01*
G03X950789Y476909I-195J-46D01*
G01X950491Y477073D01*
X950408Y477080D01*
X950367Y477066D01*
G02X949879Y476984I-490J1420D01*
G01X949876D01*
G02Y479988I0J1502D01*
G02X950330Y479917I-2J-1502D01*
G01X950332D01*
G03X950509Y479946I60J191D01*
G01X950770Y480137D01*
G03X950852Y480299I-118J161D01*
G01Y482188D01*
G03X950768Y482351I-200J0D01*
G01X950502Y482539D01*
G03X950321Y482565I-116J-163D01*
G01X950320D01*
G02X949823Y482480I-498J1417D01*
G02Y485484I0J1502D01*
G02X950320Y485399I-1J-1502D01*
G01X950321D01*
G03X950502Y485425I65J189D01*
G01X950768Y485613D01*
G03X950852Y485776I-116J163D01*
G01Y486188D01*
G03X950768Y486351I-200J0D01*
G01X950502Y486539D01*
G03X950321Y486565I-116J-163D01*
G01X950320D01*
G02X949823Y486480I-498J1417D01*
G02X948321Y487982I0J1502D01*
G02X949592Y489466I1502J0D01*
G01X949648Y489475D01*
X949734Y489548D01*
X949862Y489940D01*
G03X949813Y490144I-190J62D01*
G01X949458Y490499D01*
G03X949378Y490548I-142J-141D01*
G01X949377D01*
G02X948321Y491982I446J1434D01*
G37*
G36*
G01X975371Y493714D02*
G02X978375I1502J0D01*
G02X978005Y492727I-1501J0D01*
G01Y492726D01*
X978004D01*
G03X977956Y492596I152J-130D01*
G01Y492332D01*
G03X978004Y492202I200J0D01*
G01X978005Y492201D01*
G02X978375Y491214I-1131J-987D01*
G02X975371I-1502J0D01*
G02X975741Y492201I1501J0D01*
G01Y492202D01*
X975742D01*
G03X975790Y492332I-152J130D01*
G01Y492596D01*
G03X975742Y492726I-200J0D01*
G01X975741Y492727D01*
G02X975371Y493714I1131J987D01*
G37*
G36*
G01X604688Y495683D02*
X604806Y495654D01*
G03X604945Y495671I47J195D01*
G02X605779Y495876I835J-1598D01*
G02X606613Y495671I-1J-1803D01*
G03X606752Y495654I92J178D01*
G01X606870Y495683D01*
G03X606986Y495762I-47J194D01*
G02X608275Y496430I1289J-910D01*
G02Y493272I0J-1579D01*
G02X608041Y493290I4J1579D01*
G01X607997Y493297D01*
X607914Y493273D01*
X607651Y493046D01*
G03X607582Y492894I131J-151D01*
G01Y491852D01*
G03X607651Y491700I200J-1D01*
G01X607914Y491473D01*
X607997Y491449D01*
X608041Y491456D01*
G02X608275Y491474I238J-1561D01*
G02Y488316I0J-1579D01*
G02X606986Y488984I0J1578D01*
G03X606870Y489063I-163J-115D01*
G01X606752Y489092D01*
G03X606613Y489075I-47J-195D01*
G02X605779Y488870I-835J1598D01*
G02X604945Y489075I1J1803D01*
G03X604806Y489092I-92J-178D01*
G01X604688Y489063D01*
G03X604572Y488984I47J-194D01*
G02X603283Y488316I-1289J910D01*
G02Y491474I0J1579D01*
G02X603517Y491456I-4J-1579D01*
G01X603561Y491449D01*
X603644Y491473D01*
X603907Y491700D01*
G03X603976Y491852I-131J151D01*
G01Y492894D01*
G03X603907Y493046I-200J1D01*
G01X603644Y493273D01*
X603561Y493297D01*
X603517Y493290D01*
G02X603283Y493272I-238J1561D01*
G02Y496430I0J1579D01*
G02X604572Y495762I0J-1578D01*
G03X604688Y495683I163J115D01*
G37*
G36*
G01X1061774D02*
X1061892Y495654D01*
G03X1062031Y495671I47J195D01*
G02X1062865Y495876I835J-1598D01*
G02X1063699Y495671I-1J-1803D01*
G03X1063838Y495654I92J178D01*
G01X1063956Y495683D01*
G03X1064072Y495762I-47J194D01*
G02X1065361Y496430I1289J-910D01*
G02Y493272I0J-1579D01*
G02X1065127Y493290I4J1579D01*
G01X1065083Y493297D01*
X1065000Y493273D01*
X1064737Y493046D01*
G03X1064668Y492894I131J-151D01*
G01Y491852D01*
G03X1064737Y491700I200J-1D01*
G01X1065000Y491473D01*
X1065083Y491449D01*
X1065127Y491456D01*
G02X1065361Y491474I238J-1561D01*
G02Y488316I0J-1579D01*
G02X1064072Y488984I0J1578D01*
G03X1063956Y489063I-163J-115D01*
G01X1063838Y489092D01*
G03X1063699Y489075I-47J-195D01*
G02X1062865Y488870I-835J1598D01*
G02X1062031Y489075I1J1803D01*
G03X1061892Y489092I-92J-178D01*
G01X1061774Y489063D01*
G03X1061658Y488984I47J-194D01*
G02X1060369Y488316I-1289J910D01*
G02Y491474I0J1579D01*
G02X1060603Y491456I-4J-1579D01*
G01X1060647Y491449D01*
X1060730Y491473D01*
X1060993Y491700D01*
G03X1061062Y491852I-131J151D01*
G01Y492894D01*
G03X1060993Y493046I-200J1D01*
G01X1060730Y493273D01*
X1060647Y493297D01*
X1060603Y493290D01*
G02X1060369Y493272I-238J1561D01*
G02Y496430I0J1579D01*
G02X1061658Y495762I0J-1578D01*
G03X1061774Y495683I163J115D01*
G37*
G36*
G01X979074Y495487D02*
G02X982078I1502J0D01*
G02X981708Y494500I-1501J0D01*
G01Y494499D01*
X981707D01*
G03X981659Y494369I152J-130D01*
G01Y494105D01*
G03X981707Y493975I200J0D01*
G01X981708Y493974D01*
G02X982078Y492987I-1131J-987D01*
G02X979074I-1502J0D01*
G02X979444Y493974I1501J0D01*
G01Y493975D01*
X979445D01*
G03X979493Y494105I-152J130D01*
G01Y494369D01*
G03X979445Y494499I-200J0D01*
G01X979444Y494500D01*
G02X979074Y495487I1131J987D01*
G37*
G36*
G01X375255Y494089D02*
Y494383D01*
G03X375190Y494530I-200J-1D01*
G02X374705Y495636I1019J1106D01*
G02X377709I1502J0D01*
G02X377224Y494530I-1504J0D01*
G03X377159Y494383I135J-148D01*
G01Y494089D01*
G03X377224Y493942I200J1D01*
G02X377709Y492836I-1019J-1106D01*
G02X374705I-1502J0D01*
G02X375190Y493942I1504J0D01*
G03X375255Y494089I-135J148D01*
G37*
G36*
G01X990704Y498633D02*
G02X993708I1502J0D01*
G02X993338Y497646I-1501J0D01*
G01Y497645D01*
X993337D01*
G03X993289Y497515I152J-130D01*
G01Y497251D01*
G03X993337Y497121I200J0D01*
G01X993338Y497120D01*
G02Y495146I-1131J-987D01*
G01Y495145D01*
X993337D01*
G03X993289Y495015I152J-130D01*
G01Y494751D01*
G03X993337Y494621I200J0D01*
G01X993338Y494620D01*
G02Y492646I-1131J-987D01*
G01Y492645D01*
X993337D01*
G03X993289Y492515I152J-130D01*
G01Y492251D01*
G03X993337Y492121I200J0D01*
G01X993338Y492120D01*
G02X993708Y491133I-1131J-987D01*
G02X990704I-1502J0D01*
G02X991074Y492120I1501J0D01*
G01Y492121D01*
X991075D01*
G03X991123Y492251I-152J130D01*
G01Y492515D01*
G03X991075Y492645I-200J0D01*
G01X991074Y492646D01*
G02Y494620I1131J987D01*
G01Y494621D01*
X991075D01*
G03X991123Y494751I-152J130D01*
G01Y495015D01*
G03X991075Y495145I-200J0D01*
G01X991074Y495146D01*
G02Y497120I1131J987D01*
G01Y497121D01*
X991075D01*
G03X991123Y497251I-152J130D01*
G01Y497515D01*
G03X991075Y497645I-200J0D01*
G01X991074Y497646D01*
G02X990704Y498633I1131J987D01*
G37*
G36*
G01X977210Y505831D02*
X977211Y505830D01*
G03X977341Y505782I130J152D01*
G01X977605D01*
G03X977735Y505830I0J200D01*
G01X977736Y505831D01*
G02X978723Y506201I987J-1131D01*
G02Y503197I0J-1502D01*
G02X977736Y503567I0J1501D01*
G01X977735D01*
Y503568D01*
G03X977605Y503616I-130J-152D01*
G01X977341D01*
G03X977211Y503568I0J-200D01*
G01X977210Y503567D01*
G02X975236I-987J1131D01*
G01X975235D01*
Y503568D01*
G03X975105Y503616I-130J-152D01*
G01X974841D01*
G03X974711Y503568I0J-200D01*
G01X974710Y503567D01*
G02X973723Y503197I-987J1131D01*
G02Y506201I0J1502D01*
G02X974710Y505831I0J-1501D01*
G01X974711D01*
Y505830D01*
G03X974841Y505782I130J152D01*
G01X975105D01*
G03X975235Y505830I0J200D01*
G01X975236Y505831D01*
G02X977210I987J-1131D01*
G37*
G36*
G01X957461Y505957D02*
X957462Y505956D01*
G03X957592Y505908I130J152D01*
G01X957856D01*
G03X957986Y505956I0J200D01*
G01X957987Y505957D01*
G02X958974Y506327I987J-1131D01*
G02Y503323I0J-1502D01*
G02X957987Y503693I0J1501D01*
G01X957986D01*
Y503694D01*
G03X957856Y503742I-130J-152D01*
G01X957592D01*
G03X957462Y503694I0J-200D01*
G01X957461Y503693D01*
G02X955487I-987J1131D01*
G01X955486D01*
Y503694D01*
G03X955356Y503742I-130J-152D01*
G01X955092D01*
G03X954962Y503694I0J-200D01*
G01X954961Y503693D01*
G02X953974Y503323I-987J1131D01*
G02Y506327I0J1502D01*
G02X954961Y505957I0J-1501D01*
G01X954962D01*
Y505956D01*
G03X955092Y505908I130J152D01*
G01X955356D01*
G03X955486Y505956I0J200D01*
G01X955487Y505957D01*
G02X957461I987J-1131D01*
G37*
G36*
G01X640060Y503760D02*
Y503762D01*
G02X643761Y507462I3701J-1D01*
G01X651061D01*
G02Y500058I0J-3702D01*
G01X646180D01*
G03X646010Y499964I0J-200D01*
G01X645831Y499678D01*
G03X645820Y499486I169J-106D01*
G01Y499485D01*
G02X645968Y498836I-1354J-650D01*
G01Y498834D01*
G02X642964I-1502J0D01*
G02X643159Y499573I1502J-1D01*
G01X643182Y499615D01*
X643187Y499708D01*
X643021Y500088D01*
X642949Y500148D01*
X642903Y500159D01*
G02X640060Y503760I859J3601D01*
G37*
G36*
G01X436894Y511494D02*
G02X438396Y512995I1502J-1D01*
G02X439898Y511493I0J-1502D01*
G02X439392Y510369I-1501J0D01*
G01X439391Y510368D01*
G03X439325Y510222I134J-148D01*
G01X439320Y509926D01*
G03X439382Y509779I200J-2D01*
G01X439383Y509778D01*
G02X439855Y508685I-1030J-1093D01*
G02X438353Y507183I-1502J0D01*
G02X437001Y508031I0J1502D01*
G01Y508033D01*
X436984Y508067D01*
X436925Y508119D01*
X436585Y508241D01*
X436506Y508237D01*
X436471Y508220D01*
G02X435834Y508078I-637J1360D01*
G02Y511082I0J1502D01*
G02X436359Y510987I-1J-1502D01*
G01X436407Y510969D01*
X436507Y510984D01*
X436818Y511216D01*
G03X436898Y511389I-120J160D01*
G01Y511390D01*
G02X436894Y511492I1498J110D01*
G01Y511494D01*
G37*
G36*
G01X446025Y510010D02*
G02Y513014I0J1502D01*
G02X447012Y512644I0J-1501D01*
G01X447013D01*
Y512643D01*
G03X447143Y512595I130J152D01*
G01X447407D01*
G03X447537Y512643I0J200D01*
G01X447538Y512644D01*
G02X448525Y513014I987J-1131D01*
G02Y510010I0J-1502D01*
G02X447538Y510380I0J1501D01*
G01X447537D01*
Y510381D01*
G03X447407Y510429I-130J-152D01*
G01X447143D01*
G03X447013Y510381I0J-200D01*
G01X447012Y510380D01*
G02X446025Y510010I-987J1131D01*
G37*
G36*
G01X776989Y516449D02*
X777107Y516420D01*
G03X777246Y516437I47J195D01*
G02X778080Y516642I835J-1598D01*
G02X778914Y516437I-1J-1803D01*
G03X779053Y516420I92J178D01*
G01X779171Y516449D01*
G03X779287Y516528I-47J194D01*
G02X780576Y517196I1289J-910D01*
G02Y514038I0J-1579D01*
G02X780342Y514056I4J1579D01*
G01X780298Y514063D01*
X780215Y514039D01*
X779951Y513812D01*
G03X779882Y513660I131J-151D01*
G01Y512618D01*
G03X779951Y512466I200J-1D01*
G01X780215Y512239D01*
X780298Y512215D01*
X780342Y512222D01*
G02X780576Y512240I238J-1561D01*
G02Y509082I0J-1579D01*
G02X779287Y509750I0J1578D01*
G03X779171Y509829I-163J-115D01*
G01X779053Y509858D01*
G03X778914Y509841I-47J-195D01*
G02X778080Y509636I-835J1598D01*
G02X777246Y509841I1J1803D01*
G03X777107Y509858I-92J-178D01*
G01X776989Y509829D01*
G03X776873Y509750I47J-194D01*
G02X775584Y509082I-1289J910D01*
G02Y512240I0J1579D01*
G02X775818Y512222I-4J-1579D01*
G01X775862Y512215D01*
X775945Y512239D01*
X776209Y512466D01*
G03X776278Y512618I-131J151D01*
G01Y513660D01*
G03X776209Y513812I-200J1D01*
G01X775945Y514039D01*
X775862Y514063D01*
X775818Y514056D01*
G02X775584Y514038I-238J1561D01*
G02Y517196I0J1579D01*
G02X776873Y516528I0J-1578D01*
G03X776989Y516449I163J115D01*
G37*
G36*
G01X412773Y515717D02*
G02X415777I1502J0D01*
G02X415407Y514730I-1501J0D01*
G01Y514729D01*
X415406D01*
G03X415358Y514599I152J-130D01*
G01Y514335D01*
G03X415406Y514205I200J0D01*
G01X415407Y514204D01*
G02Y512230I-1131J-987D01*
G01Y512229D01*
X415406D01*
G03X415358Y512099I152J-130D01*
G01Y511835D01*
G03X415406Y511705I200J0D01*
G01X415407Y511704D01*
G02Y509730I-1131J-987D01*
G01Y509729D01*
X415406D01*
G03X415358Y509599I152J-130D01*
G01Y509335D01*
G03X415406Y509205I200J0D01*
G01X415407Y509204D01*
G02X415777Y508217I-1131J-987D01*
G02X412773I-1502J0D01*
G02X413143Y509204I1501J0D01*
G01Y509205D01*
X413144D01*
G03X413192Y509335I-152J130D01*
G01Y509599D01*
G03X413144Y509729I-200J0D01*
G01X413143Y509730D01*
G02Y511704I1131J987D01*
G01Y511705D01*
X413144D01*
G03X413192Y511835I-152J130D01*
G01Y512099D01*
G03X413144Y512229I-200J0D01*
G01X413143Y512230D01*
G02Y514204I1131J987D01*
G01Y514205D01*
X413144D01*
G03X413192Y514335I-152J130D01*
G01Y514599D01*
G03X413144Y514729I-200J0D01*
G01X413143Y514730D01*
G02X412773Y515717I1131J987D01*
G37*
G36*
G01X976912Y518111D02*
X976913Y518110D01*
G03X977043Y518062I130J152D01*
G01X977307D01*
G03X977437Y518110I0J200D01*
G01X977438Y518111D01*
G02X978425Y518481I987J-1131D01*
G02Y515477I0J-1502D01*
G02X977438Y515847I0J1501D01*
G01X977437D01*
Y515848D01*
G03X977307Y515896I-130J-152D01*
G01X977043D01*
G03X976913Y515848I0J-200D01*
G01X976912Y515847D01*
G02X974938I-987J1131D01*
G01X974937D01*
Y515848D01*
G03X974807Y515896I-130J-152D01*
G01X974543D01*
G03X974413Y515848I0J-200D01*
G01X974412Y515847D01*
G02X973425Y515477I-987J1131D01*
G02Y518481I0J1502D01*
G02X974412Y518111I0J-1501D01*
G01X974413D01*
Y518110D01*
G03X974543Y518062I130J152D01*
G01X974807D01*
G03X974937Y518110I0J200D01*
G01X974938Y518111D01*
G02X976912I987J-1131D01*
G37*
G36*
G01X957402Y518533D02*
X957403Y518532D01*
G03X957533Y518484I130J152D01*
G01X957797D01*
G03X957927Y518532I0J200D01*
G01X957928Y518533D01*
G02X958915Y518903I987J-1131D01*
G02Y515899I0J-1502D01*
G02X957928Y516269I0J1501D01*
G01X957927D01*
Y516270D01*
G03X957797Y516318I-130J-152D01*
G01X957533D01*
G03X957403Y516270I0J-200D01*
G01X957402Y516269D01*
G02X955428I-987J1131D01*
G01X955427D01*
Y516270D01*
G03X955297Y516318I-130J-152D01*
G01X955033D01*
G03X954903Y516270I0J-200D01*
G01X954902Y516269D01*
G02X953915Y515899I-987J1131D01*
G02Y518903I0J1502D01*
G02X954902Y518533I0J-1501D01*
G01X954903D01*
Y518532D01*
G03X955033Y518484I130J152D01*
G01X955297D01*
G03X955427Y518532I0J200D01*
G01X955428Y518533D01*
G02X957402I987J-1131D01*
G37*
G36*
G01X594286Y518531D02*
X594404Y518502D01*
G03X594543Y518519I47J195D01*
G02X595377Y518724I835J-1598D01*
G02X596211Y518519I-1J-1803D01*
G03X596350Y518502I92J178D01*
G01X596468Y518531D01*
G03X596584Y518610I-47J194D01*
G02X597873Y519278I1289J-910D01*
G02Y516120I0J-1579D01*
G02X597639Y516138I4J1579D01*
G01X597595Y516145D01*
X597512Y516121D01*
X597249Y515894D01*
G03X597180Y515742I131J-151D01*
G01Y514622D01*
G03X597250Y514470I200J0D01*
G01X597480Y514273D01*
G03X597641Y514227I130J152D01*
G02X597872Y514245I232J-1484D01*
G02Y511241I0J-1502D01*
G02X596650Y511870I0J1502D01*
G03X596530Y511949I-163J-116D01*
G01X596412Y511976D01*
G03X596269Y511954I-43J-195D01*
G02X595377Y511718I-892J1568D01*
G02X594484Y511955I1J1803D01*
G03X594341Y511977I-100J-173D01*
G01X594223Y511950D01*
G03X594103Y511871I43J-195D01*
G02X592880Y511241I-1223J872D01*
G02Y514245I0J1502D01*
G01X592882D01*
G02X593113Y514227I-1J-1502D01*
G01X593157Y514220D01*
X593240Y514244D01*
X593504Y514470D01*
G03X593574Y514622I-130J152D01*
G01Y515742D01*
G03X593505Y515894I-200J1D01*
G01X593242Y516121D01*
X593159Y516145D01*
X593115Y516138D01*
G02X592881Y516120I-238J1561D01*
G02Y519278I0J1579D01*
G02X594170Y518610I0J-1578D01*
G03X594286Y518531I163J115D01*
G37*
G36*
G01X1051372D02*
X1051490Y518502D01*
G03X1051629Y518519I47J195D01*
G02X1052463Y518724I835J-1598D01*
G02X1053297Y518519I-1J-1803D01*
G03X1053436Y518502I92J178D01*
G01X1053554Y518531D01*
G03X1053670Y518610I-47J194D01*
G02X1054959Y519278I1289J-910D01*
G02Y516120I0J-1579D01*
G02X1054725Y516138I4J1579D01*
G01X1054681Y516145D01*
X1054598Y516121D01*
X1054335Y515894D01*
G03X1054266Y515742I131J-151D01*
G01Y514700D01*
G03X1054335Y514548I200J-1D01*
G01X1054598Y514321D01*
X1054681Y514297D01*
X1054725Y514304D01*
G02X1054959Y514322I238J-1561D01*
G02Y511164I0J-1579D01*
G02X1053670Y511832I0J1578D01*
G03X1053554Y511911I-163J-115D01*
G01X1053436Y511940D01*
G03X1053297Y511923I-47J-195D01*
G02X1052463Y511718I-835J1598D01*
G02X1051629Y511923I1J1803D01*
G03X1051490Y511940I-92J-178D01*
G01X1051372Y511911D01*
G03X1051256Y511832I47J-194D01*
G02X1049967Y511164I-1289J910D01*
G02Y514322I0J1579D01*
G02X1050201Y514304I-4J-1579D01*
G01X1050245Y514297D01*
X1050328Y514321D01*
X1050591Y514548D01*
G03X1050660Y514700I-131J151D01*
G01Y515742D01*
G03X1050591Y515894I-200J1D01*
G01X1050328Y516121D01*
X1050245Y516145D01*
X1050201Y516138D01*
G02X1049967Y516120I-238J1561D01*
G02Y519278I0J1579D01*
G02X1051256Y518610I0J-1578D01*
G03X1051372Y518531I163J115D01*
G37*
G36*
G01X446025Y518197D02*
G02Y521201I0J1502D01*
G02X447012Y520831I0J-1501D01*
G01X447013D01*
Y520830D01*
G03X447143Y520782I130J152D01*
G01X447407D01*
G03X447537Y520830I0J200D01*
G01X447538Y520831D01*
G02X448525Y521201I987J-1131D01*
G02Y518197I0J-1502D01*
G02X447538Y518567I0J1501D01*
G01X447537D01*
Y518568D01*
G03X447407Y518616I-130J-152D01*
G01X447143D01*
G03X447013Y518568I0J-200D01*
G01X447012Y518567D01*
G02X446025Y518197I-987J1131D01*
G37*
G36*
G01X788482Y523754D02*
G02X789316Y523550I1J-1802D01*
G03X789455Y523533I92J178D01*
G01X789573Y523562D01*
G03X789689Y523641I-47J194D01*
G02X790978Y524308I1289J-912D01*
G02Y521152I0J-1578D01*
G02X790744Y521169I-3J1578D01*
G01X790700Y521176D01*
X790617Y521152D01*
X790353Y520925D01*
G03X790284Y520773I131J-151D01*
G01Y519731D01*
G03X790353Y519579I200J-1D01*
G01X790617Y519352D01*
X790700Y519328D01*
X790744Y519335D01*
G02X790978Y519352I231J-1561D01*
G02Y516196I0J-1578D01*
G02X789689Y516863I0J1579D01*
G03X789573Y516942I-163J-115D01*
G01X789455Y516971D01*
G03X789316Y516954I-47J-195D01*
G02X788482Y516750I-833J1598D01*
G02X787648Y516954I-1J1802D01*
G03X787509Y516971I-92J-178D01*
G01X787391Y516942D01*
G03X787275Y516863I47J-194D01*
G02X785986Y516196I-1289J912D01*
G02Y519352I0J1578D01*
G02X786220Y519335I3J-1578D01*
G01X786264Y519328D01*
X786347Y519352D01*
X786611Y519579D01*
G03X786680Y519731I-131J151D01*
G01Y520773D01*
G03X786611Y520925I-200J1D01*
G01X786347Y521152D01*
X786264Y521176D01*
X786220Y521169D01*
G02X785986Y521152I-231J1561D01*
G02Y524308I0J1578D01*
G02X787275Y523641I0J-1579D01*
G03X787391Y523562I163J115D01*
G01X787509Y523533D01*
G03X787648Y523550I47J195D01*
G02X788482Y523754I833J-1598D01*
G37*
G36*
G01X972904Y524304D02*
G02X975908I1502J0D01*
G02X975538Y523317I-1501J0D01*
G01Y523316D01*
X975537D01*
G03X975489Y523186I152J-130D01*
G01Y522922D01*
G03X975537Y522792I200J0D01*
G01X975538Y522791D01*
G02X975908Y521804I-1131J-987D01*
G02X972904I-1502J0D01*
G02X973274Y522791I1501J0D01*
G01Y522792D01*
X973275D01*
G03X973323Y522922I-152J130D01*
G01Y523186D01*
G03X973275Y523316I-200J0D01*
G01X973274Y523317D01*
G02X972904Y524304I1131J987D01*
G37*
G36*
G01X604688Y525643D02*
X604806Y525614D01*
G03X604945Y525631I47J195D01*
G02X605779Y525836I835J-1598D01*
G02X606613Y525631I-1J-1803D01*
G03X606752Y525614I92J178D01*
G01X606870Y525643D01*
G03X606986Y525722I-47J194D01*
G02X608275Y526390I1289J-910D01*
G02Y523232I0J-1579D01*
G02X608041Y523250I4J1579D01*
G01X607997Y523257D01*
X607914Y523233D01*
X607651Y523006D01*
G03X607582Y522854I131J-151D01*
G01Y521812D01*
G03X607651Y521660I200J-1D01*
G01X607914Y521433D01*
X607997Y521409D01*
X608041Y521416D01*
G02X608275Y521434I238J-1561D01*
G02Y518276I0J-1579D01*
G02X606986Y518944I0J1578D01*
G03X606870Y519023I-163J-115D01*
G01X606752Y519052D01*
G03X606613Y519035I-47J-195D01*
G02X605779Y518830I-835J1598D01*
G02X604945Y519035I1J1803D01*
G03X604806Y519052I-92J-178D01*
G01X604688Y519023D01*
G03X604572Y518944I47J-194D01*
G02X603283Y518276I-1289J910D01*
G02Y521434I0J1579D01*
G02X603517Y521416I-4J-1579D01*
G01X603561Y521409D01*
X603644Y521433D01*
X603907Y521660D01*
G03X603976Y521812I-131J151D01*
G01Y522854D01*
G03X603907Y523006I-200J1D01*
G01X603644Y523233D01*
X603561Y523257D01*
X603517Y523250D01*
G02X603283Y523232I-238J1561D01*
G02Y526390I0J1579D01*
G02X604572Y525722I0J-1578D01*
G03X604688Y525643I163J115D01*
G37*
G36*
G01X1061774D02*
X1061892Y525614D01*
G03X1062031Y525631I47J195D01*
G02X1062865Y525836I835J-1598D01*
G02X1063699Y525631I-1J-1803D01*
G03X1063838Y525614I92J178D01*
G01X1063956Y525643D01*
G03X1064072Y525722I-47J194D01*
G02X1065361Y526390I1289J-910D01*
G02Y523232I0J-1579D01*
G02X1065127Y523250I4J1579D01*
G01X1065083Y523257D01*
X1065000Y523233D01*
X1064737Y523006D01*
G03X1064668Y522854I131J-151D01*
G01Y521812D01*
G03X1064737Y521660I200J-1D01*
G01X1065000Y521433D01*
X1065083Y521409D01*
X1065127Y521416D01*
G02X1065361Y521434I238J-1561D01*
G02Y518276I0J-1579D01*
G02X1064072Y518944I0J1578D01*
G03X1063956Y519023I-163J-115D01*
G01X1063838Y519052D01*
G03X1063699Y519035I-47J-195D01*
G02X1062865Y518830I-835J1598D01*
G02X1062031Y519035I1J1803D01*
G03X1061892Y519052I-92J-178D01*
G01X1061774Y519023D01*
G03X1061658Y518944I47J-194D01*
G02X1060369Y518276I-1289J910D01*
G02Y521434I0J1579D01*
G02X1060603Y521416I-4J-1579D01*
G01X1060647Y521409D01*
X1060730Y521433D01*
X1060993Y521660D01*
G03X1061062Y521812I-131J151D01*
G01Y522854D01*
G03X1060993Y523006I-200J1D01*
G01X1060730Y523233D01*
X1060647Y523257D01*
X1060603Y523250D01*
G02X1060369Y523232I-238J1561D01*
G02Y526390I0J1579D01*
G02X1061658Y525722I0J-1578D01*
G03X1061774Y525643I163J115D01*
G37*
G36*
G01X958514Y523822D02*
Y524116D01*
G03X958449Y524263I-200J-1D01*
G02X957964Y525369I1019J1106D01*
G02X960968I1502J0D01*
G02X960483Y524263I-1504J0D01*
G03X960418Y524116I135J-148D01*
G01Y523822D01*
G03X960483Y523675I200J1D01*
G02X960968Y522569I-1019J-1106D01*
G02X957964I-1502J0D01*
G02X958449Y523675I1504J0D01*
G03X958514Y523822I-135J148D01*
G37*
G36*
G01X977415Y526497D02*
X977121D01*
G03X976974Y526432I1J-200D01*
G02X975868Y525947I-1106J1019D01*
G02Y528951I0J1502D01*
G02X976974Y528466I0J-1504D01*
G03X977121Y528401I148J135D01*
G01X977415D01*
G03X977562Y528466I-1J200D01*
G02X978668Y528951I1106J-1019D01*
G02Y525947I0J-1502D01*
G02X977562Y526432I0J1504D01*
G03X977415Y526497I-148J-135D01*
G37*
G36*
G01X776989Y530623D02*
X777107Y530594D01*
G03X777246Y530611I47J195D01*
G02X778080Y530816I835J-1598D01*
G02X778914Y530611I-1J-1803D01*
G03X779053Y530594I92J178D01*
G01X779171Y530623D01*
G03X779287Y530702I-47J194D01*
G02X780576Y531370I1289J-910D01*
G02Y528212I0J-1579D01*
G02X780342Y528230I4J1579D01*
G01X780298Y528237D01*
X780215Y528213D01*
X779951Y527986D01*
G03X779882Y527834I131J-151D01*
G01Y526792D01*
G03X779951Y526640I200J-1D01*
G01X780215Y526413D01*
X780298Y526389D01*
X780342Y526396D01*
G02X780576Y526414I238J-1561D01*
G02Y523256I0J-1579D01*
G02X779287Y523924I0J1578D01*
G03X779171Y524003I-163J-115D01*
G01X779053Y524032D01*
G03X778914Y524015I-47J-195D01*
G02X778080Y523810I-835J1598D01*
G02X777246Y524015I1J1803D01*
G03X777107Y524032I-92J-178D01*
G01X776989Y524003D01*
G03X776873Y523924I47J-194D01*
G02X775584Y523256I-1289J910D01*
G02Y526414I0J1579D01*
G02X775818Y526396I-4J-1579D01*
G01X775862Y526389D01*
X775945Y526413D01*
X776209Y526640D01*
G03X776278Y526792I-131J151D01*
G01Y527834D01*
G03X776209Y527986I-200J1D01*
G01X775945Y528213D01*
X775862Y528237D01*
X775818Y528230D01*
G02X775584Y528212I-238J1561D01*
G02Y531370I0J1579D01*
G02X776873Y530702I0J-1578D01*
G03X776989Y530623I163J115D01*
G37*
G36*
G01X981423Y528382D02*
Y528676D01*
G03X981358Y528823I-200J-1D01*
G02X980873Y529929I1019J1106D01*
G02X983877I1502J0D01*
G02X983392Y528823I-1504J0D01*
G03X983327Y528676I135J-148D01*
G01Y528382D01*
G03X983392Y528235I200J1D01*
G02X983877Y527129I-1019J-1106D01*
G02X983507Y526142I-1501J0D01*
G01Y526141D01*
X983506D01*
G03X983458Y526011I152J-130D01*
G01Y525747D01*
G03X983506Y525617I200J0D01*
G01X983507Y525616D01*
G02Y523642I-1131J-987D01*
G01Y523641D01*
X983506D01*
G03X983458Y523511I152J-130D01*
G01Y523247D01*
G03X983506Y523117I200J0D01*
G01X983507Y523116D01*
G02X983877Y522129I-1131J-987D01*
G02X983496Y521129I-1503J0D01*
G01X983470Y521101D01*
X983444Y521029D01*
X983452Y520679D01*
X983481Y520610D01*
X983508Y520583D01*
G02X983539Y520550I-1079J-1045D01*
G01X983749D01*
G03X983888Y520607I-1J200D01*
G02X984936Y521033I1048J-1076D01*
G02X985923Y520663I0J-1501D01*
G01X985924D01*
Y520662D01*
G03X986054Y520614I130J152D01*
G01X986318D01*
G03X986448Y520662I0J200D01*
G01X986449Y520663D01*
G02X988423I987J-1131D01*
G01X988424D01*
Y520662D01*
G03X988554Y520614I130J152D01*
G01X988818D01*
G03X988948Y520662I0J200D01*
G01X988949Y520663D01*
G02X989936Y521033I987J-1131D01*
G02Y518029I0J-1502D01*
G02X988949Y518399I0J1501D01*
G01X988948D01*
Y518400D01*
G03X988818Y518448I-130J-152D01*
G01X988554D01*
G03X988424Y518400I0J-200D01*
G01X988423Y518399D01*
G02X986449I-987J1131D01*
G01X986448D01*
Y518400D01*
G03X986318Y518448I-130J-152D01*
G01X986054D01*
G03X985924Y518400I0J-200D01*
G01X985923Y518399D01*
G02X983949I-987J1131D01*
G01X983948D01*
Y518400D01*
G03X983818Y518448I-130J-152D01*
G01X983554D01*
G03X983424Y518400I0J-200D01*
G01X983423Y518399D01*
G02X982436Y518029I-987J1131D01*
G02X980934Y519531I0J1502D01*
G02X981315Y520531I1503J0D01*
G01X981341Y520559D01*
X981367Y520631D01*
X981359Y520981D01*
X981330Y521050D01*
X981303Y521077D01*
G02X980873Y522129I1072J1052D01*
G02X981243Y523116I1501J0D01*
G01Y523117D01*
X981244D01*
G03X981292Y523247I-152J130D01*
G01Y523511D01*
G03X981244Y523641I-200J0D01*
G01X981243Y523642D01*
G02Y525616I1131J987D01*
G01Y525617D01*
X981244D01*
G03X981292Y525747I-152J130D01*
G01Y526011D01*
G03X981244Y526141I-200J0D01*
G01X981243Y526142D01*
G02X980873Y527129I1131J987D01*
G02X981358Y528235I1504J0D01*
G03X981423Y528382I-135J148D01*
G37*
G36*
G01X899530Y529251D02*
G02Y532255I0J1502D01*
G02X900686Y531712I0J-1502D01*
G01X900715Y531678D01*
X900795Y531640D01*
X901193D01*
X901273Y531678D01*
X901302Y531713D01*
G02X902459Y532257I1157J-958D01*
G02Y529253I0J-1502D01*
G02X901303Y529796I0J1502D01*
G01X901274Y529830D01*
X901194Y529868D01*
X900796D01*
X900716Y529830D01*
X900687Y529795D01*
G02X899530Y529251I-1157J958D01*
G37*
G36*
G01X969211Y531378D02*
G02X972215I1502J0D01*
G02X971845Y530391I-1501J0D01*
G01Y530390D01*
X971844D01*
G03X971796Y530260I152J-130D01*
G01Y529996D01*
G03X971844Y529866I200J0D01*
G01X971845Y529865D01*
G02X972215Y528878I-1131J-987D01*
G02X969211I-1502J0D01*
G02X969581Y529865I1501J0D01*
G01Y529866D01*
X969582D01*
G03X969630Y529996I-152J130D01*
G01Y530260D01*
G03X969582Y530390I-200J0D01*
G01X969581Y530391D01*
G02X969211Y531378I1131J987D01*
G37*
G36*
G01X595377Y532896D02*
G02X596211Y532692I1J-1802D01*
G03X596350Y532675I92J178D01*
G01X596468Y532704D01*
G03X596584Y532783I-47J194D01*
G02X597873Y533450I1289J-912D01*
G02Y530294I0J-1578D01*
G02X597639Y530311I-3J1578D01*
G01X597595Y530318D01*
X597512Y530294D01*
X597249Y530067D01*
G03X597180Y529915I131J-151D01*
G01Y528873D01*
G03X597249Y528721I200J-1D01*
G01X597512Y528494D01*
X597595Y528470D01*
X597639Y528477D01*
G02X597873Y528494I231J-1561D01*
G02Y525338I0J-1578D01*
G02X596584Y526005I0J1579D01*
G03X596468Y526084I-163J-115D01*
G01X596350Y526113D01*
G03X596211Y526096I-47J-195D01*
G02X595377Y525892I-833J1598D01*
G02X594543Y526096I-1J1802D01*
G03X594404Y526113I-92J-178D01*
G01X594286Y526084D01*
G03X594170Y526005I47J-194D01*
G02X592881Y525338I-1289J912D01*
G02Y528494I0J1578D01*
G02X593115Y528477I3J-1578D01*
G01X593159Y528470D01*
X593242Y528494D01*
X593505Y528721D01*
G03X593574Y528873I-131J151D01*
G01Y529915D01*
G03X593505Y530067I-200J1D01*
G01X593242Y530294D01*
X593159Y530318D01*
X593115Y530311D01*
G02X592881Y530294I-231J1561D01*
G02Y533450I0J1578D01*
G02X594170Y532783I0J-1579D01*
G03X594286Y532704I163J115D01*
G01X594404Y532675D01*
G03X594543Y532692I47J195D01*
G02X595377Y532896I833J-1598D01*
G37*
G36*
G01X1052463D02*
G02X1053297Y532692I1J-1802D01*
G03X1053436Y532675I92J178D01*
G01X1053554Y532704D01*
G03X1053670Y532783I-47J194D01*
G02X1054959Y533450I1289J-912D01*
G02Y530294I0J-1578D01*
G02X1054725Y530311I-3J1578D01*
G01X1054681Y530318D01*
X1054598Y530294D01*
X1054335Y530067D01*
G03X1054266Y529915I131J-151D01*
G01Y528873D01*
G03X1054335Y528721I200J-1D01*
G01X1054598Y528494D01*
X1054681Y528470D01*
X1054725Y528477D01*
G02X1054959Y528494I231J-1561D01*
G02Y525338I0J-1578D01*
G02X1053670Y526005I0J1579D01*
G03X1053554Y526084I-163J-115D01*
G01X1053436Y526113D01*
G03X1053297Y526096I-47J-195D01*
G02X1052463Y525892I-833J1598D01*
G02X1051629Y526096I-1J1802D01*
G03X1051490Y526113I-92J-178D01*
G01X1051372Y526084D01*
G03X1051256Y526005I47J-194D01*
G02X1049967Y525338I-1289J912D01*
G02Y528494I0J1578D01*
G02X1050201Y528477I3J-1578D01*
G01X1050245Y528470D01*
X1050328Y528494D01*
X1050591Y528721D01*
G03X1050660Y528873I-131J151D01*
G01Y529915D01*
G03X1050591Y530067I-200J1D01*
G01X1050328Y530294D01*
X1050245Y530318D01*
X1050201Y530311D01*
G02X1049967Y530294I-231J1561D01*
G02Y533450I0J1578D01*
G02X1051256Y532783I0J-1579D01*
G03X1051372Y532704I163J115D01*
G01X1051490Y532675D01*
G03X1051629Y532692I47J195D01*
G02X1052463Y532896I833J-1598D01*
G37*
G36*
G01X987815Y531997D02*
X987521D01*
G03X987374Y531932I1J-200D01*
G02X986268Y531447I-1106J1019D01*
G02Y534451I0J1502D01*
G02X987374Y533966I0J-1504D01*
G03X987521Y533901I148J135D01*
G01X987815D01*
G03X987962Y533966I-1J200D01*
G02X989068Y534451I1106J-1019D01*
G02Y531447I0J-1502D01*
G02X987962Y531932I0J1504D01*
G03X987815Y531997I-148J-135D01*
G37*
G36*
G01X826770Y535462D02*
G02X829774I1502J0D01*
G02X828912Y534103I-1502J0D01*
G01X828910D01*
X828877Y534087D01*
X828827Y534034D01*
X828709Y533750D01*
G03X828705Y533606I184J-77D01*
G02X828793Y533100I-1414J-507D01*
G02X825789I-1502J0D01*
G02X826651Y534459I1502J0D01*
G01X826653D01*
X826686Y534475D01*
X826736Y534528D01*
X826854Y534812D01*
G03X826858Y534956I-184J77D01*
G02X826770Y535462I1414J507D01*
G37*
G36*
G01X787391Y537735D02*
X787509Y537706D01*
G03X787648Y537723I47J195D01*
G02X788482Y537928I835J-1598D01*
G02X789316Y537723I-1J-1803D01*
G03X789455Y537706I92J178D01*
G01X789573Y537735D01*
G03X789689Y537814I-47J194D01*
G02X790978Y538482I1289J-910D01*
G02Y535324I0J-1579D01*
G02X790744Y535342I4J1579D01*
G01X790700Y535349D01*
X790617Y535325D01*
X790353Y535098D01*
G03X790284Y534946I131J-151D01*
G01Y533904D01*
G03X790353Y533752I200J-1D01*
G01X790617Y533525D01*
X790700Y533501D01*
X790744Y533508D01*
G02X790978Y533526I238J-1561D01*
G02Y530368I0J-1579D01*
G02X789689Y531036I0J1578D01*
G03X789573Y531115I-163J-115D01*
G01X789455Y531144D01*
G03X789316Y531127I-47J-195D01*
G02X788482Y530922I-835J1598D01*
G02X787648Y531127I1J1803D01*
G03X787509Y531144I-92J-178D01*
G01X787391Y531115D01*
G03X787275Y531036I47J-194D01*
G02X785986Y530368I-1289J910D01*
G02Y533526I0J1579D01*
G02X786220Y533508I-4J-1579D01*
G01X786264Y533501D01*
X786347Y533525D01*
X786611Y533752D01*
G03X786680Y533904I-131J151D01*
G01Y534946D01*
G03X786611Y535098I-200J1D01*
G01X786347Y535325D01*
X786264Y535349D01*
X786220Y535342D01*
G02X785986Y535324I-238J1561D01*
G02Y538482I0J1579D01*
G02X787275Y537814I0J-1578D01*
G03X787391Y537735I163J115D01*
G37*
G36*
G01X605779Y540008D02*
G02X606613Y539804I1J-1802D01*
G03X606752Y539787I92J178D01*
G01X606870Y539816D01*
G03X606986Y539895I-47J194D01*
G02X608275Y540562I1289J-912D01*
G02Y537406I0J-1578D01*
G02X608041Y537423I-3J1578D01*
G01X607997Y537430D01*
X607914Y537406D01*
X607651Y537179D01*
G03X607582Y537027I131J-151D01*
G01Y535985D01*
G03X607651Y535833I200J-1D01*
G01X607914Y535606D01*
X607997Y535582D01*
X608041Y535589D01*
G02X608275Y535606I231J-1561D01*
G02Y532450I0J-1578D01*
G02X606986Y533117I0J1579D01*
G03X606870Y533196I-163J-115D01*
G01X606752Y533225D01*
G03X606613Y533208I-47J-195D01*
G02X605779Y533004I-833J1598D01*
G02X604945Y533208I-1J1802D01*
G03X604806Y533225I-92J-178D01*
G01X604688Y533196D01*
G03X604572Y533117I47J-194D01*
G02X603283Y532450I-1289J912D01*
G02Y535606I0J1578D01*
G02X603517Y535589I3J-1578D01*
G01X603561Y535582D01*
X603644Y535606D01*
X603907Y535833D01*
G03X603976Y535985I-131J151D01*
G01Y537027D01*
G03X603907Y537179I-200J1D01*
G01X603644Y537406D01*
X603561Y537430D01*
X603517Y537423D01*
G02X603283Y537406I-231J1561D01*
G02Y540562I0J1578D01*
G02X604572Y539895I0J-1579D01*
G03X604688Y539816I163J115D01*
G01X604806Y539787D01*
G03X604945Y539804I47J195D01*
G02X605779Y540008I833J-1598D01*
G37*
G36*
G01X1062865D02*
G02X1063699Y539804I1J-1802D01*
G03X1063838Y539787I92J178D01*
G01X1063956Y539816D01*
G03X1064072Y539895I-47J194D01*
G02X1065361Y540562I1289J-912D01*
G02Y537406I0J-1578D01*
G02X1065127Y537423I-3J1578D01*
G01X1065083Y537430D01*
X1065000Y537406D01*
X1064737Y537179D01*
G03X1064668Y537027I131J-151D01*
G01Y535985D01*
G03X1064737Y535833I200J-1D01*
G01X1065000Y535606D01*
X1065083Y535582D01*
X1065127Y535589D01*
G02X1065361Y535606I231J-1561D01*
G02Y532450I0J-1578D01*
G02X1064072Y533117I0J1579D01*
G03X1063956Y533196I-163J-115D01*
G01X1063838Y533225D01*
G03X1063699Y533208I-47J-195D01*
G02X1062865Y533004I-833J1598D01*
G02X1062031Y533208I-1J1802D01*
G03X1061892Y533225I-92J-178D01*
G01X1061774Y533196D01*
G03X1061658Y533117I47J-194D01*
G02X1060369Y532450I-1289J912D01*
G02Y535606I0J1578D01*
G02X1060603Y535589I3J-1578D01*
G01X1060647Y535582D01*
X1060730Y535606D01*
X1060993Y535833D01*
G03X1061062Y535985I-131J151D01*
G01Y537027D01*
G03X1060993Y537179I-200J1D01*
G01X1060730Y537406D01*
X1060647Y537430D01*
X1060603Y537423D01*
G02X1060369Y537406I-231J1561D01*
G02Y540562I0J1578D01*
G02X1061658Y539895I0J-1579D01*
G03X1061774Y539816I163J115D01*
G01X1061892Y539787D01*
G03X1062031Y539804I47J195D01*
G02X1062865Y540008I833J-1598D01*
G37*
G36*
G01X966090Y538911D02*
Y539205D01*
G03X966025Y539352I-200J-1D01*
G02X965540Y540458I1019J1106D01*
G02X968544I1502J0D01*
G02X968059Y539352I-1504J0D01*
G03X967994Y539205I135J-148D01*
G01Y538911D01*
G03X968059Y538764I200J1D01*
G02X968544Y537658I-1019J-1106D01*
G02X965540I-1502J0D01*
G02X966025Y538764I1504J0D01*
G03X966090Y538911I-135J148D01*
G37*
G36*
G01X969243Y542231D02*
G02X972247I1502J0D01*
G02X971877Y541244I-1501J0D01*
G01Y541243D01*
X971876D01*
G03X971828Y541113I152J-130D01*
G01Y540849D01*
G03X971876Y540719I200J0D01*
G01X971877Y540718D01*
G02X972247Y539731I-1131J-987D01*
G02X969243I-1502J0D01*
G02X969613Y540718I1501J0D01*
G01Y540719D01*
X969614D01*
G03X969662Y540849I-152J130D01*
G01Y541113D01*
G03X969614Y541243I-200J0D01*
G01X969613Y541244D01*
G02X969243Y542231I1131J987D01*
G37*
G36*
G01X919981Y546096D02*
X923291D01*
G02X923433Y546037I0J-200D01*
G01X926511Y542959D01*
G02X926570Y542817I-141J-142D01*
G01Y530096D01*
G02X926511Y529954I-200J0D01*
G01X924912Y528355D01*
G02X924770Y528296I-142J141D01*
G01X906553D01*
G02X906411Y528355I0J200D01*
G01X904957Y529810D01*
G02X904898Y529952I141J142D01*
G01Y532518D01*
G03X904792Y532694I-200J0D01*
G01X904480Y532860D01*
G03X904273Y532849I-94J-176D01*
G02X903431Y532591I-842J1245D01*
G02Y535595I0J1502D01*
G02X904856Y534569I0J-1503D01*
G01X904873Y534519D01*
X904948Y534449D01*
X905330Y534360D01*
G03X905518Y534413I47J194D01*
G01X906945Y535841D01*
G03X907004Y535983I-141J142D01*
G01Y544291D01*
G02X907063Y544433I200J0D01*
G01X908667Y546037D01*
G02X908809Y546096I142J-141D01*
G01X915641D01*
G02X916559Y545669I-1J-1202D01*
G01X916697Y545505D01*
X916855Y545486D01*
X916918Y545533D01*
G02X918704I893J-1209D01*
G01X918767Y545486D01*
X918925Y545505D01*
X919063Y545669D01*
G02X919981Y546096I919J-775D01*
G37*
G36*
G01X988375Y549498D02*
X988376Y549497D01*
G03X988506Y549449I130J152D01*
G01X988770D01*
G03X988900Y549497I0J200D01*
G01X988901Y549498D01*
G02X989888Y549868I987J-1131D01*
G02Y546864I0J-1502D01*
G02X988901Y547234I0J1501D01*
G01X988900D01*
Y547235D01*
G03X988770Y547283I-130J-152D01*
G01X988506D01*
G03X988376Y547235I0J-200D01*
G01X988375Y547234D01*
G02X986401I-987J1131D01*
G01X986400D01*
Y547235D01*
G03X986270Y547283I-130J-152D01*
G01X986006D01*
G03X985876Y547235I0J-200D01*
G01X985875Y547234D01*
G02X983901I-987J1131D01*
G01X983900D01*
Y547235D01*
G03X983770Y547283I-130J-152D01*
G01X983506D01*
G03X983376Y547235I0J-200D01*
G01X983375Y547234D01*
G02X983312Y547182I-987J1132D01*
G03X983235Y547025I123J-158D01*
G01X983233Y546710D01*
G03X983308Y546554I200J0D01*
G01X983309Y546553D01*
G02X983877Y545377I-933J-1176D01*
G02X983507Y544390I-1501J0D01*
G01Y544389D01*
X983506D01*
G03X983458Y544259I152J-130D01*
G01Y543995D01*
G03X983506Y543865I200J0D01*
G01X983507Y543864D01*
G02Y541890I-1131J-987D01*
G01Y541889D01*
X983506D01*
G03X983458Y541759I152J-130D01*
G01Y541495D01*
G03X983506Y541365I200J0D01*
G01X983507Y541364D01*
G02Y539390I-1131J-987D01*
G01Y539389D01*
X983506D01*
G03X983458Y539259I152J-130D01*
G01Y538995D01*
G03X983506Y538865I200J0D01*
G01X983507Y538864D01*
G02X983877Y537877I-1131J-987D01*
G02X980873I-1502J0D01*
G02X981243Y538864I1501J0D01*
G01Y538865D01*
X981244D01*
G03X981292Y538995I-152J130D01*
G01Y539259D01*
G03X981244Y539389I-200J0D01*
G01X981243Y539390D01*
G02Y541364I1131J987D01*
G01Y541365D01*
X981244D01*
G03X981292Y541495I-152J130D01*
G01Y541759D01*
G03X981244Y541889I-200J0D01*
G01X981243Y541890D01*
G02Y543864I1131J987D01*
G01Y543865D01*
X981244D01*
G03X981292Y543995I-152J130D01*
G01Y544259D01*
G03X981244Y544389I-200J0D01*
G01X981243Y544390D01*
G02X980873Y545377I1131J987D01*
G02X981451Y546561I1502J0D01*
G03X981528Y546718I-123J158D01*
G01X981530Y547033D01*
G03X981455Y547189I-200J0D01*
G01X981454Y547190D01*
G02X980886Y548366I933J1176D01*
G02X982388Y549868I1502J0D01*
G02X983375Y549498I0J-1501D01*
G01X983376D01*
Y549497D01*
G03X983506Y549449I130J152D01*
G01X983770D01*
G03X983900Y549497I0J200D01*
G01X983901Y549498D01*
G02X985875I987J-1131D01*
G01X985876D01*
Y549497D01*
G03X986006Y549449I130J152D01*
G01X986270D01*
G03X986400Y549497I0J200D01*
G01X986401Y549498D01*
G02X988375I987J-1131D01*
G37*
G36*
G01X893949Y548861D02*
G02Y551865I0J1502D01*
G02X894718Y551653I0J-1501D01*
G01X894750Y551634D01*
X894822Y551622D01*
X895122Y551682D01*
G03X895243Y551759I-40J196D01*
G02X896449Y552365I1206J-897D01*
G02Y549361I0J-1502D01*
G02X895680Y549573I0J1501D01*
G01X895648Y549592D01*
X895576Y549604D01*
X895276Y549544D01*
G03X895155Y549467I40J-196D01*
G02X893949Y548861I-1206J897D01*
G37*
G36*
G01X952563Y554242D02*
X952269D01*
G03X952122Y554177I1J-200D01*
G02X951016Y553692I-1106J1019D01*
G02Y556696I0J1502D01*
G02X952122Y556211I0J-1504D01*
G03X952269Y556146I148J135D01*
G01X952563D01*
G03X952710Y556211I-1J200D01*
G02X953816Y556696I1106J-1019D01*
G02Y553692I0J-1502D01*
G02X952710Y554177I0J1504D01*
G03X952563Y554242I-148J-135D01*
G37*
G36*
G01X959563D02*
X959269D01*
G03X959122Y554177I1J-200D01*
G02X958016Y553692I-1106J1019D01*
G02Y556696I0J1502D01*
G02X959122Y556211I0J-1504D01*
G03X959269Y556146I148J135D01*
G01X959563D01*
G03X959710Y556211I-1J200D01*
G02X960816Y556696I1106J-1019D01*
G02Y553692I0J-1502D01*
G02X959710Y554177I0J1504D01*
G03X959563Y554242I-148J-135D01*
G37*
G36*
G01X952563Y562242D02*
X952269D01*
G03X952122Y562177I1J-200D01*
G02X951016Y561692I-1106J1019D01*
G02Y564696I0J1502D01*
G02X952122Y564211I0J-1504D01*
G03X952269Y564146I148J135D01*
G01X952563D01*
G03X952710Y564211I-1J200D01*
G02X953816Y564696I1106J-1019D01*
G02Y561692I0J-1502D01*
G02X952710Y562177I0J1504D01*
G03X952563Y562242I-148J-135D01*
G37*
G36*
G01X959563D02*
X959269D01*
G03X959122Y562177I1J-200D01*
G02X958016Y561692I-1106J1019D01*
G02Y564696I0J1502D01*
G02X959122Y564211I0J-1504D01*
G03X959269Y564146I148J135D01*
G01X959563D01*
G03X959710Y564211I-1J200D01*
G02X960816Y564696I1106J-1019D01*
G02Y561692I0J-1502D01*
G02X959710Y562177I0J1504D01*
G03X959563Y562242I-148J-135D01*
G37*
G36*
G01X776989Y566489D02*
X777107Y566460D01*
G03X777246Y566477I47J195D01*
G02X778080Y566682I835J-1598D01*
G02X778914Y566477I-1J-1803D01*
G03X779053Y566460I92J178D01*
G01X779171Y566489D01*
G03X779287Y566568I-47J194D01*
G02X780576Y567236I1289J-910D01*
G02Y564078I0J-1579D01*
G02X780342Y564096I4J1579D01*
G01X780298Y564103D01*
X780215Y564079D01*
X779951Y563852D01*
G03X779882Y563700I131J-151D01*
G01Y562658D01*
G03X779951Y562506I200J-1D01*
G01X780215Y562279D01*
X780298Y562255D01*
X780342Y562262D01*
G02X780576Y562280I238J-1561D01*
G02Y559122I0J-1579D01*
G02X779287Y559790I0J1578D01*
G03X779171Y559869I-163J-115D01*
G01X779053Y559898D01*
G03X778914Y559881I-47J-195D01*
G02X778080Y559676I-835J1598D01*
G02X777246Y559881I1J1803D01*
G03X777107Y559898I-92J-178D01*
G01X776989Y559869D01*
G03X776873Y559790I47J-194D01*
G02X775584Y559122I-1289J910D01*
G02Y562280I0J1579D01*
G02X775818Y562262I-4J-1579D01*
G01X775862Y562255D01*
X775945Y562279D01*
X776209Y562506D01*
G03X776278Y562658I-131J151D01*
G01Y563700D01*
G03X776209Y563852I-200J1D01*
G01X775945Y564079D01*
X775862Y564103D01*
X775818Y564096D01*
G02X775584Y564078I-238J1561D01*
G02Y567236I0J1579D01*
G02X776873Y566568I0J-1578D01*
G03X776989Y566489I163J115D01*
G37*
G36*
G01X952563Y570242D02*
X952269D01*
G03X952122Y570177I1J-200D01*
G02X951016Y569692I-1106J1019D01*
G02Y572696I0J1502D01*
G02X952122Y572211I0J-1504D01*
G03X952269Y572146I148J135D01*
G01X952563D01*
G03X952710Y572211I-1J200D01*
G02X953816Y572696I1106J-1019D01*
G02Y569692I0J-1502D01*
G02X952710Y570177I0J1504D01*
G03X952563Y570242I-148J-135D01*
G37*
G36*
G01X959563D02*
X959269D01*
G03X959122Y570177I1J-200D01*
G02X958016Y569692I-1106J1019D01*
G02Y572696I0J1502D01*
G02X959122Y572211I0J-1504D01*
G03X959269Y572146I148J135D01*
G01X959563D01*
G03X959710Y572211I-1J200D01*
G02X960816Y572696I1106J-1019D01*
G02Y569692I0J-1502D01*
G02X959710Y570177I0J1504D01*
G03X959563Y570242I-148J-135D01*
G37*
G36*
G01X919038Y577876D02*
G02Y580880I0J1502D01*
G02X920272Y580235I0J-1503D01*
G01X920292Y580205D01*
X920354Y580163D01*
X920650Y580093D01*
G03X920791Y580111I47J194D01*
G02X921507Y580293I717J-1320D01*
G02Y577289I0J-1502D01*
G02X920273Y577934I0J1503D01*
G01X920253Y577964D01*
X920191Y578006D01*
X919895Y578076D01*
G03X919754Y578058I-47J-194D01*
G02X919038Y577876I-717J1320D01*
G37*
G36*
G01X778080Y580854D02*
G02X778914Y580650I1J-1802D01*
G03X779053Y580633I92J178D01*
G01X779171Y580662D01*
G03X779287Y580741I-47J194D01*
G02X780576Y581408I1289J-912D01*
G02Y578252I0J-1578D01*
G02X780342Y578269I-3J1578D01*
G01X780298Y578276D01*
X780215Y578252D01*
X779951Y578025D01*
G03X779882Y577873I131J-151D01*
G01Y576831D01*
G03X779951Y576679I200J-1D01*
G01X780215Y576452D01*
X780298Y576428D01*
X780342Y576435D01*
G02X780576Y576452I231J-1561D01*
G02Y573296I0J-1578D01*
G02X779287Y573963I0J1579D01*
G03X779171Y574042I-163J-115D01*
G01X779053Y574071D01*
G03X778914Y574054I-47J-195D01*
G02X778080Y573850I-833J1598D01*
G02X777246Y574054I-1J1802D01*
G03X777107Y574071I-92J-178D01*
G01X776989Y574042D01*
G03X776873Y573963I47J-194D01*
G02X775584Y573296I-1289J912D01*
G02Y576452I0J1578D01*
G02X775818Y576435I3J-1578D01*
G01X775862Y576428D01*
X775945Y576452D01*
X776209Y576679D01*
G03X776278Y576831I-131J151D01*
G01Y577873D01*
G03X776209Y578025I-200J1D01*
G01X775945Y578252D01*
X775862Y578276D01*
X775818Y578269D01*
G02X775584Y578252I-231J1561D01*
G02Y581408I0J1578D01*
G02X776873Y580741I0J-1579D01*
G03X776989Y580662I163J115D01*
G01X777107Y580633D01*
G03X777246Y580650I47J195D01*
G02X778080Y580854I833J-1598D01*
G37*
G36*
G01X945078Y582174D02*
X945372D01*
G03X945519Y582239I-1J200D01*
G02X947731I1106J-1017D01*
G03X947878Y582174I148J135D01*
G01X948172D01*
G03X948319Y582239I-1J200D01*
G02X949425Y582724I1106J-1019D01*
G02Y579720I0J-1502D01*
G02X948319Y580205I0J1504D01*
G03X948172Y580270I-148J-135D01*
G01X947878D01*
G03X947731Y580205I1J-200D01*
G02X945519I-1106J1017D01*
G03X945372Y580270I-148J-135D01*
G01X945078D01*
G03X944931Y580205I1J-200D01*
G02X943825Y579720I-1106J1019D01*
G02Y582724I0J1502D01*
G02X944931Y582239I0J-1504D01*
G03X945078Y582174I148J135D01*
G37*
G36*
G01X960826D02*
X961120D01*
G03X961267Y582239I-1J200D01*
G02X963479I1106J-1017D01*
G03X963626Y582174I148J135D01*
G01X963920D01*
G03X964067Y582239I-1J200D01*
G02X965173Y582724I1106J-1019D01*
G02Y579720I0J-1502D01*
G02X964067Y580205I0J1504D01*
G03X963920Y580270I-148J-135D01*
G01X963626D01*
G03X963479Y580205I1J-200D01*
G02X961267I-1106J1017D01*
G03X961120Y580270I-148J-135D01*
G01X960826D01*
G03X960679Y580205I1J-200D01*
G02X959573Y579720I-1106J1019D01*
G02Y582724I0J1502D01*
G02X960679Y582239I0J-1504D01*
G03X960826Y582174I148J135D01*
G37*
G36*
G01X787391Y587775D02*
X787509Y587746D01*
G03X787648Y587763I47J195D01*
G02X788482Y587968I835J-1598D01*
G02X789316Y587763I-1J-1803D01*
G03X789455Y587746I92J178D01*
G01X789573Y587775D01*
G03X789689Y587854I-47J194D01*
G02X790978Y588522I1289J-910D01*
G02Y585364I0J-1579D01*
G02X790744Y585382I4J1579D01*
G01X790700Y585389D01*
X790617Y585365D01*
X790353Y585138D01*
G03X790284Y584986I131J-151D01*
G01Y583944D01*
G03X790353Y583792I200J-1D01*
G01X790617Y583565D01*
X790700Y583541D01*
X790744Y583548D01*
G02X790978Y583566I238J-1561D01*
G02Y580408I0J-1579D01*
G02X789689Y581076I0J1578D01*
G03X789573Y581155I-163J-115D01*
G01X789455Y581184D01*
G03X789316Y581167I-47J-195D01*
G02X788482Y580962I-835J1598D01*
G02X787648Y581167I1J1803D01*
G03X787509Y581184I-92J-178D01*
G01X787391Y581155D01*
G03X787275Y581076I47J-194D01*
G02X785986Y580408I-1289J910D01*
G02Y583566I0J1579D01*
G02X786220Y583548I-4J-1579D01*
G01X786264Y583541D01*
X786347Y583565D01*
X786611Y583792D01*
G03X786680Y583944I-131J151D01*
G01Y584986D01*
G03X786611Y585138I-200J1D01*
G01X786347Y585365D01*
X786264Y585389D01*
X786220Y585382D01*
G02X785986Y585364I-238J1561D01*
G02Y588522I0J1579D01*
G02X787275Y587854I0J-1578D01*
G03X787391Y587775I163J115D01*
G37*
G36*
G01X906999Y586772D02*
G02Y589776I0J1502D01*
G02X908469Y588582I0J-1502D01*
G01Y588580D01*
G03X908545Y588462I196J42D01*
G01X908759Y588303D01*
G03X908894Y588264I119J160D01*
G01X908895D01*
G02X909024Y588270I134J-1496D01*
G02Y585266I0J-1502D01*
G02X907554Y586460I0J1502D01*
G01Y586462D01*
G03X907478Y586580I-196J-42D01*
G01X907264Y586739D01*
G03X907129Y586778I-119J-160D01*
G01X907128D01*
G02X906999Y586772I-134J1496D01*
G37*
G36*
G01X921217Y590718D02*
G02Y587714I0J-1502D01*
G01X921216D01*
G02X921012Y587728I1J1502D01*
G01X921011D01*
G03X920866Y587691I-27J-198D01*
G01X920609Y587502D01*
X920568Y587436D01*
X920562Y587397D01*
G02X919080Y586138I-1482J243D01*
G02Y589142I0J1502D01*
G01X919081D01*
G02X919285Y589128I-1J-1502D01*
G01X919286D01*
G03X919431Y589165I27J198D01*
G01X919688Y589354D01*
X919729Y589420D01*
X919735Y589459D01*
G02X921217Y590718I1482J-243D01*
G37*
G36*
G01X945078Y592167D02*
X945372D01*
G03X945519Y592232I-1J200D01*
G02X947731I1106J-1017D01*
G03X947878Y592167I148J135D01*
G01X948172D01*
G03X948319Y592232I-1J200D01*
G02X949425Y592717I1106J-1019D01*
G02Y589713I0J-1502D01*
G02X948319Y590198I0J1504D01*
G03X948172Y590263I-148J-135D01*
G01X947878D01*
G03X947731Y590198I1J-200D01*
G02X945519I-1106J1017D01*
G03X945372Y590263I-148J-135D01*
G01X945078D01*
G03X944931Y590198I1J-200D01*
G02X943825Y589713I-1106J1019D01*
G02Y592717I0J1502D01*
G02X944931Y592232I0J-1504D01*
G03X945078Y592167I148J135D01*
G37*
G36*
G01X960826D02*
X961120D01*
G03X961267Y592232I-1J200D01*
G02X963479I1106J-1017D01*
G03X963626Y592167I148J135D01*
G01X963920D01*
G03X964067Y592232I-1J200D01*
G02X965173Y592717I1106J-1019D01*
G02Y589713I0J-1502D01*
G02X964067Y590198I0J1504D01*
G03X963920Y590263I-148J-135D01*
G01X963626D01*
G03X963479Y590198I1J-200D01*
G02X961267I-1106J1017D01*
G03X961120Y590263I-148J-135D01*
G01X960826D01*
G03X960679Y590198I1J-200D01*
G02X959573Y589713I-1106J1019D01*
G02Y592717I0J1502D01*
G02X960679Y592232I0J-1504D01*
G03X960826Y592167I148J135D01*
G37*
G36*
G01X776989Y594835D02*
X777107Y594806D01*
G03X777246Y594823I47J195D01*
G02X778080Y595028I835J-1598D01*
G02X778914Y594823I-1J-1803D01*
G03X779053Y594806I92J178D01*
G01X779171Y594835D01*
G03X779287Y594914I-47J194D01*
G02X780576Y595582I1289J-910D01*
G02Y592424I0J-1579D01*
G02X780342Y592442I4J1579D01*
G01X780298Y592449D01*
X780215Y592425D01*
X779951Y592198D01*
G03X779882Y592046I131J-151D01*
G01Y591004D01*
G03X779951Y590852I200J-1D01*
G01X780215Y590625D01*
X780298Y590601D01*
X780342Y590608D01*
G02X780576Y590626I238J-1561D01*
G02Y587468I0J-1579D01*
G02X779287Y588136I0J1578D01*
G03X779171Y588215I-163J-115D01*
G01X779053Y588244D01*
G03X778914Y588227I-47J-195D01*
G02X778080Y588022I-835J1598D01*
G02X777246Y588227I1J1803D01*
G03X777107Y588244I-92J-178D01*
G01X776989Y588215D01*
G03X776873Y588136I47J-194D01*
G02X775584Y587468I-1289J910D01*
G02Y590626I0J1579D01*
G02X775818Y590608I-4J-1579D01*
G01X775862Y590601D01*
X775945Y590625D01*
X776209Y590852D01*
G03X776278Y591004I-131J151D01*
G01Y592046D01*
G03X776209Y592198I-200J1D01*
G01X775945Y592425D01*
X775862Y592449D01*
X775818Y592442D01*
G02X775584Y592424I-238J1561D01*
G02Y595582I0J1579D01*
G02X776873Y594914I0J-1578D01*
G03X776989Y594835I163J115D01*
G37*
G36*
G01X930016Y599419D02*
Y599421D01*
G02X931594Y600998I1578J-1D01*
G02X933051Y600028I0J-1579D01*
G03X933141Y599928I185J76D01*
G01X933246Y599873D01*
G03X933380Y599853I95J176D01*
G02X933741Y599890I363J-1767D01*
G02X935544Y598087I0J-1803D01*
G01Y594687D01*
G02X933741Y592884I-1803J0D01*
G02X933450Y592908I2J1803D01*
G03X933316Y592883I-33J-197D01*
G01X933214Y592823D01*
G03X933127Y592720I100J-173D01*
G02X932808Y592200I-1480J550D01*
G01X932783Y592173D01*
X932756Y592107D01*
X932748Y591807D01*
G03X932794Y591674I200J-5D01*
G02X933035Y591277I-1214J-1009D01*
G03X933125Y591177I185J76D01*
G01X933230Y591122D01*
G03X933363Y591102I94J176D01*
G02X933725Y591138I358J-1766D01*
G02X935528Y589336I1J-1802D01*
G01Y585936D01*
G02X933725Y584134I-1803J1D01*
G01X933722D01*
G02X933452Y584155I4J1802D01*
G03X933315Y584126I-30J-198D01*
G01X933213Y584062D01*
G03X933128Y583951I106J-169D01*
G02X931620Y582838I-1508J465D01*
G02X930042Y584416I0J1578D01*
G02X931542Y585993I1579J0D01*
G03X931677Y586055I-10J200D01*
G01X931867Y586254D01*
G03X931922Y586392I-146J138D01*
G01Y588691D01*
G03X931865Y588830I-200J-1D01*
G01X931644Y589058D01*
X931573Y589089D01*
X931534Y589090D01*
G02X930000Y590668I45J1578D01*
G01Y590670D01*
G02X930417Y591738I1578J-1D01*
G01X930442Y591765D01*
X930469Y591831D01*
X930477Y592131D01*
G03X930431Y592264I-200J5D01*
G02X930068Y593270I1216J1007D01*
G02X931560Y594846I1578J0D01*
G01X931599Y594848D01*
X931668Y594880D01*
X931884Y595108D01*
G03X931938Y595245I-146J137D01*
G01Y597442D01*
G03X931881Y597581I-200J-1D01*
G01X931660Y597809D01*
X931589Y597840D01*
X931550Y597841D01*
G02X930016Y599419I45J1578D01*
G37*
G36*
G01X788482Y602140D02*
G02X789316Y601936I1J-1802D01*
G03X789455Y601919I92J178D01*
G01X789573Y601948D01*
G03X789689Y602027I-47J194D01*
G02X790978Y602694I1289J-912D01*
G02Y599538I0J-1578D01*
G02X790744Y599555I-3J1578D01*
G01X790700Y599562D01*
X790617Y599538D01*
X790353Y599311D01*
G03X790284Y599159I131J-151D01*
G01Y598117D01*
G03X790353Y597965I200J-1D01*
G01X790617Y597738D01*
X790700Y597714D01*
X790744Y597721D01*
G02X790978Y597738I231J-1561D01*
G02Y594582I0J-1578D01*
G02X789689Y595249I0J1579D01*
G03X789573Y595328I-163J-115D01*
G01X789455Y595357D01*
G03X789316Y595340I-47J-195D01*
G02X788482Y595136I-833J1598D01*
G02X787648Y595340I-1J1802D01*
G03X787509Y595357I-92J-178D01*
G01X787391Y595328D01*
G03X787275Y595249I47J-194D01*
G02X785986Y594582I-1289J912D01*
G02Y597738I0J1578D01*
G02X786220Y597721I3J-1578D01*
G01X786264Y597714D01*
X786347Y597738D01*
X786611Y597965D01*
G03X786680Y598117I-131J151D01*
G01Y599159D01*
G03X786611Y599311I-200J1D01*
G01X786347Y599538D01*
X786264Y599562D01*
X786220Y599555D01*
G02X785986Y599538I-231J1561D01*
G02Y602694I0J1578D01*
G02X787275Y602027I0J-1579D01*
G03X787391Y601948I163J115D01*
G01X787509Y601919D01*
G03X787648Y601936I47J195D01*
G02X788482Y602140I833J-1598D01*
G37*
G36*
G01X776989Y609009D02*
X777107Y608980D01*
G03X777246Y608997I47J195D01*
G02X778080Y609202I835J-1598D01*
G02X778914Y608997I-1J-1803D01*
G03X779053Y608980I92J178D01*
G01X779171Y609009D01*
G03X779287Y609088I-47J194D01*
G02X780576Y609756I1289J-910D01*
G02Y606598I0J-1579D01*
G02X780342Y606616I4J1579D01*
G01X780298Y606623D01*
X780215Y606599D01*
X779951Y606372D01*
G03X779882Y606220I131J-151D01*
G01Y605178D01*
G03X779951Y605026I200J-1D01*
G01X780215Y604799D01*
X780298Y604775D01*
X780342Y604782D01*
G02X780576Y604800I238J-1561D01*
G02Y601642I0J-1579D01*
G02X779287Y602310I0J1578D01*
G03X779171Y602389I-163J-115D01*
G01X779053Y602418D01*
G03X778914Y602401I-47J-195D01*
G02X778080Y602196I-835J1598D01*
G02X777246Y602401I1J1803D01*
G03X777107Y602418I-92J-178D01*
G01X776989Y602389D01*
G03X776873Y602310I47J-194D01*
G02X775584Y601642I-1289J910D01*
G02Y604800I0J1579D01*
G02X775818Y604782I-4J-1579D01*
G01X775862Y604775D01*
X775945Y604799D01*
X776209Y605026D01*
G03X776278Y605178I-131J151D01*
G01Y606220D01*
G03X776209Y606372I-200J1D01*
G01X775945Y606599D01*
X775862Y606623D01*
X775818Y606616D01*
G02X775584Y606598I-238J1561D01*
G02Y609756I0J1579D01*
G02X776873Y609088I0J-1578D01*
G03X776989Y609009I163J115D01*
G37*
G36*
G01X963798Y611514D02*
X964092D01*
G03X964239Y611579I-1J200D01*
G02X966451I1106J-1017D01*
G03X966598Y611514I148J135D01*
G01X966892D01*
G03X967039Y611579I-1J200D01*
G02X968145Y612064I1106J-1019D01*
G02X969647Y610562I0J-1502D01*
G02X969162Y609456I-1504J0D01*
G03X969097Y609309I135J-148D01*
G01Y609015D01*
G03X969162Y608868I200J1D01*
G02X969647Y607762I-1019J-1106D01*
G02X968145Y606260I-1502J0D01*
G02X967039Y606745I0J1504D01*
G03X966892Y606810I-148J-135D01*
G01X966598D01*
G03X966451Y606745I1J-200D01*
G02X964239I-1106J1017D01*
G03X964092Y606810I-148J-135D01*
G01X963798D01*
G03X963651Y606745I1J-200D01*
G02X961439I-1106J1017D01*
G03X961292Y606810I-148J-135D01*
G01X960998D01*
G03X960851Y606745I1J-200D01*
G02X959745Y606260I-1106J1019D01*
G02X958243Y607762I0J1502D01*
G02X958728Y608868I1504J0D01*
G03X958793Y609015I-135J148D01*
G01Y609309D01*
G03X958728Y609456I-200J-1D01*
G02X958243Y610562I1019J1106D01*
G02X959745Y612064I1502J0D01*
G02X960851Y611579I0J-1504D01*
G03X960998Y611514I148J135D01*
G01X961292D01*
G03X961439Y611579I-1J200D01*
G02X963651I1106J-1017D01*
G03X963798Y611514I148J135D01*
G37*
G36*
G01X787391Y616121D02*
X787509Y616092D01*
G03X787648Y616109I47J195D01*
G02X788482Y616314I835J-1598D01*
G02X789316Y616109I-1J-1803D01*
G03X789455Y616092I92J178D01*
G01X789573Y616121D01*
G03X789689Y616200I-47J194D01*
G02X790978Y616868I1289J-910D01*
G02Y613710I0J-1579D01*
G02X790744Y613728I4J1579D01*
G01X790700Y613735D01*
X790617Y613711D01*
X790353Y613484D01*
G03X790284Y613332I131J-151D01*
G01Y612290D01*
G03X790353Y612138I200J-1D01*
G01X790617Y611911D01*
X790700Y611887D01*
X790744Y611894D01*
G02X790978Y611912I238J-1561D01*
G02Y608754I0J-1579D01*
G02X789689Y609422I0J1578D01*
G03X789573Y609501I-163J-115D01*
G01X789455Y609530D01*
G03X789316Y609513I-47J-195D01*
G02X788482Y609308I-835J1598D01*
G02X787648Y609513I1J1803D01*
G03X787509Y609530I-92J-178D01*
G01X787391Y609501D01*
G03X787275Y609422I47J-194D01*
G02X785986Y608754I-1289J910D01*
G02Y611912I0J1579D01*
G02X786220Y611894I-4J-1579D01*
G01X786264Y611887D01*
X786347Y611911D01*
X786611Y612138D01*
G03X786680Y612290I-131J151D01*
G01Y613332D01*
G03X786611Y613484I-200J1D01*
G01X786347Y613711D01*
X786264Y613735D01*
X786220Y613728D01*
G02X785986Y613710I-238J1561D01*
G02Y616868I0J1579D01*
G02X787275Y616200I0J-1578D01*
G03X787391Y616121I163J115D01*
G37*
G36*
G01X500134Y698123D02*
G03X499586Y698431I-395J-62D01*
G02X499012Y698317I-574J1388D01*
G02Y701321I0J1502D01*
G02X500496Y700051I0J-1502D01*
G03X501044Y699743I395J62D01*
G02X501618Y699857I574J-1388D01*
G02Y696853I0J-1502D01*
G02X500134Y698123I0J1502D01*
G37*
G36*
G01X484341Y703982D02*
G02Y706986I0J1502D01*
G02X485563Y706357I0J-1502D01*
G03X485682Y706278I163J116D01*
G01X485802Y706251D01*
G03X485945Y706272I44J195D01*
G02X486837Y706508I892J-1568D01*
G01X486839D01*
G02X488640Y704706I-1J-1802D01*
G01Y701306D01*
G02X486837Y699504I-1803J1D01*
G02X485945Y699740I0J1804D01*
G03X485802Y699761I-99J-174D01*
G01X485682Y699734D01*
G03X485563Y699655I44J-195D01*
G02X484341Y699026I-1222J873D01*
G02Y702030I0J1502D01*
G02X484573Y702012I0J-1502D01*
G01X484617Y702005D01*
X484700Y702029D01*
X484964Y702255D01*
G03X485034Y702407I-130J152D01*
G01Y703605D01*
G03X484964Y703757I-200J0D01*
G01X484734Y703954D01*
G03X484573Y704000I-130J-152D01*
G02X484341Y703982I-232J1484D01*
G37*
G36*
G01X512530Y716799D02*
G02Y719803I0J1502D01*
G02X514032Y718298I0J-1502D01*
G03X514094Y718153I200J0D01*
G01X514334Y717924D01*
X514412Y717896D01*
X514453Y717898D01*
G02X514530Y717900I77J-1500D01*
G01X514531D01*
G02Y714896I0J-1502D01*
G02X513029Y716401I0J1502D01*
G03X512967Y716546I-200J0D01*
G01X512727Y716775D01*
X512649Y716803D01*
X512608Y716801D01*
G02X512531Y716799I-77J1500D01*
G01X512530D01*
G37*
G36*
G01X483184Y661152D02*
G02X483059Y661147I-122J1497D01*
G02X484561Y662649I0J1502D01*
G01Y662648D01*
G02X484402Y661976I-1502J1D01*
G03X484807Y661400I357J-179D01*
G02X485005Y661412I198J-1629D01*
G02X483364Y659771I0J-1641D01*
G02X483567Y660561I1641J-1D01*
G03X483184Y661152I-350J193D01*
G37*
G36*
G01X976436Y606904D02*
G02X975460Y608311I526J1407D01*
G02X978464I1502J0D01*
G02X978195Y607453I-1503J0D01*
G03X978383Y606850I328J-228D01*
G02X979359Y605443I-526J-1407D01*
G02X976355I-1502J0D01*
G02X976624Y606301I1503J0D01*
G03X976436Y606904I-328J228D01*
G37*
G36*
G01X892143Y587404D02*
G02X890956Y586823I-1187J922D01*
G02Y589827I0J1502D01*
G02X892185Y589189I0J-1503D01*
G03X892828Y589174I327J230D01*
G02X894015Y589755I1187J-922D01*
G02Y586751I0J-1502D01*
G02X892786Y587389I0J1503D01*
G03X892143Y587404I-327J-230D01*
G37*
G36*
G01X988011Y576484D02*
G02X991015I1502J0D01*
G02X990373Y575253I-1501J0D01*
G03X990289Y575114I114J-164D01*
G01X990246Y574778D01*
X990270Y574697D01*
X990298Y574665D01*
G02X990658Y573689I-1143J-976D01*
G02X989937Y572406I-1502J0D01*
G01X989893Y572379D01*
X989842Y572291D01*
X989834Y571849D01*
X989881Y571759D01*
X989924Y571731D01*
G02X990598Y570478I-828J-1253D01*
G02X989096Y568976I-1502J0D01*
G02X987917Y569547I0J1503D01*
G01X987891Y569580D01*
X987817Y569619D01*
X987438Y569648D01*
X987360Y569620D01*
X987329Y569591D01*
G02X986301Y569184I-1028J1095D01*
G02X984799Y570686I0J1502D01*
G02X985300Y571806I1502J0D01*
G01X985329Y571831D01*
X985363Y571901D01*
X985388Y572215D01*
G03X985344Y572356I-199J15D01*
G02X985008Y573303I1167J947D01*
G02X986510Y574805I1502J0D01*
G02X987401Y574512I0J-1501D01*
G01X987402D01*
X987433Y574489D01*
X987509Y574470D01*
X987865Y574522D01*
X987934Y574563D01*
X987957Y574594D01*
G02X988296Y574920I1198J-906D01*
G03X988380Y575059I-114J164D01*
G01X988423Y575395D01*
X988399Y575476D01*
X988371Y575508D01*
G02X988011Y576484I1143J976D01*
G37*
G36*
G01X979817Y572121D02*
G02X978581Y571473I-1236J855D01*
G02Y574477I0J1502D01*
G02X979883Y573724I0J-1502D01*
G03X980559Y573696I347J199D01*
G02X981795Y574344I1236J-855D01*
G02Y571340I0J-1502D01*
G02X980493Y572093I0J1502D01*
G03X979817Y572121I-347J-199D01*
G37*
G36*
G01X788482Y573794D02*
G02X789316Y573589I-1J-1803D01*
G03X789455Y573572I92J178D01*
G01X789573Y573601D01*
G03X789689Y573680I-47J194D01*
G02X790978Y574348I1289J-910D01*
G02Y571190I0J-1579D01*
G02X790744Y571208I4J1579D01*
G01X790700Y571215D01*
X790617Y571191D01*
X790353Y570964D01*
G03X790284Y570812I131J-151D01*
G01Y569770D01*
G03X790353Y569618I200J-1D01*
G01X790617Y569391D01*
X790700Y569367D01*
X790744Y569374D01*
G02X790978Y569392I238J-1561D01*
G02Y566234I0J-1579D01*
G02X789689Y566902I0J1578D01*
G03X789573Y566981I-163J-115D01*
G01X789455Y567010D01*
G03X789316Y566993I-47J-195D01*
G02X788482Y566788I-835J1598D01*
G02X787648Y566993I1J1803D01*
G03X787509Y567010I-92J-178D01*
G01X787391Y566981D01*
G03X787275Y566902I47J-194D01*
G02X786217Y566251I-1290J911D01*
G01X786166Y566244D01*
X786085Y566183D01*
X785903Y565786D01*
X785909Y565686D01*
X785936Y565643D01*
G02X786167Y564843I-1270J-800D01*
G02X783163I-1502J0D01*
G02X784408Y566323I1502J0D01*
G01X784458Y566331D01*
X784537Y566393D01*
X784709Y566796D01*
X784700Y566895D01*
X784672Y566938D01*
G02X784408Y567813I1314J874D01*
G02X785986Y569392I1578J1D01*
G02X786220Y569374I-4J-1579D01*
G01X786264Y569367D01*
X786347Y569391D01*
X786611Y569618D01*
G03X786680Y569770I-131J151D01*
G01Y570812D01*
G03X786611Y570964I-200J1D01*
G01X786347Y571191D01*
X786264Y571215D01*
X786220Y571208D01*
G02X785986Y571190I-238J1561D01*
G02Y574348I0J1579D01*
G02X787275Y573680I0J-1578D01*
G03X787391Y573601I163J115D01*
G01X787509Y573572D01*
G03X787648Y573589I47J195D01*
G02X788482Y573794I835J-1598D01*
G37*
G36*
G01X990804Y566797D02*
G02X993808I1502J0D01*
G02X993176Y565573I-1501J0D01*
G03X993092Y565410I116J-163D01*
G01Y565084D01*
G03X993176Y564921I200J0D01*
G02X993808Y563697I-869J-1224D01*
G02X993402Y562670I-1502J0D01*
G01X993376Y562643D01*
X993348Y562572D01*
Y562222D01*
X993376Y562151D01*
X993402Y562124D01*
G02Y560070I-1096J-1027D01*
G01X993376Y560043D01*
X993348Y559972D01*
Y559622D01*
X993376Y559551D01*
X993402Y559524D01*
G02Y557470I-1096J-1027D01*
G01X993376Y557443D01*
X993348Y557372D01*
Y557022D01*
X993376Y556951D01*
X993402Y556924D01*
G02Y554870I-1096J-1027D01*
G01X993376Y554843D01*
X993348Y554772D01*
Y554422D01*
X993376Y554351D01*
X993402Y554324D01*
G02X993808Y553297I-1096J-1027D01*
G02X990804I-1502J0D01*
G02X991210Y554324I1502J0D01*
G01X991236Y554351D01*
X991264Y554422D01*
Y554772D01*
X991236Y554843D01*
X991210Y554870D01*
G02Y556924I1096J1027D01*
G01X991236Y556951D01*
X991264Y557022D01*
Y557372D01*
X991236Y557443D01*
X991210Y557470D01*
G02Y559524I1096J1027D01*
G01X991236Y559551D01*
X991264Y559622D01*
Y559972D01*
X991236Y560043D01*
X991210Y560070D01*
G02Y562124I1096J1027D01*
G01X991236Y562151D01*
X991264Y562222D01*
Y562572D01*
X991236Y562643D01*
X991210Y562670D01*
G02X990804Y563697I1096J1027D01*
G02X991436Y564921I1501J0D01*
G03X991520Y565084I-116J163D01*
G01Y565410D01*
G03X991436Y565573I-200J0D01*
G02X990804Y566797I869J1224D01*
G37*
G36*
G01X915949Y564865D02*
G02Y561861I0J-1502D01*
G02X915796Y561869I2J1502D01*
G01X915754Y561873D01*
X915674Y561847D01*
X915422Y561622D01*
G03X915355Y561475I133J-149D01*
G01Y561474D01*
G02X914716Y560258I-1502J13D01*
G03X914633Y560068I115J-163D01*
G01X914687Y559660D01*
X914756Y559574D01*
X914809Y559555D01*
G02X915798Y558143I-513J-1412D01*
G02X912794I-1502J0D01*
G02X913433Y559372I1501J0D01*
G03X913516Y559562I-115J163D01*
G01X913462Y559970D01*
X913393Y560056D01*
X913340Y560075D01*
G02X912351Y561487I513J1412D01*
G02X913853Y562989I1502J0D01*
G02X914006Y562981I-2J-1502D01*
G01X914048Y562977D01*
X914128Y563003D01*
X914380Y563228D01*
G03X914447Y563375I-133J149D01*
G01Y563376D01*
G02X915949Y564865I1502J-13D01*
G37*
G36*
G01X911903Y549479D02*
G02X910578Y548684I-1325J707D01*
G02Y551688I0J1502D01*
G02X911740Y551137I0J-1501D01*
G03X912403Y551202I310J253D01*
G02X913728Y551997I1325J-707D01*
G02Y548993I0J-1502D01*
G02X912566Y549544I0J1501D01*
G03X911903Y549479I-310J-253D01*
G37*
G36*
G01X976756Y545847D02*
X977050D01*
G03X977197Y545912I-1J200D01*
G02X978303Y546397I1106J-1019D01*
G02X979805Y544895I0J-1502D01*
G02X979226Y543710I-1502J0D01*
G03X979149Y543552I123J-158D01*
G01Y543238D01*
G03X979226Y543080I200J0D01*
G02X979805Y541895I-923J-1185D01*
G02X978303Y540393I-1502J0D01*
G02X977316Y540763I0J1501D01*
G01X977315D01*
Y540764D01*
G03X977185Y540812I-130J-152D01*
G01X976921D01*
G03X976791Y540764I0J-200D01*
G01X976790Y540763D01*
G02X975803Y540393I-987J1131D01*
G02X974301Y541895I0J1502D01*
G02X974773Y542988I1502J0D01*
G01X974774Y542989D01*
G03X974835Y543154I-138J145D01*
G01X974804Y543469D01*
G03X974710Y543619I-199J-20D01*
G02X974001Y544895I794J1276D01*
G02X975503Y546397I1502J0D01*
G02X976609Y545912I0J-1504D01*
G03X976756Y545847I148J135D01*
G37*
G36*
G01X881654Y537803D02*
G02X880693Y539204I541J1401D01*
G02X883697I1502J0D01*
G01Y539203D01*
G02X883286Y538171I-1502J0D01*
G03X883432Y537523I290J-275D01*
G02X884393Y536122I-541J-1401D01*
G02X881389I-1502J0D01*
G01Y536123D01*
G02X881800Y537155I1502J0D01*
G03X881654Y537803I-290J275D01*
G37*
G36*
G01X832780Y536085D02*
G02X835784I1502J0D01*
G02X835505Y535213I-1502J0D01*
G01X835477Y535174D01*
X835462Y535081D01*
X835593Y534682D01*
X835659Y534616D01*
X835705Y534601D01*
G02X836738Y533174I-469J-1427D01*
G02X835615Y531721I-1501J0D01*
G01X835573Y531710D01*
X835507Y531656D01*
X835353Y531349D01*
G03X835346Y531184I178J-90D01*
G02X835455Y530623I-1393J-562D01*
G01Y530621D01*
G02X832451I-1502J0D01*
G02X833574Y532074I1501J0D01*
G01X833616Y532085D01*
X833682Y532139D01*
X833836Y532446D01*
G03X833843Y532611I-178J90D01*
G02X833734Y533172I1393J562D01*
G01Y533174D01*
G02X834013Y534046I1502J0D01*
G01X834041Y534085D01*
X834056Y534178D01*
X833925Y534577D01*
X833859Y534643D01*
X833813Y534658D01*
G02X832780Y536085I469J1427D01*
G37*
G36*
G01X952531Y530446D02*
G02Y533450I0J1502D01*
G02X953755Y532819I0J-1503D01*
G01X953782Y532780D01*
X953866Y532736D01*
X954234Y532728D01*
G03X954396Y532805I4J200D01*
G02X955581Y533384I1185J-923D01*
G02X956568Y533014I0J-1501D01*
G01X956569D01*
Y533013D01*
G03X956699Y532965I130J152D01*
G01X956963D01*
G03X957093Y533013I0J200D01*
G01X957094Y533014D01*
G02X959068I987J-1131D01*
G01X959069D01*
Y533013D01*
G03X959199Y532965I130J152D01*
G01X959463D01*
G03X959593Y533013I0J200D01*
G01X959594Y533014D01*
G02X960581Y533384I987J-1131D01*
G02X962083Y531882I0J-1502D01*
G02X961816Y531027I-1502J0D01*
G01X961793Y530993D01*
X961776Y530912D01*
X961856Y530545D01*
X961904Y530478D01*
X961939Y530457D01*
G02X962668Y529169I-773J-1288D01*
G02X959664I-1502J0D01*
G02X959931Y530024I1502J0D01*
G01X959954Y530058D01*
X959971Y530139D01*
X959891Y530506D01*
X959843Y530573D01*
X959808Y530594D01*
G02X959595Y530750I777J1285D01*
G03X959593Y530751I-88J-173D01*
G03X959463Y530799I-130J-152D01*
G01X959199D01*
G03X959069Y530751I0J-200D01*
G01X959068Y530750D01*
G02X957094I-987J1131D01*
G01X957093D01*
Y530751D01*
G03X956963Y530799I-130J-152D01*
G01X956699D01*
G03X956569Y530751I0J-200D01*
G01X956568Y530750D01*
G02X955581Y530380I-987J1131D01*
G02X954357Y531011I0J1503D01*
G01X954330Y531050D01*
X954246Y531094D01*
X953878Y531102D01*
G03X953716Y531025I-4J-200D01*
G02X952531Y530446I-1185J923D01*
G37*
G36*
G01X939205Y529737D02*
G02X938325Y531104I622J1367D01*
G02X941329I1502J0D01*
G02X940579Y529804I-1502J0D01*
G03X940614Y529093I200J-347D01*
G02X941494Y527726I-622J-1367D01*
G02X938490I-1502J0D01*
G02X939240Y529026I1502J0D01*
G03X939205Y529737I-200J347D01*
G37*
G36*
G01X423229Y515952D02*
G02X426233I1502J0D01*
G02X425863Y514965I-1501J0D01*
G01Y514964D01*
X425862D01*
G03X425814Y514834I152J-130D01*
G01Y514570D01*
G03X425862Y514440I200J0D01*
G01X425863Y514439D01*
G02Y512465I-1131J-987D01*
G01Y512464D01*
X425862D01*
G03X425814Y512334I152J-130D01*
G01Y512070D01*
G03X425862Y511940I200J0D01*
G01X425863Y511939D01*
G02X426233Y510952I-1131J-987D01*
G02X425748Y509846I-1504J0D01*
G03X425683Y509699I135J-148D01*
G01Y509405D01*
G03X425748Y509258I200J1D01*
G02X425860Y509143I-1019J-1104D01*
G03X426208Y509245I150J132D01*
G02X427693Y510522I1485J-225D01*
G02X429195Y509020I0J-1502D01*
G02X428825Y508033I-1501J0D01*
G01Y508032D01*
X428824D01*
G03X428776Y507902I152J-130D01*
G01Y507638D01*
G03X428824Y507508I200J0D01*
G01X428825Y507507D01*
G02X429195Y506520I-1131J-987D01*
G02X427693Y505018I-1502J0D01*
G02X426191Y506519I0J1502D01*
G01Y506521D01*
G02X426192Y506562I1502J-16D01*
G03X426089Y506743I-200J6D01*
G01X425727Y506942D01*
X425616Y506937D01*
X425569Y506905D01*
G02X424732Y506650I-837J1247D01*
G01X424731D01*
G02X423229Y508152I0J1502D01*
G02X423714Y509258I1504J0D01*
G03X423779Y509405I-135J148D01*
G01Y509699D01*
G03X423714Y509846I-200J-1D01*
G02X423229Y510952I1019J1106D01*
G02X423599Y511939I1501J0D01*
G01Y511940D01*
X423600D01*
G03X423648Y512070I-152J130D01*
G01Y512334D01*
G03X423600Y512464I-200J0D01*
G01X423599Y512465D01*
G02Y514439I1131J987D01*
G01Y514440D01*
X423600D01*
G03X423648Y514570I-152J130D01*
G01Y514834D01*
G03X423600Y514964I-200J0D01*
G01X423599Y514965D01*
G02X423229Y515952I1131J987D01*
G37*
G36*
G01X450942Y507951D02*
G02Y504947I0J-1502D01*
G02X449955Y505317I0J1501D01*
G01X449954D01*
Y505318D01*
G03X449824Y505366I-130J-152D01*
G01X449560D01*
G03X449430Y505318I0J-200D01*
G01X449429Y505317D01*
G02X447455I-987J1131D01*
G01X447454D01*
Y505318D01*
G03X447324Y505366I-130J-152D01*
G01X447060D01*
G03X446930Y505318I0J-200D01*
G01X446929Y505317D01*
G02X445942Y504947I-987J1131D01*
G02X444669Y505652I0J1502D01*
G01X444641Y505697D01*
X444551Y505747D01*
X444158Y505744D01*
G03X443988Y505647I1J-200D01*
G02X442704Y504925I-1284J781D01*
G02Y507929I0J1502D01*
G02X443977Y507224I0J-1502D01*
G01X444005Y507179D01*
X444095Y507129D01*
X444488Y507132D01*
G03X444658Y507229I-1J200D01*
G02X445942Y507951I1284J-781D01*
G02X446929Y507581I0J-1501D01*
G01X446930D01*
Y507580D01*
G03X447060Y507532I130J152D01*
G01X447324D01*
G03X447454Y507580I0J200D01*
G01X447455Y507581D01*
G02X449429I987J-1131D01*
G01X449430D01*
Y507580D01*
G03X449560Y507532I130J152D01*
G01X449824D01*
G03X449954Y507580I0J200D01*
G01X449955Y507581D01*
G02X450942Y507951I987J-1131D01*
G37*
G36*
G01X986587Y499103D02*
X986881D01*
G03X987028Y499168I-1J200D01*
G02X988134Y499653I1106J-1019D01*
G02X989636Y498151I0J-1502D01*
G02X989057Y496966I-1502J0D01*
G03X988980Y496808I123J-158D01*
G01Y496494D01*
G03X989057Y496336I200J0D01*
G02X989636Y495151I-923J-1185D01*
G02X988134Y493649I-1502J0D01*
G02X987147Y494019I0J1501D01*
G01X987146D01*
Y494020D01*
G03X987016Y494068I-130J-152D01*
G01X986752D01*
G03X986622Y494020I0J-200D01*
G01X986621Y494019D01*
G02X985634Y493649I-987J1131D01*
G02X984132Y495151I0J1502D01*
G02X984604Y496244I1502J0D01*
G01X984605Y496245D01*
G03X984666Y496410I-138J145D01*
G01X984635Y496725D01*
G03X984541Y496875I-199J-20D01*
G02X983832Y498151I794J1276D01*
G02X985334Y499653I1502J0D01*
G02X986440Y499168I0J-1504D01*
G03X986587Y499103I148J135D01*
G37*
G36*
G01X665167Y497464D02*
G02Y494306I0J-1579D01*
G02X664900Y494329I2J1579D01*
G03X664737Y494285I-34J-197D01*
G01X664641Y494203D01*
G03X664570Y494049I129J-153D01*
G01Y490641D01*
Y490634D01*
G03X664641Y490480I200J-1D01*
G01X664737Y490398D01*
G03X664900Y490354I129J153D01*
G02X665167Y490376I263J-1556D01*
G02X666222Y489972I0J-1580D01*
G03X666355Y489921I133J149D01*
G01X666479D01*
G03X666612Y489972I0J200D01*
G02X667667Y490376I1055J-1176D01*
G02X669226Y489048I0J-1579D01*
G01X669232Y489007D01*
X669276Y488937D01*
X669548Y488750D01*
G03X669701Y488719I113J165D01*
G01X669702D01*
G02X670067Y488756I363J-1765D01*
G02X670432Y488719I2J-1802D01*
G01X670433D01*
G03X670586Y488750I40J196D01*
G01X670858Y488937D01*
X670902Y489007D01*
X670908Y489048D01*
G02X672467Y490376I1559J-251D01*
G02Y487220I0J-1578D01*
G02X672200Y487242I-4J1578D01*
G03X672037Y487198I-34J-197D01*
G01X671941Y487116D01*
G03X671870Y486962I129J-153D01*
G01Y483554D01*
Y483547D01*
G03X671941Y483393I200J-1D01*
G01X672037Y483311D01*
G03X672200Y483267I129J153D01*
G02X672467Y483290I269J-1556D01*
G02Y480132I0J-1579D01*
G02X670908Y481461I0J1579D01*
G01X670902Y481502D01*
X670859Y481570D01*
X670586Y481758D01*
G03X670433Y481789I-113J-165D01*
G01X670432D01*
G02X670067Y481752I-363J1765D01*
G02X669702Y481789I-2J1802D01*
G01X669701D01*
G03X669548Y481758I-40J-196D01*
G01X669275Y481570D01*
X669232Y481502D01*
X669226Y481461D01*
G02X667667Y480132I-1559J250D01*
G02X666612Y480537I1J1579D01*
G03X666479Y480588I-133J-149D01*
G01X666355D01*
G03X666222Y480537I0J-200D01*
G02X665167Y480132I-1056J1174D01*
G02X664900Y480155I2J1579D01*
G03X664737Y480111I-34J-197D01*
G01X664641Y480029D01*
G03X664570Y479875I129J-153D01*
G01Y476468D01*
Y476461D01*
G03X664641Y476307I200J-1D01*
G01X664737Y476225D01*
G03X664900Y476181I129J153D01*
G02X665167Y476204I269J-1556D01*
G02X666222Y475799I-1J-1579D01*
G03X666355Y475748I133J149D01*
G01X666479D01*
G03X666612Y475799I0J200D01*
G02X667667Y476204I1056J-1174D01*
G02X669226Y474875I0J-1579D01*
G01X669232Y474834D01*
X669276Y474764D01*
X669548Y474577D01*
G03X669701Y474546I113J165D01*
G01X669702D01*
G02X670067Y474584I368J-1765D01*
G02X670431Y474546I-4J-1803D01*
G01X670433D01*
G03X670586Y474577I40J196D01*
G01X670858Y474764D01*
X670902Y474834D01*
X670908Y474875D01*
G02X672467Y476204I1559J-250D01*
G02Y473046I0J-1579D01*
G02X672200Y473069I2J1579D01*
G03X672037Y473025I-34J-197D01*
G01X671941Y472943D01*
G03X671870Y472789I129J-153D01*
G01Y469381D01*
Y469374D01*
G03X671941Y469220I200J-1D01*
G01X672037Y469138D01*
G03X672200Y469094I129J153D01*
G02X672467Y469116I263J-1556D01*
G02X674046Y467539I1J-1578D01*
G01Y467537D01*
G02X674037Y467377I-1579J9D01*
G01X674031Y467323D01*
X674075Y467225D01*
X674403Y466991D01*
G03X674603Y466973I116J163D01*
G01X674604D01*
G02X675237Y467113I633J-1361D01*
G02X673735Y465611I0J-1502D01*
G02X673740Y465731I1502J-2D01*
G01X673744Y465785D01*
X673698Y465882D01*
X673365Y466108D01*
G03X673165Y466122I-112J-166D01*
G01X673164D01*
G02X672468Y465960I-696J1416D01*
G01X672467D01*
G02X670908Y467288I0J1579D01*
G01X670902Y467329D01*
X670859Y467397D01*
X670586Y467585D01*
G03X670433Y467616I-113J-165D01*
G01X670432D01*
G02X670067Y467578I-368J1765D01*
G02X669703Y467616I4J1803D01*
G01X669701D01*
G03X669548Y467585I-40J-196D01*
G01X669275Y467397D01*
X669232Y467329D01*
X669226Y467288D01*
G02X667667Y465960I-1559J251D01*
G02Y469116I0J1578D01*
G02X667934Y469094I4J-1578D01*
G03X668097Y469138I34J197D01*
G01X668193Y469220D01*
G03X668264Y469374I-129J153D01*
G01Y472781D01*
Y472789D01*
G03X668193Y472943I-200J1D01*
G01X668097Y473025D01*
G03X667934Y473069I-129J-153D01*
G02X667667Y473046I-269J1556D01*
G02X666612Y473451I1J1579D01*
G03X666479Y473502I-133J-149D01*
G01X666355D01*
G03X666222Y473451I0J-200D01*
G02X665167Y473046I-1056J1174D01*
G02X663608Y474375I0J1579D01*
G01X663602Y474416D01*
X663559Y474484D01*
X663286Y474672D01*
G03X663133Y474703I-113J-165D01*
G01X663132D01*
G02X662767Y474666I-363J1765D01*
G02X662339Y474717I-2J1802D01*
G01X662298Y474727D01*
X662217Y474713D01*
X661936Y474526D01*
G03X661849Y474392I110J-167D01*
G01Y474391D01*
G02X660366Y473124I-1483J234D01*
G02Y476128I0J1502D01*
G02X660635Y476104I2J-1502D01*
G03X660801Y476149I36J197D01*
G01X660897Y476231D01*
G03X660966Y476392I-131J151D01*
G02X660964Y476468I1801J85D01*
G01Y479868D01*
G02X660966Y479946I1803J-7D01*
G03X660897Y480107I-200J10D01*
G01X660801Y480190D01*
G03X660634Y480235I-130J-152D01*
G02X660366Y480211I-267J1478D01*
G02Y483215I0J1502D01*
G02X661850Y481946I0J-1502D01*
G01X661856Y481904D01*
X661901Y481834D01*
X662218Y481623D01*
X662299Y481609D01*
X662340Y481619D01*
G02X662767Y481670I426J-1751D01*
G02X663132Y481633I2J-1802D01*
G01X663133D01*
G03X663286Y481664I40J196D01*
G01X663559Y481852D01*
X663602Y481920D01*
X663608Y481961D01*
G02X665167Y483290I1559J-250D01*
G02X666222Y482885I-1J-1579D01*
G03X666355Y482834I133J149D01*
G01X666479D01*
G03X666612Y482885I0J200D01*
G02X667667Y483290I1056J-1174D01*
G02X667934Y483267I-2J-1579D01*
G03X668097Y483311I34J197D01*
G01X668193Y483393D01*
G03X668264Y483547I-129J153D01*
G01Y486954D01*
Y486962D01*
G03X668193Y487116I-200J1D01*
G01X668097Y487198D01*
G03X667934Y487242I-129J-153D01*
G02X667667Y487220I-263J1556D01*
G02X666612Y487624I0J1580D01*
G03X666479Y487675I-133J-149D01*
G01X666355D01*
G03X666222Y487624I0J-200D01*
G02X665167Y487220I-1055J1176D01*
G02X663608Y488548I0J1579D01*
G01X663602Y488589D01*
X663559Y488657D01*
X663286Y488845D01*
G03X663133Y488876I-113J-165D01*
G01X663132D01*
G02X662767Y488838I-368J1765D01*
G02X662339Y488890I2J1803D01*
G01X662298Y488900D01*
X662217Y488886D01*
X661936Y488699D01*
G03X661849Y488565I110J-167D01*
G01Y488564D01*
G02X660366Y487297I-1483J234D01*
G02Y490301I0J1502D01*
G02X660635Y490277I2J-1502D01*
G03X660801Y490322I36J197D01*
G01X660897Y490404D01*
G03X660966Y490565I-131J151D01*
G02X660964Y490641I1801J85D01*
G01Y494041D01*
G02X660966Y494119I1803J-7D01*
G03X660897Y494280I-200J10D01*
G01X660801Y494363D01*
G03X660634Y494408I-130J-152D01*
G02X660366Y494384I-267J1478D01*
G02Y497388I0J1502D01*
G02X661850Y496119I0J-1502D01*
G01X661856Y496077D01*
X661901Y496007D01*
X662218Y495796D01*
X662299Y495782D01*
X662340Y495792D01*
G02X662767Y495844I430J-1751D01*
G02X663131Y495806I-4J-1803D01*
G01X663133D01*
G03X663286Y495837I40J196D01*
G01X663558Y496024D01*
X663602Y496094D01*
X663608Y496135D01*
G02X665167Y497464I1559J-250D01*
G37*
G36*
G01X858961Y496338D02*
X887905D01*
G02X888827Y495956I-1J-1306D01*
G01X901928Y482855D01*
G03X902070Y482796I142J141D01*
G01X921458D01*
G02X922382Y482413I0J-1306D01*
G01X925364Y479431D01*
G03X925444Y479382I142J141D01*
G01X925445D01*
G02X926501Y477948I-446J-1434D01*
G02X924999Y476446I-1502J0D01*
G02X923565Y477501I0J1502D01*
G01Y477503D01*
G03X923516Y477583I-190J-62D01*
G01X923161Y477938D01*
G03X922957Y477987I-142J-141D01*
G01X922565Y477859D01*
X922492Y477773D01*
X922483Y477717D01*
G02X920999Y476446I-1484J231D01*
G02X919497Y477948I0J1502D01*
G02X920768Y479432I1502J0D01*
G01X920824Y479441D01*
X920910Y479514D01*
X921038Y479906D01*
G03X920989Y480110I-190J62D01*
G01X920976Y480123D01*
G03X920834Y480182I-142J-141D01*
G01X901446D01*
G02X900522Y480565I0J1306D01*
G01X887421Y493667D01*
G03X887279Y493726I-142J-141D01*
G01X858961D01*
G03X858868Y493703I0J-200D01*
G02X858169Y493530I-700J1329D01*
G02Y496534I0J1502D01*
G02X858868Y496361I-1J-1502D01*
G03X858961Y496338I93J177D01*
G37*
G36*
G01X385296Y485889D02*
G02X385133Y485880I-164J1493D01*
G01X385131D01*
G02X386633Y487382I0J1502D01*
G01Y487381D01*
G02X386554Y486901I-1502J1D01*
G03X386976Y486375I379J-128D01*
G02X387139Y486384I164J-1493D01*
G01X387141D01*
G02X385639Y484882I0J-1502D01*
G01Y484883D01*
G02X385718Y485363I1502J-1D01*
G03X385296Y485889I-379J128D01*
G37*
G36*
G01X832331Y483240D02*
G02X831057Y482534I-1274J796D01*
G02Y485538I0J1502D01*
G02X832277Y484912I0J-1502D01*
G03X832941Y484934I325J234D01*
G02X834215Y485640I1274J-796D01*
G02Y482636I0J-1502D01*
G02X832995Y483262I0J1502D01*
G03X832331Y483240I-325J-234D01*
G37*
G36*
G01X842433Y480881D02*
G02X840974Y482382I43J1501D01*
G02X843978I1502J0D01*
G01Y482380D01*
G02X843902Y481909I-1502J1D01*
G03X844270Y481383I380J-126D01*
G02X845729Y479882I-43J-1501D01*
G02X842725I-1502J0D01*
G01Y479884D01*
G02X842801Y480355I1502J-1D01*
G03X842433Y480881I-380J126D01*
G37*
G36*
G01X963177Y474629D02*
X963410Y474432D01*
G03X963571Y474387I129J152D01*
G01X963572D01*
G02X963816Y474407I244J-1482D01*
G02X965318Y472905I0J-1502D01*
G02X964788Y471760I-1502J0D01*
G01X964740Y471719D01*
X964708Y471599D01*
X964860Y471187D01*
G03X965048Y471056I188J69D01*
G01X966584D01*
G03X966772Y471187I0J200D01*
G01X966924Y471599D01*
X966892Y471719D01*
X966844Y471760D01*
G02X966314Y472905I972J1145D01*
G02X967719Y474404I1502J0D01*
G01X967772Y474407D01*
X967861Y474465D01*
X968064Y474868D01*
X968059Y474973D01*
X968030Y475018D01*
G02X967795Y475825I1268J807D01*
G02X968280Y476931I1504J0D01*
G03X968345Y477078I-135J148D01*
G01Y477372D01*
G03X968280Y477519I-200J-1D01*
G02X967795Y478625I1019J1106D01*
G02X970799I1502J0D01*
G02X970314Y477519I-1504J0D01*
G03X970249Y477372I135J-148D01*
G01Y477078D01*
G03X970314Y476931I200J1D01*
G02X970799Y475825I-1019J-1106D01*
G02X969394Y474326I-1502J0D01*
G01X969341Y474323D01*
X969252Y474265D01*
X969049Y473862D01*
X969054Y473757D01*
X969083Y473712D01*
G02X969318Y472905I-1268J-807D01*
G02X968788Y471760I-1502J0D01*
G01X968740Y471719D01*
X968708Y471599D01*
X968860Y471187D01*
G03X969048Y471056I188J69D01*
G01X971225D01*
G03X971414Y471191I0J200D01*
G01X971538Y471548D01*
G03X971472Y471771I-189J65D01*
G02X970895Y472954I924J1183D01*
G02X972397Y474456I1502J0D01*
G02X973870Y473247I0J-1502D01*
G01Y473245D01*
X973881Y473191D01*
X973954Y473111D01*
X974346Y472991D01*
G03X974546Y473041I58J191D01*
G01X974914Y473410D01*
G03X974963Y473490I-141J142D01*
G01Y473491D01*
G02X977831Y473492I1434J-445D01*
G01Y473490D01*
G03X977880Y473410I190J62D01*
G01X978235Y473055D01*
G03X978439Y473006I142J141D01*
G01X978831Y473134D01*
X978904Y473220D01*
X978913Y473276D01*
G02X980397Y474547I1484J-231D01*
G02X981899Y473045I0J-1502D01*
G02X980628Y471561I-1502J0D01*
G01X980572Y471552D01*
X980486Y471479D01*
X980358Y471087D01*
G03X980407Y470883I190J-62D01*
G01X980829Y470461D01*
G03X980971Y470402I142J141D01*
G01X988660D01*
G02X989584Y470019I0J-1306D01*
G01X1000521Y459081D01*
G03X1000663Y459022I142J141D01*
G01X1056116D01*
G02X1057038Y458640I-1J-1306D01*
G01X1057368Y458310D01*
G03X1057592Y458269I142J141D01*
G01X1057990Y458449D01*
X1058054Y458556D01*
X1058050Y458617D01*
G02X1058047Y458711I1499J95D01*
G02X1059549Y460213I1502J0D01*
G02X1060655Y459728I0J-1504D01*
G03X1060802Y459663I148J135D01*
G01X1061096D01*
G03X1061243Y459728I-1J200D01*
G02X1062349Y460213I1106J-1019D01*
G02X1063851Y458711I0J-1502D01*
G02X1063591Y457867I-1502J1D01*
G01Y457866D01*
X1063566Y457830D01*
X1063552Y457746D01*
X1063656Y457365D01*
X1063712Y457299D01*
X1063752Y457280D01*
G02X1064615Y455921I-639J-1359D01*
G01Y455918D01*
G02X1064591Y455652I-1502J1D01*
G01X1064583Y455610D01*
X1064604Y455527D01*
X1064843Y455224D01*
X1064919Y455184D01*
X1064962Y455182D01*
G02X1066378Y453682I-86J-1500D01*
G02X1063374I-1502J0D01*
G01Y453685D01*
G02X1063398Y453951I1502J-1D01*
G01X1063406Y453993D01*
X1063385Y454076D01*
X1063146Y454379D01*
X1063070Y454419D01*
X1063027Y454421D01*
G02X1062416Y454591I88J1499D01*
G03X1062412Y454593I-91J-178D01*
G01X1062391Y454604D01*
X1062347Y454614D01*
X1057909D01*
G02X1056985Y454997I0J1306D01*
G01X1055632Y456351D01*
G03X1055490Y456410I-142J-141D01*
G01X1000037D01*
G02X999115Y456792I1J1306D01*
G01X988178Y467729D01*
G03X988036Y467788I-142J-141D01*
G01X980347D01*
G02X979423Y468171I0J1306D01*
G01X976538Y471056D01*
G03X976256I-141J-142D01*
G01X974025Y468825D01*
G02X973101Y468442I-924J923D01*
G01X962564D01*
G02X961640Y468825I0J1306D01*
G01X960876Y469589D01*
G02X960494Y470511I924J923D01*
G01Y471023D01*
G03X960425Y471175I-200J1D01*
G01X960195Y471373D01*
G03X960036Y471419I-130J-152D01*
G01X960035D01*
G02X959817Y471403I-219J1486D01*
G01X959816D01*
G02Y474407I0J1502D01*
G01X959817D01*
G02X960035Y474391I-1J-1502D01*
G01X960036D01*
G03X960195Y474437I29J198D01*
G01X960425Y474635D01*
G03X960494Y474787I-131J151D01*
G01Y478477D01*
G03X960435Y478619I-200J0D01*
G01X958371Y480682D01*
G03X958291Y480731I-142J-141D01*
G01X958290D01*
G02X957234Y482165I446J1434D01*
G02X958736Y483667I1502J0D01*
G02X960170Y482612I0J-1502D01*
G01Y482610D01*
G03X960219Y482530I190J62D01*
G01X962724Y480025D01*
G02X963106Y479103I-924J-923D01*
G01Y474782D01*
G03X963177Y474629I200J0D01*
G37*
G36*
G01X817328Y473555D02*
G02X818830Y472053I0J-1502D01*
G02X818131Y470783I-1503J0D01*
G03X818038Y470611I107J-169D01*
G01X818043Y470270D01*
G03X818142Y470101I200J4D01*
G02X818882Y468806I-763J-1295D01*
G02X817380Y467304I-1502J0D01*
G02X816274Y467789I0J1504D01*
G03X816127Y467854I-148J-135D01*
G01X815833D01*
G03X815686Y467789I1J-200D01*
G02X814580Y467304I-1106J1019D01*
G02X813078Y468806I0J1502D01*
G02X813904Y470147I1502J0D01*
G03X814014Y470311I-90J179D01*
G01X814043Y470705D01*
X813999Y470800D01*
X813956Y470830D01*
G02X813326Y472053I872J1223D01*
G02X814828Y473555I1502J0D01*
G02X815815Y473185I0J-1501D01*
G01X815816D01*
Y473184D01*
G03X815946Y473136I130J152D01*
G01X816210D01*
G03X816340Y473184I0J200D01*
G01X816341Y473185D01*
G02X817328Y473555I987J-1131D01*
G37*
G36*
G01X472907Y469208D02*
G02X472156Y470509I751J1301D01*
G02X475160I1502J0D01*
G02X474409Y469208I-1502J0D01*
G03Y468516I200J-346D01*
G02X475160Y467215I-751J-1301D01*
G02X472156I-1502J0D01*
G02X472907Y468516I1502J0D01*
G03Y469208I-200J346D01*
G37*
G36*
G01X970895Y465004D02*
G02X973899I1502J0D01*
G02X972540Y463509I-1502J0D01*
G03X972386Y463411I19J-199D01*
G01X972223Y463131D01*
G03X972213Y462948I173J-101D01*
G02X972342Y462339I-1373J-609D01*
G02X971972Y461352I-1501J0D01*
G01Y461351D01*
X971971D01*
G03X971923Y461221I152J-130D01*
G01Y460957D01*
G03X971971Y460827I200J0D01*
G01X971972Y460826D01*
G02Y458852I-1131J-987D01*
G01Y458851D01*
X971971D01*
G03X971923Y458721I152J-130D01*
G01Y458457D01*
G03X971971Y458327I200J0D01*
G01X971972Y458326D01*
G02X972342Y457339I-1131J-987D01*
G02X970840Y455837I-1502J0D01*
G02X969853Y456207I0J1501D01*
G01X969852D01*
Y456208D01*
G03X969722Y456256I-130J-152D01*
G01X969458D01*
G03X969328Y456208I0J-200D01*
G01X969327Y456207D01*
G02X968340Y455837I-987J1131D01*
G02X966838Y457339I0J1502D01*
G02X967208Y458326I1501J0D01*
G01Y458327D01*
X967209D01*
G03X967257Y458457I-152J130D01*
G01Y458721D01*
G03X967209Y458851I-200J0D01*
G01X967208Y458852D01*
G02Y460826I1131J987D01*
G01Y460827D01*
X967209D01*
G03X967257Y460957I-152J130D01*
G01Y461221D01*
G03X967209Y461351I-200J0D01*
G01X967208Y461352D01*
G02X966838Y462339I1131J987D01*
G02X968340Y463841I1502J0D01*
G02X969327Y463471I0J-1501D01*
G01X969328D01*
Y463470D01*
G03X969458Y463422I130J152D01*
G01X969722D01*
G03X969852Y463470I0J200D01*
G01X969853Y463471D01*
G02X970697Y463834I987J-1132D01*
G03X970851Y463932I-19J199D01*
G01X971014Y464212D01*
G03X971024Y464395I-173J101D01*
G02X970895Y465004I1373J609D01*
G37*
G36*
G01X467848Y466068D02*
G02X469111Y465378I0J-1501D01*
G03X469280Y465286I168J108D01*
G01X469616D01*
G03X469785Y465378I1J200D01*
G02X471048Y466068I1263J-811D01*
G02Y463064I0J-1502D01*
G02X469785Y463754I0J1501D01*
G03X469616Y463846I-168J-108D01*
G01X469280D01*
G03X469111Y463754I-1J-200D01*
G02X467848Y463064I-1263J811D01*
G02X466663Y463643I0J1502D01*
G03X466505Y463720I-158J-123D01*
G01X466191D01*
G03X466033Y463643I0J-200D01*
G02X464848Y463064I-1185J923D01*
G02Y466068I0J1502D01*
G02X466033Y465489I0J-1502D01*
G03X466191Y465412I158J123D01*
G01X466505D01*
G03X466663Y465489I0J200D01*
G02X467848Y466068I1185J-923D01*
G37*
G36*
G01X426280Y464026D02*
G02X429284I1502J0D01*
G02X429227Y463618I-1502J2D01*
G01Y463616D01*
G03X429262Y463440I193J-53D01*
G01X429461Y463185D01*
G03X429624Y463108I158J123D01*
G01X429625D01*
G02X429672Y463109I55J-1501D01*
G01X429674D01*
G02X431175Y461607I-1J-1502D01*
G02X428171I-1502J0D01*
G02X428228Y462015I1502J-2D01*
G01Y462017D01*
G03X428193Y462193I-193J53D01*
G01X427994Y462448D01*
G03X427831Y462525I-158J-123D01*
G01X427830D01*
G02X427783Y462524I-55J1501D01*
G01X427781D01*
G02X427557Y462541I1J1502D01*
G01X427506Y462549D01*
X427411Y462513D01*
X427121Y462182D01*
X427099Y462082D01*
X427114Y462032D01*
G02X427175Y461610I-1441J-424D01*
G01Y461607D01*
G02X425673Y463109I-1502J0D01*
G02X425898Y463092I0J-1502D01*
G01X425949Y463084D01*
X426044Y463120D01*
X426334Y463451D01*
X426356Y463551D01*
X426341Y463601D01*
G02X426280Y464023I1441J424D01*
G01Y464026D01*
G37*
G36*
G01X918620Y460230D02*
G02X917549Y459668I-1071J739D01*
G02Y462272I0J1302D01*
G02X918620Y461710I0J-1301D01*
G03X919278I329J228D01*
G02X920349Y462272I1071J-739D01*
G02Y459668I0J-1302D01*
G02X919278Y460230I0J1301D01*
G03X918620I-329J-228D01*
G37*
G36*
G01Y456687D02*
G02X917549Y456125I-1071J739D01*
G02Y458729I0J1302D01*
G02X918620Y458167I0J-1301D01*
G03X919278I329J228D01*
G02X920349Y458729I1071J-739D01*
G02Y456125I0J-1302D01*
G02X919278Y456687I0J1301D01*
G03X918620I-329J-228D01*
G37*
G36*
G01X366813Y454733D02*
G02X366062Y456034I751J1301D01*
G02X369066I1502J0D01*
G02X368315Y454733I-1502J0D01*
G03Y454041I200J-346D01*
G02X369066Y452740I-751J-1301D01*
G02X366062I-1502J0D01*
G02X366813Y454041I1502J0D01*
G03Y454733I-200J346D01*
G37*
G36*
G01X918620Y453144D02*
G02X917549Y452582I-1071J739D01*
G02Y455186I0J1302D01*
G02X918620Y454624I0J-1301D01*
G03X919278I329J228D01*
G02X920349Y455186I1071J-739D01*
G02Y452582I0J-1302D01*
G02X919278Y453144I0J1301D01*
G03X918620I-329J-228D01*
G37*
G36*
G01X926134Y452505D02*
G02X929138I1502J0D01*
G02X929113Y452234I-1502J2D01*
G01X929106Y452195D01*
X929121Y452122D01*
X929291Y451860D01*
G03X929411Y451774I168J108D01*
G02X930552Y450316I-361J-1458D01*
G02X929194Y448821I-1502J0D01*
G01X929193D01*
G03X929034Y448712I20J-199D01*
G01X928858Y448365D01*
X928862Y448263D01*
X928888Y448219D01*
G02X929098Y447453I-1292J-766D01*
G02X926094I-1502J0D01*
G02X927452Y448948I1502J0D01*
G01X927453D01*
G03X927612Y449057I-20J199D01*
G01X927788Y449404D01*
X927784Y449506D01*
X927758Y449550D01*
G02X927548Y450316I1292J766D01*
G02X927573Y450587I1502J-2D01*
G01X927580Y450626D01*
X927565Y450699D01*
X927395Y450961D01*
G03X927275Y451047I-168J-108D01*
G02X926134Y452505I361J1458D01*
G37*
G36*
G01X981168Y450201D02*
G02X984172I1502J0D01*
G02X983673Y449083I-1502J0D01*
G01X983639Y449053D01*
X983605Y448971D01*
X983620Y448617D01*
G03X983699Y448466I200J8D01*
G02X984294Y447269I-907J-1197D01*
G02X982792Y445767I-1502J0D01*
G02X982018Y445982I0J1501D01*
G01X981971Y446010D01*
X981862Y446011D01*
X981464Y445781D01*
X981411Y445686D01*
X981412Y445632D01*
Y445603D01*
G02X979910Y447105I-1502J0D01*
G02X980684Y446890I0J-1501D01*
G01X980731Y446862D01*
X980840Y446861D01*
X981238Y447091D01*
X981291Y447186D01*
X981290Y447240D01*
Y447269D01*
G02X981789Y448387I1502J0D01*
G01X981823Y448417D01*
X981857Y448499D01*
X981842Y448853D01*
G03X981763Y449004I-200J-8D01*
G02X981168Y450201I907J1197D01*
G37*
G36*
G01X918620Y449600D02*
G02X917549Y449038I-1071J739D01*
G02Y451642I0J1302D01*
G02X918620Y451080I0J-1301D01*
G03X919278I329J228D01*
G02X920349Y451642I1071J-739D01*
G02Y449038I0J-1302D01*
G02X919278Y449600I0J1301D01*
G03X918620I-329J-228D01*
G37*
G36*
G01X972372Y448162D02*
G02X972193Y448872I1323J711D01*
G01Y448874D01*
G02X975197I1502J0D01*
G02X973703Y447372I-1502J0D01*
G03X973353Y446783I2J-400D01*
G02X973532Y446073I-1323J-711D01*
G01Y446071D01*
G02X970528I-1502J0D01*
G02X972022Y447573I1502J0D01*
G03X972372Y448162I-2J400D01*
G37*
G36*
G01X423294Y443889D02*
G02X422223Y443327I-1071J739D01*
G02Y445931I0J1302D01*
G02X423294Y445369I0J-1301D01*
G03X423952I329J228D01*
G02X425023Y445931I1071J-739D01*
G02Y443327I0J-1302D01*
G02X423952Y443889I0J1301D01*
G03X423294I-329J-228D01*
G37*
G36*
G01X818840Y445593D02*
G02X820103Y444903I0J-1501D01*
G03X820272Y444811I168J108D01*
G01X820608D01*
G03X820777Y444903I1J200D01*
G02X822040Y445593I1263J-811D01*
G02Y442589I0J-1502D01*
G02X820777Y443279I0J1501D01*
G03X820608Y443371I-168J-108D01*
G01X820272D01*
G03X820103Y443279I-1J-200D01*
G02X818840Y442589I-1263J811D01*
G02X817655Y443168I0J1502D01*
G03X817497Y443245I-158J-123D01*
G01X817183D01*
G03X817025Y443168I0J-200D01*
G02X816972Y443104I-1183J926D01*
G03X816925Y442948I151J-131D01*
G01X816940Y442821D01*
G03X817026Y442681I198J25D01*
G02X817679Y441442I-849J-1239D01*
G02X816177Y439940I-1502J0D01*
G02X815090Y440405I0J1503D01*
G01X815062Y440435D01*
X814989Y440466D01*
X814661Y440470D01*
G03X814519Y440413I-2J-200D01*
G01X814518Y440412D01*
G02X813456Y439972I-1062J1062D01*
G02X811959Y441355I0J1502D01*
G01Y441357D01*
G03X811860Y441513I-199J-17D01*
G01X811575Y441678D01*
G03X811389Y441686I-101J-173D01*
G02X810750Y441543I-640J1359D01*
G01X810749D01*
G02Y444547I0J1502D01*
G02X812246Y443164I0J-1502D01*
G01Y443162D01*
G03X812345Y443006I199J17D01*
G01X812630Y442841D01*
G03X812816Y442833I101J173D01*
G02X813455Y442976I640J-1359D01*
G01X813456D01*
G02X814612Y442433I0J-1502D01*
G03X814763Y442361I154J128D01*
G01X814891Y442359D01*
G03X815044Y442428I2J200D01*
G01X815045Y442429D01*
G03X815093Y442585I-151J132D01*
G01X815077Y442712D01*
G03X814991Y442852I-198J-25D01*
G02X814338Y444091I849J1239D01*
G02X815840Y445593I1502J0D01*
G02X817025Y445014I0J-1502D01*
G03X817183Y444937I158J123D01*
G01X817497D01*
G03X817655Y445014I0J200D01*
G02X818840Y445593I1185J-923D01*
G37*
G36*
G01X740001Y443180D02*
G02X743005I1502J0D01*
G02X742200Y441850I-1501J0D01*
G01X742199D01*
G03X742094Y441688I94J-176D01*
G01X742068Y441350D01*
G03X742149Y441173I199J-16D01*
G02X742761Y439963I-890J-1210D01*
G02X742219Y438808I-1502J0D01*
G03X742147Y438657I128J-154D01*
G01X742142Y438353D01*
G03X742210Y438200I200J-3D01*
G02X742720Y437072I-992J-1128D01*
G02X739716I-1502J0D01*
G02X740258Y438227I1502J0D01*
G03X740330Y438378I-128J154D01*
G01X740335Y438682D01*
G03X740267Y438835I-200J3D01*
G02X739757Y439963I992J1128D01*
G02X740562Y441293I1501J0D01*
G01X740563D01*
G03X740668Y441455I-94J176D01*
G01X740694Y441793D01*
G03X740613Y441970I-199J16D01*
G02X740001Y443180I890J1210D01*
G37*
G36*
G01X423294Y440346D02*
G02X422223Y439784I-1071J739D01*
G02Y442388I0J1302D01*
G02X423294Y441826I0J-1301D01*
G03X423952I329J228D01*
G02X425023Y442388I1071J-739D01*
G02Y439784I0J-1302D01*
G02X423952Y440346I0J1301D01*
G03X423294I-329J-228D01*
G37*
G36*
G01Y436803D02*
G02X422223Y436241I-1071J739D01*
G02Y438845I0J1302D01*
G02X423294Y438283I0J-1301D01*
G03X423952I329J228D01*
G02X425023Y438845I1071J-739D01*
G02Y436241I0J-1302D01*
G02X423952Y436803I0J1301D01*
G03X423294I-329J-228D01*
G37*
G36*
G01X430808Y436164D02*
G02X433812I1502J0D01*
G02X433787Y435893I-1502J2D01*
G01X433780Y435854D01*
X433795Y435781D01*
X433965Y435519D01*
G03X434085Y435433I168J108D01*
G02X435226Y433975I-361J-1458D01*
G02X433868Y432480I-1502J0D01*
G01X433867D01*
G03X433708Y432371I20J-199D01*
G01X433532Y432024D01*
X433536Y431922D01*
X433562Y431878D01*
G02X433772Y431112I-1292J-766D01*
G02X430768I-1502J0D01*
G02X432126Y432607I1502J0D01*
G01X432127D01*
G03X432286Y432716I-20J199D01*
G01X432462Y433063D01*
X432458Y433165D01*
X432432Y433209D01*
G02X432222Y433975I1292J766D01*
G02X432247Y434246I1502J-2D01*
G01X432254Y434285D01*
X432239Y434358D01*
X432069Y434620D01*
G03X431949Y434706I-168J-108D01*
G02X430808Y436164I361J1458D01*
G37*
G36*
G01X423294Y433259D02*
G02X422223Y432697I-1071J739D01*
G02Y435301I0J1302D01*
G02X423294Y434739I0J-1301D01*
G03X423952I329J228D01*
G02X425023Y435301I1071J-739D01*
G02Y432697I0J-1302D01*
G02X423952Y433259I0J1301D01*
G03X423294I-329J-228D01*
G37*
G36*
G01X968462Y430870D02*
G02X969964Y429368I0J-1502D01*
G02X968564Y427869I-1503J0D01*
G01X968528Y427867D01*
X968463Y427837D01*
X968251Y427625D01*
G03X968193Y427497I142J-141D01*
G02X966694Y426097I-1499J103D01*
G02X965722Y426454I0J1502D01*
G01X965681Y426489D01*
X965572Y426508D01*
X965142Y426341D01*
X965074Y426255D01*
X965067Y426200D01*
G02X963577Y424889I-1490J191D01*
G02Y427893I0J1502D01*
G02X964549Y427536I0J-1502D01*
G01X964590Y427501D01*
X964699Y427482D01*
X965129Y427649D01*
X965197Y427735D01*
X965204Y427790D01*
G02X966592Y429098I1490J-191D01*
G01X966628Y429100D01*
X966693Y429130D01*
X966905Y429342D01*
G03X966963Y429470I-142J141D01*
G02X968462Y430870I1499J-103D01*
G37*
G36*
G01X784105Y427380D02*
G02X783400Y428653I797J1273D01*
G02X786404I1502J0D01*
G02X785621Y427334I-1502J0D01*
G03X785601Y426644I192J-351D01*
G02X786306Y425371I-797J-1273D01*
G02X783302I-1502J0D01*
G02X784085Y426690I1502J0D01*
G03X784105Y427380I-192J351D01*
G37*
G36*
G01X875596Y423726D02*
X875910D01*
G03X876068Y423803I0J200D01*
G02X877253Y424382I1185J-923D01*
G02X878755Y422880I0J-1502D01*
G02X878385Y421893I-1501J0D01*
G01Y421892D01*
X878384D01*
G03X878336Y421762I152J-130D01*
G01Y421498D01*
G03X878384Y421368I200J0D01*
G01X878385Y421367D01*
G02X878755Y420380I-1131J-987D01*
G02X877253Y418878I-1502J0D01*
G02X876160Y419350I0J1502D01*
G01X876159Y419351D01*
G03X875994Y419412I-145J-138D01*
G01X875679Y419381D01*
G03X875529Y419287I20J-199D01*
G02X874253Y418578I-1276J794D01*
G02X872751Y420080I0J1502D01*
G02X873236Y421186I1504J0D01*
G03X873301Y421333I-135J148D01*
G01Y421627D01*
G03X873236Y421774I-200J-1D01*
G02X872751Y422880I1019J1106D01*
G02X874253Y424382I1502J0D01*
G02X875438Y423803I0J-1502D01*
G03X875596Y423726I158J123D01*
G37*
G36*
G01X857325Y419896D02*
G02X858827Y421398I1502J0D01*
G02X860006Y420827I0J-1503D01*
G01X860032Y420794D01*
X860106Y420755D01*
X860485Y420726D01*
X860563Y420754D01*
X860594Y420783D01*
G02X861622Y421190I1028J-1095D01*
G02X863124Y419688I0J-1502D01*
G02X862623Y418568I-1502J0D01*
G01X862594Y418543D01*
X862560Y418473D01*
X862535Y418159D01*
G03X862579Y418018I199J-15D01*
G02X862915Y417071I-1167J-947D01*
G02X861413Y415569I-1502J0D01*
G02X860522Y415862I0J1501D01*
G01X860521D01*
X860490Y415885D01*
X860414Y415904D01*
X860058Y415852D01*
X859989Y415811D01*
X859966Y415780D01*
G02X859627Y415454I-1198J906D01*
G03X859543Y415315I114J-164D01*
G01X859500Y414979D01*
X859524Y414898D01*
X859552Y414866D01*
G02X859912Y413890I-1143J-976D01*
G02X856908I-1502J0D01*
G02X857550Y415121I1501J0D01*
G03X857634Y415260I-114J164D01*
G01X857677Y415596D01*
X857653Y415677D01*
X857625Y415709D01*
G02X857265Y416685I1143J976D01*
G02X857986Y417968I1502J0D01*
G01X858030Y417995D01*
X858081Y418083D01*
X858089Y418525D01*
X858042Y418615D01*
X857999Y418643D01*
G02X857325Y419896I828J1253D01*
G37*
G36*
G01X867364Y416678D02*
G02X866128Y416030I-1236J855D01*
G02Y419034I0J1502D01*
G02X867430Y418281I0J-1502D01*
G03X868106Y418253I347J199D01*
G02X869342Y418901I1236J-855D01*
G02Y415897I0J-1502D01*
G02X868040Y416650I0J1502D01*
G03X867364Y416678I-347J-199D01*
G37*
G36*
G01X380270Y410385D02*
X380584D01*
G03X380742Y410462I0J200D01*
G02X381927Y411041I1185J-923D01*
G02X383429Y409539I0J-1502D01*
G02X383059Y408552I-1501J0D01*
G01Y408551D01*
X383058D01*
G03X383010Y408421I152J-130D01*
G01Y408157D01*
G03X383058Y408027I200J0D01*
G01X383059Y408026D01*
G02X383429Y407039I-1131J-987D01*
G02X381927Y405537I-1502J0D01*
G02X380834Y406009I0J1502D01*
G01X380833Y406010D01*
G03X380668Y406071I-145J-138D01*
G01X380353Y406040D01*
G03X380203Y405946I20J-199D01*
G02X378927Y405237I-1276J794D01*
G02X377425Y406739I0J1502D01*
G02X377910Y407845I1504J0D01*
G03X377975Y407992I-135J148D01*
G01Y408286D01*
G03X377910Y408433I-200J-1D01*
G02X377425Y409539I1019J1106D01*
G02X378927Y411041I1502J0D01*
G02X380112Y410462I0J-1502D01*
G03X380270Y410385I158J123D01*
G37*
G36*
G01X792391Y409502D02*
G02X795395I1502J0D01*
G02X794011Y408005I-1502J0D01*
G01X793955Y408000D01*
X793866Y407936D01*
X793704Y407559D01*
G03X793732Y407354I183J-79D01*
G02X794066Y406410I-1167J-944D01*
G02X792564Y404908I-1502J0D01*
G02X791705Y405178I0J1501D01*
G03X791506Y405195I-114J-164D01*
G01X791143Y405025D01*
X791082Y404937D01*
X791078Y404884D01*
G02X789581Y403509I-1497J127D01*
G02Y406513I0J1502D01*
G02X790440Y406243I0J-1501D01*
G03X790639Y406226I114J164D01*
G01X791002Y406396D01*
X791063Y406484D01*
X791067Y406537D01*
G02X792446Y407907I1497J-127D01*
G01X792502Y407912D01*
X792591Y407976D01*
X792753Y408353D01*
G03X792725Y408558I-183J79D01*
G02X792391Y409502I1167J944D01*
G37*
G36*
G01X870780Y407193D02*
G02X869342Y406125I-1438J434D01*
G02Y409129I0J1502D01*
G02X870254Y408820I0J-1502D01*
G03X870880Y409023I243J318D01*
G02X872318Y410091I1438J-434D01*
G02Y407087I0J-1502D01*
G02X871406Y407396I0J1502D01*
G03X870780Y407193I-243J-318D01*
G37*
G36*
G01X533236Y396710D02*
G02X531992Y396050I-1244J842D01*
G02Y399054I0J1502D01*
G02X533236Y398394I0J-1502D01*
G03X533898I331J224D01*
G02X535142Y399054I1244J-842D01*
G02Y396050I0J-1502D01*
G02X533898Y396710I0J1502D01*
G03X533236I-331J-224D01*
G37*
G36*
G01X540532Y392209D02*
G02X543536I1502J0D01*
G02X542694Y390860I-1502J0D01*
G01X542648Y390837D01*
X542590Y390755D01*
X542543Y390372D01*
G03X542612Y390195I199J-25D01*
G02X543146Y389047I-967J-1148D01*
G02X542674Y387954I-1502J0D01*
G01X542643Y387925D01*
X542611Y387847D01*
X542619Y387464D01*
X542655Y387388D01*
X542687Y387360D01*
G02X543208Y386223I-980J-1137D01*
G02X540204I-1502J0D01*
G02X540676Y387316I1502J0D01*
G01X540707Y387345D01*
X540739Y387423D01*
X540731Y387806D01*
X540695Y387882D01*
X540663Y387910D01*
G02X540142Y389047I980J1137D01*
G02X540984Y390396I1502J0D01*
G01X541030Y390419D01*
X541088Y390501D01*
X541135Y390884D01*
G03X541066Y391061I-199J25D01*
G02X540532Y392209I967J1148D01*
G37*
G36*
G01X471411Y391589D02*
G02X472913Y390087I1502J0D01*
G02X472523Y390138I-2J1502D01*
G01X472476Y390151D01*
X472379Y390130D01*
X472054Y389853D01*
X472017Y389761D01*
X472022Y389713D01*
G02X472030Y389553I-1633J-162D01*
G02X471942Y389025I-1641J2D01*
G01X471924Y388971D01*
X471949Y388860D01*
X472282Y388525D01*
X472391Y388498D01*
X472445Y388516D01*
G02X472913Y388591I469J-1427D01*
G02X471411Y387089I0J-1502D01*
G02X471475Y387522I1502J-1D01*
G01X471491Y387577D01*
X471462Y387685D01*
X471160Y387971D01*
G03X470954Y388013I-137J-146D01*
G02X470389Y387912I-567J1540D01*
G02Y391194I0J1641D01*
G02X470891Y391115I-1J-1641D01*
G03X471074Y391147I61J190D01*
G01X471374Y391377D01*
X471415Y391466D01*
X471413Y391515D01*
G02X471411Y391589I1500J78D01*
G37*
G36*
G01X551811Y389233D02*
G02X551623Y389221I-189J1490D01*
G01X551620D01*
G02X553122Y390723I0J1502D01*
G02X553096Y390447I-1502J2D01*
G03X553540Y389977I393J-73D01*
G02X553728Y389989I189J-1490D01*
G01X553731D01*
G02X552229Y388487I0J-1502D01*
G02X552255Y388763I1502J-2D01*
G03X551811Y389233I-393J73D01*
G37*
G36*
G01X480222Y382589D02*
G02X483226I1502J0D01*
G02X483195Y382289I-1502J4D01*
G01Y382287D01*
G03X483234Y382124I196J-39D01*
G01X483426Y381883D01*
G03X483578Y381808I156J125D01*
G02X485043Y380306I-37J-1502D01*
G02X483587Y378805I-1502J0D01*
G03X483439Y378732I7J-200D01*
G01X483247Y378498D01*
G03X483205Y378339I155J-126D01*
G01Y378338D01*
G02X483226Y378089I-1481J-250D01*
G01Y378087D01*
G02X483201Y377815I-1502J1D01*
G03X483243Y377651I197J-37D01*
G01X483467Y377380D01*
X483547Y377342D01*
X483592D01*
G02Y374338I-8J-1502D01*
G01X483547D01*
X483467Y374300D01*
X483242Y374029D01*
G03X483200Y373865I155J-127D01*
G02X483226Y373589I-1476J-278D01*
G02X483188Y373251I-1502J-2D01*
G01X483177Y373204D01*
X483200Y373112D01*
X483442Y372831D01*
G03X483611Y372763I151J131D01*
G02X483736Y372768I122J-1497D01*
G02X485238Y371266I0J-1502D01*
G02X483737Y369764I-1502J0D01*
G01X483735D01*
G02X483634Y369768I9J1502D01*
G01X483632D01*
G03X483472Y369704I-13J-200D01*
G01X483261Y369475D01*
G03X483210Y369310I147J-136D01*
G02X483226Y369089I-1486J-219D01*
G02X483114Y368519I-1502J-1D01*
G01X483096Y368476D01*
X483102Y368383D01*
X483309Y368028D01*
X483387Y367977D01*
X483433Y367971D01*
G02X484744Y366481I-191J-1490D01*
G02X481740I-1502J0D01*
G01Y366483D01*
G02X481852Y367051I1502J-1D01*
G01X481870Y367094D01*
X481864Y367187D01*
X481657Y367542D01*
X481579Y367593D01*
X481533Y367599D01*
G02X480222Y369089I191J1490D01*
G02X481723Y370591I1502J0D01*
G01X481725D01*
G02X481826Y370587I-9J-1502D01*
G01X481828D01*
G03X481988Y370651I13J200D01*
G01X482199Y370880D01*
G03X482250Y371045I-147J136D01*
G02X482234Y371266I1486J219D01*
G02X482272Y371604I1502J2D01*
G01X482283Y371651D01*
X482260Y371743D01*
X482018Y372024D01*
G03X481849Y372092I-151J-131D01*
G02X481724Y372087I-122J1497D01*
G02X480222Y373589I0J1502D01*
G02X481716Y375091I1502J0D01*
G01X481761D01*
X481841Y375129D01*
X482066Y375400D01*
G03X482108Y375564I-155J127D01*
G02X482082Y375840I1476J278D01*
G01Y375842D01*
G02X482107Y376114I1502J-1D01*
G03X482065Y376278I-197J37D01*
G01X481841Y376549D01*
X481761Y376587D01*
X481716D01*
G02X480222Y378089I8J1502D01*
G02X481678Y379590I1502J0D01*
G03X481826Y379663I-7J200D01*
G01X482018Y379897D01*
G03X482060Y380056I-155J126D01*
G01Y380057D01*
G02X482039Y380306I1481J250D01*
G02X482070Y380606I1502J-4D01*
G01Y380608D01*
G03X482031Y380771I-196J39D01*
G01X481839Y381012D01*
G03X481687Y381087I-156J-125D01*
G02X480222Y382589I37J1502D01*
G37*
G36*
G01X732344Y379863D02*
G02X731511Y379611I-833J1251D01*
G02Y382615I0J1502D01*
G02X733011Y381194I0J-1502D01*
G03X733645Y380891I399J21D01*
G02X734606Y381202I961J-1329D01*
G02Y377922I0J-1640D01*
G02X732966Y379537I0J1640D01*
G03X732344Y379863I-400J-7D01*
G37*
G36*
G01X392744Y379426D02*
G02X392735Y379589I1493J164D01*
G01Y379591D01*
G02X394237Y378089I1502J0D01*
G01X394236D01*
G02X393756Y378168I1J1502D01*
G03X393230Y377746I-128J-379D01*
G02X393239Y377583I-1493J-164D01*
G01Y377581D01*
G02X391737Y379083I-1502J0D01*
G01X391738D01*
G02X392218Y379004I-1J-1502D01*
G03X392744Y379426I128J379D01*
G37*
G36*
G01X365207Y376455D02*
G02X365024Y377173I1319J718D01*
G02X368028I1502J0D01*
G02X366646Y375676I-1502J0D01*
G03X366334Y375072I31J-399D01*
G02X366566Y374234I-1401J-839D01*
G01Y374232D01*
G02X363300I-1633J0D01*
G02X364871Y375864I1633J0D01*
G03X365207Y376455I-16J400D01*
G37*
G36*
G01X490949Y375632D02*
G02X490815Y376252I1367J620D01*
G02X493819I1502J0D01*
G02X492554Y374769I-1502J0D01*
G03X492253Y374209I63J-395D01*
G02X492387Y373589I-1367J-620D01*
G02X489383I-1502J0D01*
G02X490648Y375072I1502J0D01*
G03X490949Y375632I-63J395D01*
G37*
G36*
G01X869437Y373094D02*
G02X868086Y372248I-1351J656D01*
G02Y375252I0J1502D01*
G02X869338Y374580I0J-1502D01*
G03X870031Y374627I333J221D01*
G02X871382Y375473I1351J-656D01*
G02Y372469I0J-1502D01*
G02X870130Y373141I0J1502D01*
G03X869437Y373094I-333J-221D01*
G37*
G36*
G01X467826Y365600D02*
G02X466375Y364724I-1451J764D01*
G02Y368006I0J1641D01*
G02X467597Y367459I-1J-1641D01*
G03X468239Y367522I298J267D01*
G02X469530Y368256I1291J-768D01*
G02Y365252I0J-1502D01*
G02X468464Y365696I0J1502D01*
G03X467826Y365600I-284J-282D01*
G37*
G36*
G01X531497Y363639D02*
G02X530215Y362920I-1282J783D01*
G02Y365924I0J1502D01*
G02X531299Y365461I-1J-1502D01*
G03X531929Y365529I289J277D01*
G02X533211Y366248I1282J-783D01*
G02Y363244I0J-1502D01*
G02X532127Y363707I1J1502D01*
G03X531497Y363639I-289J-277D01*
G37*
G36*
G01X907123Y359317D02*
G02X910127I1502J0D01*
G02X909675Y358243I-1502J0D01*
G01X909648Y358216D01*
X909617Y358148D01*
X909604Y357834D01*
G03X909653Y357695I200J-8D01*
G02X910023Y356708I-1131J-987D01*
G02X908521Y355206I-1502J0D01*
G02X907623Y355504I0J1502D01*
G01X907622D01*
G03X907417Y355524I-119J-160D01*
G01X907098Y355373D01*
G03X906984Y355200I86J-181D01*
G02X905483Y353760I-1501J62D01*
G02Y356764I0J1502D01*
G02X906381Y356466I0J-1502D01*
G01X906382D01*
G03X906587Y356446I119J160D01*
G01X906906Y356597D01*
G03X907020Y356770I-86J181D01*
G02X907471Y357782I1501J-62D01*
G01X907498Y357809D01*
X907529Y357877D01*
X907542Y358191D01*
G03X907493Y358330I-200J8D01*
G02X907123Y359317I1131J987D01*
G37*
G36*
G01X853120Y359004D02*
G02X856124I1502J0D01*
G01Y359003D01*
G02X856018Y358449I-1502J0D01*
G01X856001Y358406D01*
X856007Y358316D01*
X856181Y358006D01*
G03X856322Y357907I174J98D01*
G02X857571Y356426I-254J-1481D01*
G02X854567I-1502J0D01*
G01Y356427D01*
G02X854673Y356981I1502J0D01*
G01X854690Y357024D01*
X854684Y357114D01*
X854510Y357424D01*
G03X854369Y357523I-174J-98D01*
G02X854195Y357564I257J1480D01*
G03X853946Y357314I-58J-192D01*
G03X853953Y357295I191J60D01*
G02X854071Y356712I-1384J-584D01*
G02X852569Y358214I-1502J0D01*
G02X852722Y358206I-2J-1502D01*
G01X852770Y358201D01*
X852858Y358235D01*
X853140Y358550D01*
X853164Y358641D01*
X853154Y358688D01*
G02X853120Y359004I1468J318D01*
G37*
G36*
G01X365559Y352798D02*
G02Y355802I0J1502D01*
G02X366598Y355385I0J-1503D01*
G01X366625Y355359D01*
X366690Y355331D01*
X366990Y355317D01*
G03X367122Y355359I9J200D01*
G01X367123Y355360D01*
G02X368057Y355686I934J-1175D01*
G02X369458Y354726I0J-1502D01*
G03X369623Y354599I187J72D01*
G01X369977Y354561D01*
G03X370164Y354648I21J199D01*
G01X370165Y354649D01*
G02X371417Y355322I1252J-828D01*
G02Y352318I0J-1502D01*
G02X370016Y353278I0J1502D01*
G03X369851Y353405I-187J-72D01*
G01X369497Y353443D01*
G03X369310Y353356I-21J-199D01*
G01X369309Y353355D01*
G02X368057Y352682I-1252J828D01*
G02X367018Y353099I0J1503D01*
G01X366991Y353125D01*
X366926Y353153D01*
X366626Y353167D01*
G03X366494Y353125I-9J-200D01*
G01X366493Y353124D01*
G02X365559Y352798I-934J1175D01*
G37*
G36*
G01X530110Y354272D02*
G02X533114I1502J0D01*
G02X533043Y353818I-1502J2D01*
G01Y353816D01*
X533030Y353776D01*
X533040Y353694D01*
X533231Y353363D01*
X533299Y353314D01*
X533341Y353305D01*
G02X534529Y351836I-314J-1469D01*
G02X533252Y350351I-1502J0D01*
G01X533251D01*
X533203Y350343D01*
X533126Y350287D01*
X532936Y349907D01*
X532937Y349810D01*
X532960Y349767D01*
G02X533138Y349058I-1324J-709D01*
G01Y349057D01*
G02X530134I-1502J0D01*
G02X531411Y350542I1502J0D01*
G01X531412D01*
X531460Y350550D01*
X531537Y350606D01*
X531727Y350986D01*
X531726Y351083D01*
X531703Y351126D01*
G02X531525Y351835I1324J709D01*
G01Y351836D01*
G02X531596Y352290I1502J-2D01*
G01Y352292D01*
X531609Y352332D01*
X531599Y352414D01*
X531408Y352745D01*
X531340Y352794D01*
X531298Y352803D01*
G02X530110Y354272I314J1469D01*
G37*
G36*
G01X919356Y342348D02*
X915953D01*
G02X914366Y343295I0J1803D01*
G01X914339Y343345D01*
X914240Y343402D01*
X913824Y343387D01*
G03X913649Y343268I8J-200D01*
G02X912278Y342379I-1371J613D01*
G02Y345383I0J1502D01*
G02X913545Y344687I0J-1501D01*
G03X913735Y344595I169J107D01*
G01X914093Y344635D01*
G03X914259Y344764I-21J199D01*
G01Y344765D01*
G02X915953Y345952I1694J-615D01*
G01X919357D01*
G02X919866Y345878I-2J-1802D01*
G03X920057Y345922I56J192D01*
G01X920350Y346187D01*
X920382Y346286D01*
X920372Y346337D01*
G02X920345Y346619I1475J284D01*
G01Y346622D01*
G02X921847Y345120I1502J0D01*
G02X921549Y345150I1J1502D01*
G01X921497Y345160D01*
X921399Y345129D01*
X921131Y344839D01*
G03X921086Y344647I147J-136D01*
G02X921156Y344151I-1733J-498D01*
G01Y344149D01*
G02X921145Y343961I-1802J11D01*
G01Y343959D01*
X921140Y343909D01*
X921179Y343815D01*
X921526Y343541D01*
X921628Y343524D01*
X921676Y343541D01*
G02X922197Y343630I523J-1490D01*
G01X922199D01*
G02X922327Y343624I-10J-1579D01*
G01X922329D01*
X922371Y343621D01*
X922449Y343648D01*
X922697Y343879D01*
G03X922761Y344025I-136J147D01*
G01Y344026D01*
X922760Y344034D01*
Y344048D01*
G02X924563Y345844I1803J-7D01*
G01X927963D01*
G02X929766Y344046I0J-1803D01*
G01Y344036D01*
G02X929765Y344020I-1798J104D01*
G01Y344019D01*
G03X929831Y343869I200J-2D01*
G01X930087Y343638D01*
X930169Y343613D01*
X930212Y343618D01*
G02X930398Y343628I178J-1568D01*
G02Y340472I0J-1578D01*
G02X928825Y341920I0J1578D01*
G01Y341922D01*
G03X928745Y342064I-199J-19D01*
G01X928504Y342244D01*
G03X928343Y342279I-119J-161D01*
G01X928342D01*
G02X927963Y342238I-382J1762D01*
G01X924563D01*
G02X924241Y342268I6J1803D01*
G01X924239D01*
G03X924084Y342230I-34J-197D01*
G01X923848Y342051D01*
G03X923770Y341910I121J-159D01*
G02X922198Y340472I-1572J140D01*
G02X920620Y342051I1J1579D01*
G02X920621Y342111I1578J4D01*
G03X920534Y342283I-200J7D01*
G01X920256Y342474D01*
G03X920064Y342493I-113J-165D01*
G01X920063D01*
G02X919356Y342348I-708J1657D01*
G37*
G36*
G01X395872Y344439D02*
G02X397374Y342937I1502J0D01*
G02X397023Y342978I-2J1502D01*
G01X396969Y342991D01*
X396862Y342957D01*
X396593Y342646D01*
G03X396558Y342443I151J-131D01*
G01Y342442D01*
G02X396686Y341777I-1663J-665D01*
G01Y338377D01*
G02X394883Y336574I-1803J0D01*
G02X393991Y336811I1J1803D01*
G03X393848Y336832I-99J-174D01*
G01X393728Y336805D01*
G03X393609Y336726I44J-195D01*
G02X392387Y336097I-1222J873D01*
G02Y339101I0J1502D01*
G02X392619Y339083I0J-1502D01*
G01X392663Y339076D01*
X392746Y339100D01*
X393010Y339326D01*
G03X393080Y339478I-130J152D01*
G01Y340676D01*
G03X393010Y340828I-200J0D01*
G01X392780Y341025D01*
G03X392619Y341071I-130J-152D01*
G02X392387Y341053I-232J1484D01*
G02Y344057I0J1502D01*
G02X393609Y343428I0J-1502D01*
G03X393728Y343349I163J116D01*
G01X393848Y343322D01*
G03X393991Y343343I44J195D01*
G02X394883Y343580I893J-1566D01*
G02X395435Y343493I-1J-1803D01*
G01X395489Y343475D01*
X395597Y343501D01*
X395890Y343791D01*
G03X395940Y343992I-141J142D01*
G02X395872Y344439I1435J447D01*
G37*
G36*
G01X863057Y342231D02*
G02X861770Y341504I-1287J776D01*
G02Y344508I0J1502D01*
G02X862971Y343908I0J-1502D01*
G03X863633Y343943I319J241D01*
G02X864920Y344670I1287J-776D01*
G02Y341666I0J-1502D01*
G02X863719Y342266I0J1502D01*
G03X863057Y342231I-319J-241D01*
G37*
G36*
G01X1030461Y339760D02*
G02X1029880Y340947I922J1187D01*
G02X1032884I1502J0D01*
G02X1032246Y339718I-1503J0D01*
G03X1032231Y339075I230J-327D01*
G02X1032812Y337888I-922J-1187D01*
G02X1029808I-1502J0D01*
G02X1030446Y339117I1503J0D01*
G03X1030461Y339760I-230J327D01*
G37*
G36*
G01X684186Y338777D02*
G02X682857Y337975I-1329J700D01*
G02Y340979I0J1502D01*
G02X684020Y340428I0J-1503D01*
G03X684683Y340495I309J253D01*
G02X686012Y341297I1329J-700D01*
G02Y338293I0J-1502D01*
G02X684849Y338844I0J1503D01*
G03X684186Y338777I-309J-253D01*
G37*
G36*
G01X578193Y334889D02*
G02Y337893I0J1502D01*
G02X579430Y337244I0J-1503D01*
G03X579612Y337158I165J113D01*
G01X580012Y337193D01*
X580100Y337254D01*
X580122Y337303D01*
G02X581487Y338178I1365J-627D01*
G02X582845Y337318I0J-1502D01*
G03X583002Y337205I181J85D01*
G01X583336Y337163D01*
G03X583516Y337236I24J199D01*
G02X584679Y337787I1163J-952D01*
G02Y334783I0J-1502D01*
G02X583321Y335643I0J1502D01*
G03X583164Y335756I-181J-85D01*
G01X582830Y335798D01*
G03X582650Y335725I-24J-199D01*
G02X581487Y335174I-1163J952D01*
G02X580250Y335823I0J1503D01*
G03X580068Y335909I-165J-113D01*
G01X579668Y335874D01*
X579580Y335813D01*
X579558Y335764D01*
G02X578193Y334889I-1365J627D01*
G37*
G36*
G01X411169Y333418D02*
G02X414173I1502J0D01*
G02X413740Y332363I-1502J0D01*
G03X413682Y332212I142J-141D01*
G01X413700Y331876D01*
X413738Y331801D01*
X413770Y331774D01*
G02X414314Y330617I-958J-1157D01*
G02X412812Y329115I-1502J0D01*
G02X411346Y330289I0J1502D01*
G01X411334Y330341D01*
X411262Y330420D01*
X410878Y330539D01*
G03X410682Y330493I-58J-191D01*
G02X409655Y330087I-1027J1096D01*
G02X411157Y331589I0J1502D01*
G02X411155Y331507I-1502J-4D01*
G03X411526Y331393I200J-11D01*
G02X411743Y331672I1286J-776D01*
G03X411801Y331823I-142J141D01*
G01X411783Y332159D01*
X411745Y332234D01*
X411713Y332261D01*
G02X411169Y333418I958J1157D01*
G37*
G36*
G01X758187Y330773D02*
G02X757527Y332017I842J1244D01*
G02X760531I1502J0D01*
G02X759871Y330773I-1502J0D01*
G03Y330111I224J-331D01*
G02X760531Y328867I-842J-1244D01*
G02X757527I-1502J0D01*
G02X758187Y330111I1502J0D01*
G03Y330773I-224J331D01*
G37*
G36*
G01X1029860Y329268D02*
G02X1032864I1502J0D01*
G02X1032058Y327937I-1502J0D01*
G03X1031951Y327760I93J-177D01*
G01X1031949Y327350D01*
X1032007Y327255D01*
X1032056Y327229D01*
G02X1032856Y325901I-702J-1328D01*
G02X1032280Y324718I-1503J0D01*
G03X1032203Y324561I123J-158D01*
G01Y324245D01*
G03X1032280Y324088I200J1D01*
G02X1032856Y322905I-927J-1183D01*
G02X1029852I-1502J0D01*
G02X1030428Y324088I1503J0D01*
G03X1030505Y324245I-123J158D01*
G01Y324561D01*
G03X1030428Y324718I-200J-1D01*
G02X1029852Y325901I927J1183D01*
G02X1030658Y327232I1502J0D01*
G03X1030765Y327409I-93J177D01*
G01X1030767Y327819D01*
X1030709Y327914D01*
X1030660Y327940D01*
G02X1029860Y329268I702J1328D01*
G37*
G36*
G01X943542Y326441D02*
G02X945120Y324862I1578J-1D01*
G02X944936Y324873I2J1579D01*
G01X944889Y324879D01*
X944798Y324845D01*
X944546Y324571D01*
G03X944497Y324398I147J-135D01*
G02X944532Y324045I-1767J-353D01*
G01Y324044D01*
G02X942730Y322242I-1802J0D01*
G01X939330D01*
G02X937528Y324044I0J1802D01*
G02X937530Y324129I1802J0D01*
G01Y324131D01*
G03X937455Y324295I-200J8D01*
G01X937165Y324528D01*
X937071Y324548D01*
X937025Y324535D01*
G02X936608Y324480I-413J1524D01*
G02Y327636I0J1578D01*
G02X938186Y326105I0J-1579D01*
G03X938273Y325946I200J6D01*
G01X938541Y325763D01*
G03X938721Y325740I113J165D01*
G02X939330Y325846I609J-1696D01*
G01X942730D01*
G02X943078Y325813I5J-1802D01*
G01X943125Y325804D01*
X943218Y325830D01*
X943526Y326116D01*
X943559Y326205D01*
X943553Y326253D01*
G02X943542Y326441I1567J186D01*
G37*
G36*
G01X992536Y320000D02*
G02X991741Y321325I707J1325D01*
G02X994745I1502J0D01*
G02X994194Y320163I-1501J0D01*
G03X994259Y319500I253J-310D01*
G02X995054Y318175I-707J-1325D01*
G02X992050I-1502J0D01*
G02X992601Y319337I1501J0D01*
G03X992536Y320000I-253J310D01*
G37*
G36*
G01X808684Y312562D02*
G02X807987Y313830I805J1268D01*
G02X810991I1502J0D01*
G02X810276Y312551I-1501J0D01*
G03X810271Y311872I209J-341D01*
G02X810968Y310604I-805J-1268D01*
G02X807964I-1502J0D01*
G02X808679Y311883I1501J0D01*
G03X808684Y312562I-209J341D01*
G37*
G36*
G01X911654Y304843D02*
G02X910988Y303555I-1578J0D01*
G03X910909Y303439I115J-163D01*
G01X910880Y303321D01*
G03X910897Y303182I195J-47D01*
G02X911102Y302347I-1598J-835D01*
G02X909299Y300544I-1803J0D01*
G01X905899D01*
G02X904096Y302347I0J1803D01*
G02X904301Y303180I1803J-2D01*
G03X904317Y303321I-178J92D01*
G01X904288Y303438D01*
G03X904210Y303554I-195J-47D01*
G02X903542Y304843I910J1289D01*
G02X906698I1578J0D01*
G02X906681Y304609I-1578J-3D01*
G01X906674Y304565D01*
X906698Y304482D01*
X906925Y304219D01*
G03X907077Y304150I151J131D01*
G01X908119D01*
G03X908271Y304219I1J200D01*
G01X908498Y304482D01*
X908522Y304565D01*
X908515Y304609D01*
G02X908498Y304843I1561J231D01*
G02X910076Y306422I1578J1D01*
G02X910660Y306310I0J-1579D01*
G01X910706Y306291D01*
X910806Y306302D01*
X911121Y306518D01*
G03X911208Y306683I-113J165D01*
G01Y306699D01*
G02X912786Y308276I1578J-1D01*
G02X913718Y307971I-1J-1579D01*
G03X913883Y307938I118J161D01*
G01X914180Y308009D01*
G03X914312Y308113I-46J195D01*
G01Y308114D01*
G02X915653Y308940I1341J-676D01*
G02Y305936I0J-1502D01*
G02X914807Y306197I0J1502D01*
G01X914806D01*
G03X914641Y306224I-112J-165D01*
G01X914347Y306143D01*
G03X914219Y306034I54J-193D01*
G02X912786Y305118I-1433J663D01*
G02X912202Y305230I0J1579D01*
G01X912156Y305249D01*
X912056Y305238D01*
X911741Y305022D01*
G03X911654Y304857I113J-165D01*
G01Y304843D01*
G37*
G36*
G01X876475Y305368D02*
G02X879479I1502J0D01*
G02X879181Y304470I-1502J0D01*
G03X879154Y304279I160J-120D01*
G01X879273Y303964D01*
G03X879419Y303839I187J71D01*
G01X879420D01*
G02X880614Y302369I-308J-1470D01*
G02X879112Y300867I-1502J0D01*
G02X877850Y301554I0J1503D01*
G01X877826Y301591D01*
X877752Y301637D01*
X877364Y301690D01*
X877280Y301664D01*
X877248Y301635D01*
G02X876246Y301252I-1002J1119D01*
G02X874744Y302754I0J1502D01*
G02X876220Y304256I1502J0D01*
G01X876221D01*
G03X876384Y304346I-4J200D01*
G01X876593Y304661D01*
X876603Y304760D01*
X876584Y304805D01*
G02X876475Y305366I1393J562D01*
G01Y305368D01*
G37*
G36*
G01X788625Y288806D02*
G02X788522Y288802I-110J1498D01*
G02X790024Y290304I0J1502D01*
G02X789807Y289526I-1503J0D01*
G03X790175Y288919I342J-208D01*
G01X790177D01*
G02X790280Y288923I110J-1498D01*
G02X788778Y287421I0J-1502D01*
G02X788995Y288199I1503J0D01*
G03X788627Y288806I-342J208D01*
G01X788625D01*
G37*
G36*
G01X1028174Y288283D02*
G02X1027216Y287938I-958J1158D01*
G02Y290942I0J1502D01*
G02X1028602Y290019I0J-1502D01*
G03X1029226Y289866I369J155D01*
G02X1030184Y290211I958J-1158D01*
G02Y287207I0J-1502D01*
G02X1028798Y288130I0J1502D01*
G03X1028174Y288283I-369J-155D01*
G37*
G36*
G01X400038Y930768D02*
Y931104D01*
X400013Y931171D01*
X399989Y931199D01*
G02X399619Y932186I1131J987D01*
G02X402623I1502J0D01*
G02X402253Y931199I-1501J0D01*
G01X402229Y931171D01*
X402204Y931104D01*
Y930768D01*
X402229Y930701D01*
X402253Y930673D01*
G02X402623Y929686I-1131J-987D01*
G02X399619I-1502J0D01*
G02X399989Y930673I1501J0D01*
G01X400013Y930701D01*
X400038Y930768D01*
G37*
G36*
G01X408038D02*
Y931104D01*
X408013Y931171D01*
X407989Y931199D01*
G02X407619Y932186I1131J987D01*
G02X410623I1502J0D01*
G02X410253Y931199I-1501J0D01*
G01X410229Y931171D01*
X410204Y931104D01*
Y930768D01*
X410229Y930701D01*
X410253Y930673D01*
G02X410623Y929686I-1131J-987D01*
G02X407619I-1502J0D01*
G02X407989Y930673I1501J0D01*
G01X408013Y930701D01*
X408038Y930768D01*
G37*
G36*
G01X416038D02*
Y931104D01*
X416013Y931171D01*
X415989Y931199D01*
G02X415619Y932186I1131J987D01*
G02X418623I1502J0D01*
G02X418253Y931199I-1501J0D01*
G01X418229Y931171D01*
X418204Y931104D01*
Y930768D01*
X418229Y930701D01*
X418253Y930673D01*
G02X418623Y929686I-1131J-987D01*
G02X415619I-1502J0D01*
G02X415989Y930673I1501J0D01*
G01X416013Y930701D01*
X416038Y930768D01*
G37*
G36*
G01X424038D02*
Y931104D01*
X424013Y931171D01*
X423989Y931199D01*
G02X423619Y932186I1131J987D01*
G02X426623I1502J0D01*
G02X426253Y931199I-1501J0D01*
G01X426229Y931171D01*
X426204Y931104D01*
Y930768D01*
X426229Y930701D01*
X426253Y930673D01*
G02X426623Y929686I-1131J-987D01*
G02X423619I-1502J0D01*
G02X423989Y930673I1501J0D01*
G01X424013Y930701D01*
X424038Y930768D01*
G37*
G36*
G01X451789Y1003333D02*
X451426Y1003469D01*
X451340Y1003463D01*
X451302Y1003443D01*
G02X450591Y1003264I-711J1323D01*
G02Y1006268I0J1502D01*
G02X451996Y1005297I0J-1502D01*
G01X452011Y1005256D01*
X452072Y1005196D01*
X452435Y1005060D01*
X452521Y1005066D01*
X452559Y1005086D01*
G02X453270Y1005265I711J-1323D01*
G02Y1002261I0J-1502D01*
G02X451865Y1003232I0J1502D01*
G01X451850Y1003273D01*
X451789Y1003333D01*
G37*
G36*
G01X471844Y1030987D02*
X472125Y1031185D01*
X472165Y1031246D01*
X472174Y1031283D01*
G02X473639Y1032454I1465J-331D01*
G02Y1029450I0J-1502D01*
G02X473461Y1029461I3J1502D01*
G01X473423Y1029465D01*
X473353Y1029447D01*
X473072Y1029249D01*
X473032Y1029188D01*
X473023Y1029151D01*
G02X471558Y1027980I-1465J331D01*
G02Y1030984I0J1502D01*
G02X471736Y1030973I-3J-1502D01*
G01X471774Y1030969D01*
X471844Y1030987D01*
G37*
G36*
G01X411129Y1061780D02*
X411465D01*
X411532Y1061805D01*
X411560Y1061829D01*
G02X413534I987J-1131D01*
G01X413562Y1061805D01*
X413629Y1061780D01*
X413965D01*
X414032Y1061805D01*
X414060Y1061829D01*
G02X415047Y1062199I987J-1131D01*
G02X416549Y1060697I0J-1502D01*
G02X416143Y1059670I-1502J0D01*
G01X416117Y1059642D01*
X416089Y1059573D01*
Y1059221D01*
X416117Y1059152D01*
X416143Y1059124D01*
G02X416549Y1058097I-1096J-1027D01*
G02X415047Y1056595I-1502J0D01*
G02X414060Y1056965I0J1501D01*
G01X414032Y1056989D01*
X413965Y1057014D01*
X413629D01*
X413562Y1056989D01*
X413534Y1056965D01*
G02X411560I-987J1131D01*
G01X411532Y1056989D01*
X411465Y1057014D01*
X411129D01*
X411062Y1056989D01*
X411034Y1056965D01*
G02X409060I-987J1131D01*
G01X409032Y1056989D01*
X408965Y1057014D01*
X408629D01*
X408562Y1056989D01*
X408534Y1056965D01*
G02X406560I-987J1131D01*
G01X406532Y1056989D01*
X406465Y1057014D01*
X406129D01*
X406062Y1056989D01*
X406034Y1056965D01*
G02X405047Y1056595I-987J1131D01*
G02X403545Y1058097I0J1502D01*
G02X403951Y1059124I1502J0D01*
G01X403977Y1059152D01*
X404005Y1059221D01*
Y1059573D01*
X403977Y1059642D01*
X403951Y1059670D01*
G02X403545Y1060697I1096J1027D01*
G02X405047Y1062199I1502J0D01*
G02X406034Y1061829I0J-1501D01*
G01X406062Y1061805D01*
X406129Y1061780D01*
X406465D01*
X406532Y1061805D01*
X406560Y1061829D01*
G02X408534I987J-1131D01*
G01X408562Y1061805D01*
X408629Y1061780D01*
X408965D01*
X409032Y1061805D01*
X409060Y1061829D01*
G02X411034I987J-1131D01*
G01X411062Y1061805D01*
X411129Y1061780D01*
G37*
G36*
G01X499259D02*
X499595D01*
X499662Y1061805D01*
X499690Y1061829D01*
G02X501664I987J-1131D01*
G01X501692Y1061805D01*
X501759Y1061780D01*
X502095D01*
X502162Y1061805D01*
X502190Y1061829D01*
G02X503177Y1062199I987J-1131D01*
G02X504679Y1060697I0J-1502D01*
G02X504273Y1059670I-1502J0D01*
G01X504247Y1059642D01*
X504219Y1059573D01*
Y1059221D01*
X504247Y1059152D01*
X504273Y1059124D01*
G02X504679Y1058097I-1096J-1027D01*
G02X503177Y1056595I-1502J0D01*
G02X502190Y1056965I0J1501D01*
G01X502162Y1056989D01*
X502095Y1057014D01*
X501759D01*
X501692Y1056989D01*
X501664Y1056965D01*
G02X499690I-987J1131D01*
G01X499662Y1056989D01*
X499595Y1057014D01*
X499259D01*
X499192Y1056989D01*
X499164Y1056965D01*
G02X497190I-987J1131D01*
G01X497162Y1056989D01*
X497095Y1057014D01*
X496759D01*
X496692Y1056989D01*
X496664Y1056965D01*
G02X494690I-987J1131D01*
G01X494662Y1056989D01*
X494595Y1057014D01*
X494259D01*
X494192Y1056989D01*
X494164Y1056965D01*
G02X493177Y1056595I-987J1131D01*
G02X491675Y1058097I0J1502D01*
G02X492081Y1059124I1502J0D01*
G01X492107Y1059152D01*
X492135Y1059221D01*
Y1059573D01*
X492107Y1059642D01*
X492081Y1059670D01*
G02X491675Y1060697I1096J1027D01*
G02X493177Y1062199I1502J0D01*
G02X494164Y1061829I0J-1501D01*
G01X494192Y1061805D01*
X494259Y1061780D01*
X494595D01*
X494662Y1061805D01*
X494690Y1061829D01*
G02X496664I987J-1131D01*
G01X496692Y1061805D01*
X496759Y1061780D01*
X497095D01*
X497162Y1061805D01*
X497190Y1061829D01*
G02X499164I987J-1131D01*
G01X499192Y1061805D01*
X499259Y1061780D01*
G37*
G36*
G01X497585Y1087879D02*
X497921D01*
X497988Y1087904D01*
X498016Y1087928D01*
G02X499990I987J-1131D01*
G01X500018Y1087904D01*
X500085Y1087879D01*
X500421D01*
X500488Y1087904D01*
X500516Y1087928D01*
G02X501503Y1088298I987J-1131D01*
G02X503005Y1086796I0J-1502D01*
G02X502635Y1085809I-1501J0D01*
G01X502611Y1085781D01*
X502586Y1085714D01*
Y1085378D01*
X502611Y1085311D01*
X502635Y1085283D01*
G02X503005Y1084296I-1131J-987D01*
G02X501503Y1082794I-1502J0D01*
G02X500516Y1083164I0J1501D01*
G01X500488Y1083188D01*
X500421Y1083213D01*
X500085D01*
X500018Y1083188D01*
X499990Y1083164D01*
G02X498016I-987J1131D01*
G01X497988Y1083188D01*
X497921Y1083213D01*
X497585D01*
X497518Y1083188D01*
X497490Y1083164D01*
G02X495516I-987J1131D01*
G01X495488Y1083188D01*
X495421Y1083213D01*
X495085D01*
X495018Y1083188D01*
X494990Y1083164D01*
G02X493016I-987J1131D01*
G01X492988Y1083188D01*
X492921Y1083213D01*
X492585D01*
X492518Y1083188D01*
X492490Y1083164D01*
G02X491503Y1082794I-987J1131D01*
G02X490001Y1084296I0J1502D01*
G02X490371Y1085283I1501J0D01*
G01X490395Y1085311D01*
X490420Y1085378D01*
Y1085714D01*
X490395Y1085781D01*
X490371Y1085809D01*
G02X490001Y1086796I1131J987D01*
G02X491503Y1088298I1502J0D01*
G02X492490Y1087928I0J-1501D01*
G01X492518Y1087904D01*
X492585Y1087879D01*
X492921D01*
X492988Y1087904D01*
X493016Y1087928D01*
G02X494990I987J-1131D01*
G01X495018Y1087904D01*
X495085Y1087879D01*
X495421D01*
X495488Y1087904D01*
X495516Y1087928D01*
G02X497490I987J-1131D01*
G01X497518Y1087904D01*
X497585Y1087879D01*
G37*
G36*
G01X500879Y1091541D02*
Y1091835D01*
G03X500814Y1091982I-200J-1D01*
G02X500329Y1093088I1017J1105D01*
G02X503333I1502J0D01*
G02X502848Y1091982I-1502J-1D01*
G03X502783Y1091835I135J-148D01*
G01Y1091541D01*
G03X502848Y1091394I200J1D01*
G02X503333Y1090288I-1017J-1105D01*
G02X500329I-1502J0D01*
G02X500814Y1091394I1502J1D01*
G03X500879Y1091541I-135J148D01*
G37*
G36*
G01X413498Y1112565D02*
X413162D01*
X413095Y1112540D01*
X413067Y1112516D01*
G02X412080Y1112146I-987J1131D01*
G02Y1115150I0J1502D01*
G02X413067Y1114780I0J-1501D01*
G01X413095Y1114756D01*
X413162Y1114731D01*
X413498D01*
X413565Y1114756D01*
X413593Y1114780D01*
G02X414580Y1115150I987J-1131D01*
G02Y1112146I0J-1502D01*
G02X413593Y1112516I0J1501D01*
G01X413565Y1112540D01*
X413498Y1112565D01*
G37*
G36*
G01X445626D02*
X445290D01*
X445223Y1112540D01*
X445195Y1112516D01*
G02X444208Y1112146I-987J1131D01*
G02Y1115150I0J1502D01*
G02X445195Y1114780I0J-1501D01*
G01X445223Y1114756D01*
X445290Y1114731D01*
X445626D01*
X445693Y1114756D01*
X445721Y1114780D01*
G02X446708Y1115150I987J-1131D01*
G02Y1112146I0J-1502D01*
G02X445721Y1112516I0J1501D01*
G01X445693Y1112540D01*
X445626Y1112565D01*
G37*
G36*
G01X479085D02*
X478749D01*
X478682Y1112540D01*
X478654Y1112516D01*
G02X477667Y1112146I-987J1131D01*
G02Y1115150I0J1502D01*
G02X478654Y1114780I0J-1501D01*
G01X478682Y1114756D01*
X478749Y1114731D01*
X479085D01*
X479152Y1114756D01*
X479180Y1114780D01*
G02X480167Y1115150I987J-1131D01*
G02Y1112146I0J-1502D01*
G02X479180Y1112516I0J1501D01*
G01X479152Y1112540D01*
X479085Y1112565D01*
G37*
G36*
G01X511213D02*
X510877D01*
X510810Y1112540D01*
X510782Y1112516D01*
G02X509795Y1112146I-987J1131D01*
G02Y1115150I0J1502D01*
G02X510782Y1114780I0J-1501D01*
G01X510810Y1114756D01*
X510877Y1114731D01*
X511213D01*
X511280Y1114756D01*
X511308Y1114780D01*
G02X512295Y1115150I987J-1131D01*
G02Y1112146I0J-1502D01*
G02X511308Y1112516I0J1501D01*
G01X511280Y1112540D01*
X511213Y1112565D01*
G37*
G36*
G01X430393Y1116978D02*
Y1117314D01*
X430368Y1117381D01*
X430344Y1117409D01*
G02X429974Y1118396I1131J987D01*
G02X432978I1502J0D01*
G02X432608Y1117409I-1501J0D01*
G01X432584Y1117381D01*
X432559Y1117314D01*
Y1116978D01*
X432584Y1116911D01*
X432608Y1116883D01*
G02X432978Y1115896I-1131J-987D01*
G02X429974I-1502J0D01*
G02X430344Y1116883I1501J0D01*
G01X430368Y1116911D01*
X430393Y1116978D01*
G37*
G36*
G01X462521D02*
Y1117314D01*
X462496Y1117381D01*
X462472Y1117409D01*
G02X462102Y1118396I1131J987D01*
G02X465106I1502J0D01*
G02X464736Y1117409I-1501J0D01*
G01X464712Y1117381D01*
X464687Y1117314D01*
Y1116978D01*
X464712Y1116911D01*
X464736Y1116883D01*
G02X465106Y1115896I-1131J-987D01*
G02X462102I-1502J0D01*
G02X462472Y1116883I1501J0D01*
G01X462496Y1116911D01*
X462521Y1116978D01*
G37*
G36*
G01X495980D02*
Y1117314D01*
X495955Y1117381D01*
X495931Y1117409D01*
G02X495561Y1118396I1131J987D01*
G02X498565I1502J0D01*
G02X498195Y1117409I-1501J0D01*
G01X498171Y1117381D01*
X498146Y1117314D01*
Y1116978D01*
X498171Y1116911D01*
X498195Y1116883D01*
G02X498565Y1115896I-1131J-987D01*
G02X495561I-1502J0D01*
G02X495931Y1116883I1501J0D01*
G01X495955Y1116911D01*
X495980Y1116978D01*
G37*
G36*
G01X528108D02*
Y1117314D01*
X528083Y1117381D01*
X528059Y1117409D01*
G02X527689Y1118396I1131J987D01*
G02X530693I1502J0D01*
G02X530323Y1117409I-1501J0D01*
G01X530299Y1117381D01*
X530274Y1117314D01*
Y1116978D01*
X530299Y1116911D01*
X530323Y1116883D01*
G02X530693Y1115896I-1131J-987D01*
G02X527689I-1502J0D01*
G02X528059Y1116883I1501J0D01*
G01X528083Y1116911D01*
X528108Y1116978D01*
G37*
G36*
G01X459007Y1017640D02*
X458970Y1017669D01*
G02X458383Y1018860I915J1191D01*
G02X461387I1502J0D01*
G02X461380Y1018720I-1502J5D01*
G01X461376Y1018672D01*
X461411Y1018584D01*
X461725Y1018306D01*
X461817Y1018282D01*
X461864Y1018292D01*
G02X462185Y1018327I322J-1467D01*
G02Y1015323I0J-1502D01*
G02X461710Y1015400I0J1502D01*
G01X461675Y1015412D01*
X461602Y1015409D01*
X461289Y1015274D01*
X461237Y1015223D01*
X461221Y1015190D01*
G02X459860Y1014323I-1361J635D01*
G02X458358Y1015825I0J1502D01*
G02X458964Y1017031I1503J0D01*
G01X459003Y1017059D01*
X459045Y1017142D01*
X459048Y1017556D01*
X459007Y1017640D01*
G37*
G36*
G01X431105Y1020336D02*
X431399D01*
G03X431546Y1020401I-1J200D01*
G02X432652Y1020886I1105J-1017D01*
G02X434154Y1019384I0J-1502D01*
G02X433475Y1018128I-1501J0D01*
G01X433433Y1018100D01*
X433385Y1018010D01*
X433388Y1017572D01*
X433438Y1017483D01*
X433481Y1017455D01*
G02X434180Y1016186I-802J-1269D01*
G02X432678Y1014684I-1502J0D01*
G02X431572Y1015169I-1J1502D01*
G03X431425Y1015234I-148J-135D01*
G01X431131D01*
G03X430984Y1015169I1J-200D01*
G02X429878Y1014684I-1105J1017D01*
G02X428772Y1015169I-1J1502D01*
G03X428625Y1015234I-148J-135D01*
G01X428331D01*
G03X428184Y1015169I1J-200D01*
G02X427078Y1014684I-1105J1017D01*
G02X425576Y1016186I0J1502D01*
G02X426255Y1017442I1501J0D01*
G01X426297Y1017470D01*
X426345Y1017560D01*
X426342Y1017998D01*
X426292Y1018087D01*
X426249Y1018115D01*
G02X425550Y1019384I802J1269D01*
G02X427052Y1020886I1502J0D01*
G02X428158Y1020401I1J-1502D01*
G03X428305Y1020336I148J135D01*
G01X428599D01*
G03X428746Y1020401I-1J200D01*
G02X429852Y1020886I1105J-1017D01*
G02X430958Y1020401I1J-1502D01*
G03X431105Y1020336I148J135D01*
G37*
G36*
G01X473357Y1091860D02*
X473323Y1091888D01*
G02X472775Y1093048I954J1160D01*
G02X475779I1502J0D01*
G02X475287Y1091936I-1503J0D01*
G01X475254Y1091906D01*
X475220Y1091828D01*
X475230Y1091436D01*
X475268Y1091359D01*
X475302Y1091331D01*
G02X475689Y1090848I-954J-1161D01*
G01X475713Y1090800D01*
X475800Y1090742D01*
X476249Y1090711D01*
X476343Y1090756D01*
X476374Y1090800D01*
G02X477607Y1091444I1233J-858D01*
G02X479109Y1089942I0J-1502D01*
G02X478655Y1088866I-1502J0D01*
G01X478616Y1088828D01*
X478587Y1088721D01*
X478713Y1088277D01*
X478793Y1088201D01*
X478846Y1088189D01*
G02X480019Y1086724I-328J-1465D01*
G02X479649Y1085737I-1501J0D01*
G01X479625Y1085709D01*
X479600Y1085642D01*
Y1085306D01*
X479625Y1085239D01*
X479649Y1085211D01*
G02Y1083237I-1131J-987D01*
G01X479625Y1083209D01*
X479600Y1083142D01*
Y1082806D01*
X479625Y1082739D01*
X479649Y1082711D01*
G02X480019Y1081724I-1131J-987D01*
G02X478517Y1080222I-1502J0D01*
G02X477530Y1080592I0J1501D01*
G01X477502Y1080616D01*
X477435Y1080641D01*
X477099D01*
X477032Y1080616D01*
X477004Y1080592D01*
G02X476017Y1080222I-987J1131D01*
G02X474515Y1081724I0J1502D01*
G02X474885Y1082711I1501J0D01*
G01X474909Y1082739D01*
X474934Y1082806D01*
Y1083142D01*
X474909Y1083209D01*
X474885Y1083237D01*
G02Y1085211I1131J987D01*
G01X474909Y1085239D01*
X474934Y1085306D01*
Y1085642D01*
X474909Y1085709D01*
X474885Y1085737D01*
G02X474515Y1086724I1131J987D01*
G02X476017Y1088226I1502J0D01*
G02X477004Y1087856I0J-1501D01*
G01X477032Y1087832D01*
X477099Y1087807D01*
X477435D01*
X477502Y1087832D01*
X477530Y1087856D01*
G02X477846Y1088068I988J-1131D01*
G03X477739Y1088446I-90J179D01*
G02X477607Y1088440I-134J1496D01*
G02X476266Y1089265I0J1502D01*
G01X476242Y1089313D01*
X476155Y1089371D01*
X475706Y1089402D01*
X475612Y1089357D01*
X475581Y1089313D01*
G02X474348Y1088669I-1233J858D01*
G02X472846Y1090171I0J1502D01*
G02X473338Y1091283I1503J0D01*
G01X473371Y1091313D01*
X473405Y1091391D01*
X473395Y1091783D01*
X473357Y1091860D01*
G37*
G36*
G01X434758Y1093314D02*
X434767Y1093363D01*
G02X436244Y1094590I1477J-275D01*
G02X437746Y1093088I0J-1502D01*
G02X437261Y1091982I-1502J-1D01*
G03X437196Y1091835I135J-148D01*
G01Y1091541D01*
G03X437261Y1091394I200J1D01*
G02X437746Y1090288I-1017J-1105D01*
G02X436244Y1088786I-1502J0D01*
G02X435405Y1089042I0J1503D01*
G01X435366Y1089069D01*
X435273Y1089081D01*
X434883Y1088949D01*
X434817Y1088883D01*
X434802Y1088838D01*
G02X434510Y1088329I-1424J478D01*
G01X434486Y1088301D01*
X434461Y1088234D01*
Y1087898D01*
X434486Y1087831D01*
X434510Y1087803D01*
G02Y1085829I-1131J-987D01*
G01X434486Y1085801D01*
X434461Y1085734D01*
Y1085398D01*
X434486Y1085331D01*
X434510Y1085303D01*
G02Y1083329I-1131J-987D01*
G01X434486Y1083301D01*
X434461Y1083234D01*
Y1082898D01*
X434486Y1082831D01*
X434510Y1082803D01*
G02X434880Y1081816I-1131J-987D01*
G02X433378Y1080314I-1502J0D01*
G02X432391Y1080684I0J1501D01*
G01X432363Y1080708D01*
X432296Y1080733D01*
X431960D01*
X431893Y1080708D01*
X431865Y1080684D01*
G02X430878Y1080314I-987J1131D01*
G02X429376Y1081816I0J1502D01*
G02X429746Y1082803I1501J0D01*
G01X429770Y1082831D01*
X429795Y1082898D01*
Y1083234D01*
X429770Y1083301D01*
X429746Y1083329D01*
G02Y1085303I1131J987D01*
G01X429770Y1085331D01*
X429795Y1085398D01*
Y1085734D01*
X429770Y1085801D01*
X429746Y1085829D01*
G02X429376Y1086816I1131J987D01*
G02X430878Y1088318I1502J0D01*
G02X431926Y1087892I0J-1502D01*
G03X432065Y1087835I140J143D01*
G01X432191D01*
G03X432330Y1087892I-1J200D01*
G02X432359Y1087919I1038J-1086D01*
G01Y1088129D01*
G03X432302Y1088268I-200J-1D01*
G02X431876Y1089316I1076J1048D01*
G02X432246Y1090303I1501J0D01*
G01X432270Y1090331D01*
X432295Y1090398D01*
Y1090734D01*
X432270Y1090801D01*
X432246Y1090829D01*
G02X431876Y1091816I1131J987D01*
G02X433378Y1093318I1502J0D01*
G02X434165Y1093096I1J-1502D01*
G01X434208Y1093069D01*
X434305Y1093063D01*
X434698Y1093237D01*
X434758Y1093314D01*
G37*
G36*
G01X407924Y1092771D02*
G02X407345Y1093956I923J1185D01*
G02X410349I1502J0D01*
G02X409770Y1092771I-1502J0D01*
G03X409693Y1092614I123J-158D01*
G01Y1092298D01*
G03X409770Y1092141I200J1D01*
G02X410349Y1090956I-923J-1185D01*
G02X409689Y1089712I-1502J0D01*
G01X409646Y1089683D01*
X409599Y1089589D01*
X409622Y1089142D01*
X409678Y1089054D01*
X409725Y1089029D01*
G02X410051Y1088792I-712J-1322D01*
G01X410086Y1088759D01*
X410175Y1088732D01*
X410585Y1088800D01*
X410660Y1088855D01*
X410682Y1088897D01*
G02X411225Y1089482I1333J-692D01*
G01X411265Y1089507D01*
X411314Y1089587D01*
X411353Y1089999D01*
X411319Y1090086D01*
X411284Y1090118D01*
G02X410795Y1091227I1013J1109D01*
G02X413799I1502J0D01*
G02X413087Y1089950I-1501J0D01*
G01X413047Y1089925D01*
X412998Y1089845D01*
X412959Y1089433D01*
X412993Y1089346D01*
X413028Y1089314D01*
G02X413200Y1089128I-1013J-1109D01*
G03X413357Y1089051I158J123D01*
G01X413673D01*
G03X413830Y1089128I-1J200D01*
G02X415015Y1089707I1185J-923D01*
G02X416517Y1088205I0J-1502D01*
G02X415938Y1087020I-1502J0D01*
G03X415861Y1086863I123J-158D01*
G01Y1086547D01*
G03X415938Y1086390I200J1D01*
G02X416517Y1085205I-923J-1185D01*
G02X416061Y1084127I-1502J0D01*
G01X416032Y1084099D01*
X416001Y1084026D01*
X415997Y1083661D01*
X416027Y1083587D01*
X416056Y1083559D01*
G02X416491Y1082501I-1067J-1057D01*
G02X414989Y1080999I-1502J0D01*
G02X413804Y1081578I0J1502D01*
G03X413647Y1081655I-158J-123D01*
G01X413331D01*
G03X413174Y1081578I1J-200D01*
G02X410804I-1185J923D01*
G03X410647Y1081655I-158J-123D01*
G01X410331D01*
G03X410174Y1081578I1J-200D01*
G02X408989Y1080999I-1185J923D01*
G02X407487Y1082501I0J1502D01*
G02X407943Y1083579I1502J0D01*
G01X407972Y1083607D01*
X408003Y1083680D01*
X408007Y1084045D01*
X407977Y1084119D01*
X407948Y1084147D01*
G02X407513Y1085205I1067J1057D01*
G02X407883Y1086192I1501J0D01*
G01X407907Y1086220D01*
X407932Y1086287D01*
Y1086623D01*
X407907Y1086690D01*
X407883Y1086718D01*
G02X407513Y1087705I1131J987D01*
G02X408173Y1088949I1502J0D01*
G01X408216Y1088978D01*
X408263Y1089072D01*
X408240Y1089519D01*
X408184Y1089607D01*
X408137Y1089632D01*
G02X407345Y1090956I711J1324D01*
G02X407924Y1092141I1502J0D01*
G03X408001Y1092298I-123J158D01*
G01Y1092614D01*
G03X407924Y1092771I-200J-1D01*
G37*
G36*
G01X423604Y1106328D02*
X423588Y1106372D01*
G02X423493Y1106897I1407J526D01*
G02X426497I1502J0D01*
G02X425095Y1105398I-1502J0D01*
G01X425048Y1105395D01*
X424967Y1105347D01*
X424741Y1104998D01*
X424731Y1104904D01*
X424747Y1104860D01*
G02X424842Y1104335I-1407J-526D01*
G02X424785Y1103925I-1503J0D01*
G01X424772Y1103881D01*
X424788Y1103792D01*
X425022Y1103463D01*
X425101Y1103419D01*
X425147Y1103416D01*
G02X426562Y1101917I-86J-1499D01*
G02X423558I-1502J0D01*
G02X423615Y1102327I1503J0D01*
G01X423628Y1102371D01*
X423612Y1102460D01*
X423378Y1102789D01*
X423299Y1102833D01*
X423253Y1102836D01*
G02X421899Y1103910I86J1499D01*
G01X421887Y1103952D01*
X421832Y1104016D01*
X421485Y1104181D01*
X421401Y1104183D01*
X421361Y1104166D01*
G02X420782Y1104050I-579J1387D01*
G02X419340Y1105133I0J1502D01*
G01X419329Y1105171D01*
X419282Y1105231D01*
X418972Y1105409D01*
X418897Y1105419D01*
X418859Y1105410D01*
G02X418798Y1105396I-366J1457D01*
G01X418761Y1105388D01*
X418698Y1105348D01*
X418495Y1105069D01*
X418476Y1104997D01*
X418481Y1104959D01*
G02X418490Y1104792I-1493J-164D01*
G02X415486I-1502J0D01*
G02X416685Y1106263I1502J0D01*
G01X416722Y1106271D01*
X416785Y1106311D01*
X416988Y1106590D01*
X417007Y1106662D01*
X417002Y1106700D01*
G02X416993Y1106867I1493J164D01*
G02X418495Y1108369I1502J0D01*
G02X419937Y1107286I0J-1502D01*
G01X419948Y1107248D01*
X419995Y1107188D01*
X420305Y1107010D01*
X420380Y1107000D01*
X420418Y1107009D01*
G02X420782Y1107054I365J-1457D01*
G02X422223Y1105977I0J-1503D01*
G01X422235Y1105935D01*
X422290Y1105871D01*
X422637Y1105706D01*
X422721Y1105704D01*
X422761Y1105721D01*
G02X423240Y1105834I580J-1386D01*
G01X423287Y1105837D01*
X423368Y1105885D01*
X423594Y1106234D01*
X423604Y1106328D01*
G37*
G36*
G01X455732D02*
X455716Y1106372D01*
G02X455621Y1106897I1407J526D01*
G02X458625I1502J0D01*
G02X457223Y1105398I-1502J0D01*
G01X457176Y1105395D01*
X457095Y1105347D01*
X456869Y1104998D01*
X456859Y1104904D01*
X456875Y1104860D01*
G02X456970Y1104335I-1407J-526D01*
G02X456913Y1103925I-1503J0D01*
G01X456900Y1103881D01*
X456916Y1103792D01*
X457150Y1103463D01*
X457229Y1103419D01*
X457275Y1103416D01*
G02X458690Y1101917I-86J-1499D01*
G02X455686I-1502J0D01*
G02X455743Y1102327I1503J0D01*
G01X455756Y1102371D01*
X455740Y1102460D01*
X455506Y1102789D01*
X455427Y1102833D01*
X455381Y1102836D01*
G02X454027Y1103910I86J1499D01*
G01X454015Y1103952D01*
X453960Y1104016D01*
X453613Y1104181D01*
X453529Y1104183D01*
X453489Y1104166D01*
G02X452910Y1104050I-579J1387D01*
G02X451468Y1105133I0J1502D01*
G01X451457Y1105171D01*
X451410Y1105231D01*
X451100Y1105409D01*
X451025Y1105419D01*
X450987Y1105410D01*
G02X450926Y1105396I-366J1457D01*
G01X450889Y1105388D01*
X450826Y1105348D01*
X450623Y1105069D01*
X450604Y1104997D01*
X450609Y1104959D01*
G02X450618Y1104792I-1493J-164D01*
G02X447614I-1502J0D01*
G02X448813Y1106263I1502J0D01*
G01X448850Y1106271D01*
X448913Y1106311D01*
X449116Y1106590D01*
X449135Y1106662D01*
X449130Y1106700D01*
G02X449121Y1106867I1493J164D01*
G02X450623Y1108369I1502J0D01*
G02X452065Y1107286I0J-1502D01*
G01X452076Y1107248D01*
X452123Y1107188D01*
X452433Y1107010D01*
X452508Y1107000D01*
X452546Y1107009D01*
G02X452910Y1107054I365J-1457D01*
G02X454351Y1105977I0J-1503D01*
G01X454363Y1105935D01*
X454418Y1105871D01*
X454765Y1105706D01*
X454849Y1105704D01*
X454889Y1105721D01*
G02X455368Y1105834I580J-1386D01*
G01X455415Y1105837D01*
X455496Y1105885D01*
X455722Y1106234D01*
X455732Y1106328D01*
G37*
G36*
G01X489191D02*
X489175Y1106372D01*
G02X489080Y1106897I1407J526D01*
G02X492084I1502J0D01*
G02X490682Y1105398I-1502J0D01*
G01X490635Y1105395D01*
X490554Y1105347D01*
X490328Y1104998D01*
X490318Y1104904D01*
X490334Y1104860D01*
G02X490429Y1104335I-1407J-526D01*
G02X490372Y1103925I-1503J0D01*
G01X490359Y1103881D01*
X490375Y1103792D01*
X490609Y1103463D01*
X490688Y1103419D01*
X490734Y1103416D01*
G02X492149Y1101917I-86J-1499D01*
G02X489145I-1502J0D01*
G02X489202Y1102327I1503J0D01*
G01X489215Y1102371D01*
X489199Y1102460D01*
X488965Y1102789D01*
X488886Y1102833D01*
X488840Y1102836D01*
G02X487486Y1103910I86J1499D01*
G01X487474Y1103952D01*
X487419Y1104016D01*
X487072Y1104181D01*
X486988Y1104183D01*
X486948Y1104166D01*
G02X486369Y1104050I-579J1387D01*
G02X484927Y1105133I0J1502D01*
G01X484916Y1105171D01*
X484869Y1105231D01*
X484559Y1105409D01*
X484484Y1105419D01*
X484446Y1105410D01*
G02X484385Y1105396I-366J1457D01*
G01X484348Y1105388D01*
X484285Y1105348D01*
X484082Y1105069D01*
X484063Y1104997D01*
X484068Y1104959D01*
G02X484077Y1104792I-1493J-164D01*
G02X481073I-1502J0D01*
G02X482272Y1106263I1502J0D01*
G01X482309Y1106271D01*
X482372Y1106311D01*
X482575Y1106590D01*
X482594Y1106662D01*
X482589Y1106700D01*
G02X482580Y1106867I1493J164D01*
G02X484082Y1108369I1502J0D01*
G02X485524Y1107286I0J-1502D01*
G01X485535Y1107248D01*
X485582Y1107188D01*
X485892Y1107010D01*
X485967Y1107000D01*
X486005Y1107009D01*
G02X486369Y1107054I365J-1457D01*
G02X487810Y1105977I0J-1503D01*
G01X487822Y1105935D01*
X487877Y1105871D01*
X488224Y1105706D01*
X488308Y1105704D01*
X488348Y1105721D01*
G02X488827Y1105834I580J-1386D01*
G01X488874Y1105837D01*
X488955Y1105885D01*
X489181Y1106234D01*
X489191Y1106328D01*
G37*
G36*
G01X521319D02*
X521303Y1106372D01*
G02X521208Y1106897I1407J526D01*
G02X524212I1502J0D01*
G02X522810Y1105398I-1502J0D01*
G01X522763Y1105395D01*
X522682Y1105347D01*
X522456Y1104998D01*
X522446Y1104904D01*
X522462Y1104860D01*
G02X522557Y1104335I-1407J-526D01*
G02X522500Y1103925I-1503J0D01*
G01X522487Y1103881D01*
X522503Y1103792D01*
X522737Y1103463D01*
X522816Y1103419D01*
X522862Y1103416D01*
G02X524277Y1101917I-86J-1499D01*
G02X521273I-1502J0D01*
G02X521330Y1102327I1503J0D01*
G01X521343Y1102371D01*
X521327Y1102460D01*
X521093Y1102789D01*
X521014Y1102833D01*
X520968Y1102836D01*
G02X519614Y1103910I86J1499D01*
G01X519602Y1103952D01*
X519547Y1104016D01*
X519200Y1104181D01*
X519116Y1104183D01*
X519076Y1104166D01*
G02X518497Y1104050I-579J1387D01*
G02X517055Y1105133I0J1502D01*
G01X517044Y1105171D01*
X516997Y1105231D01*
X516687Y1105409D01*
X516612Y1105419D01*
X516574Y1105410D01*
G02X516513Y1105396I-366J1457D01*
G01X516476Y1105388D01*
X516413Y1105348D01*
X516210Y1105069D01*
X516191Y1104997D01*
X516196Y1104959D01*
G02X516205Y1104792I-1493J-164D01*
G02X513201I-1502J0D01*
G02X514400Y1106263I1502J0D01*
G01X514437Y1106271D01*
X514500Y1106311D01*
X514703Y1106590D01*
X514722Y1106662D01*
X514717Y1106700D01*
G02X514708Y1106867I1493J164D01*
G02X516210Y1108369I1502J0D01*
G02X517652Y1107286I0J-1502D01*
G01X517663Y1107248D01*
X517710Y1107188D01*
X518020Y1107010D01*
X518095Y1107000D01*
X518133Y1107009D01*
G02X518497Y1107054I365J-1457D01*
G02X519938Y1105977I0J-1503D01*
G01X519950Y1105935D01*
X520005Y1105871D01*
X520352Y1105706D01*
X520436Y1105704D01*
X520476Y1105721D01*
G02X520955Y1105834I580J-1386D01*
G01X521002Y1105837D01*
X521083Y1105885D01*
X521309Y1106234D01*
X521319Y1106328D01*
G37*
G36*
G01X401723Y1112652D02*
G02X401193Y1113797I972J1145D01*
G02X402695Y1115299I1502J0D01*
G02X404151Y1114167I0J-1502D01*
G01X404160Y1114130D01*
X404205Y1114068D01*
X404501Y1113880D01*
X404576Y1113865D01*
X404613Y1113872D01*
G02X404895Y1113899I284J-1475D01*
G02X405698Y1113666I0J-1502D01*
G01X405740Y1113640D01*
X405839Y1113632D01*
X406233Y1113803D01*
X406295Y1113881D01*
X406305Y1113929D01*
G02X407780Y1115150I1475J-280D01*
G02X409282Y1113648I0J-1502D01*
G02X408285Y1112234I-1501J0D01*
G01X408238Y1112217D01*
X408171Y1112144D01*
X408064Y1111726D01*
X408087Y1111630D01*
X408120Y1111592D01*
G02X408497Y1110597I-1125J-995D01*
G02X408050Y1109528I-1502J0D01*
G01X408023Y1109501D01*
X407993Y1109433D01*
X407979Y1109081D01*
X408004Y1109011D01*
X408029Y1108982D01*
G02X408397Y1107997I-1134J-985D01*
G02X406895Y1106495I-1502J0D01*
G02X405442Y1107615I0J1503D01*
G01X405433Y1107650D01*
X405391Y1107710D01*
X405108Y1107898D01*
X405037Y1107914D01*
X405001Y1107909D01*
G02X404795Y1107895I-205J1488D01*
G02X404589Y1107909I-1J1502D01*
G01X404553Y1107914D01*
X404482Y1107898D01*
X404199Y1107710D01*
X404157Y1107650D01*
X404148Y1107615D01*
G02X402695Y1106495I-1453J383D01*
G02X401193Y1107997I0J1502D01*
G02X401723Y1109142I1502J0D01*
G03X401794Y1109295I-129J153D01*
G01Y1109599D01*
G03X401723Y1109752I-200J0D01*
G02Y1112042I972J1145D01*
G03X401794Y1112195I-129J153D01*
G01Y1112499D01*
G03X401723Y1112652I-200J0D01*
G37*
G36*
G01X440330Y1117707D02*
X440301Y1117735D01*
G02X439857Y1118801I1058J1066D01*
G02X442861I1502J0D01*
G02X442417Y1117735I-1502J0D01*
G01X442388Y1117707D01*
X442358Y1117633D01*
Y1117269D01*
X442388Y1117195D01*
X442417Y1117167D01*
G02X442861Y1116101I-1058J-1066D01*
G02X441642Y1114626I-1502J0D01*
G01X441600Y1114618D01*
X441530Y1114569D01*
X441333Y1114236D01*
X441324Y1114151D01*
X441337Y1114110D01*
G02X441410Y1113648I-1429J-463D01*
G02X440413Y1112234I-1501J0D01*
G01X440366Y1112217D01*
X440299Y1112144D01*
X440192Y1111726D01*
X440215Y1111630D01*
X440248Y1111592D01*
G02X440625Y1110597I-1125J-995D01*
G02X440178Y1109528I-1502J0D01*
G01X440151Y1109501D01*
X440121Y1109433D01*
X440107Y1109081D01*
X440132Y1109011D01*
X440157Y1108982D01*
G02X440525Y1107997I-1134J-985D01*
G02X439023Y1106495I-1502J0D01*
G02X437570Y1107615I0J1503D01*
G01X437561Y1107650D01*
X437519Y1107710D01*
X437236Y1107898D01*
X437165Y1107914D01*
X437129Y1107909D01*
G02X436923Y1107895I-205J1488D01*
G02X436717Y1107909I-1J1502D01*
G01X436681Y1107914D01*
X436610Y1107898D01*
X436327Y1107710D01*
X436285Y1107650D01*
X436276Y1107615D01*
G02X434823Y1106495I-1453J383D01*
G02X433321Y1107997I0J1502D01*
G02X433851Y1109142I1502J0D01*
G03X433922Y1109295I-129J153D01*
G01Y1109599D01*
G03X433851Y1109752I-200J0D01*
G02Y1112042I972J1145D01*
G03X433922Y1112195I-129J153D01*
G01Y1112499D01*
G03X433851Y1112652I-200J0D01*
G02X433321Y1113797I972J1145D01*
G02X434823Y1115299I1502J0D01*
G02X436279Y1114167I0J-1502D01*
G01X436288Y1114130D01*
X436333Y1114068D01*
X436629Y1113880D01*
X436704Y1113865D01*
X436741Y1113872D01*
G02X437023Y1113899I284J-1475D01*
G02X437826Y1113666I0J-1502D01*
G01X437868Y1113640D01*
X437967Y1113632D01*
X438361Y1113803D01*
X438423Y1113881D01*
X438433Y1113929D01*
G02X439625Y1115123I1475J-281D01*
G01X439667Y1115131D01*
X439737Y1115180D01*
X439934Y1115513D01*
X439943Y1115598D01*
X439930Y1115639D01*
G02X439857Y1116101I1429J463D01*
G02X440301Y1117167I1502J0D01*
G01X440330Y1117195D01*
X440360Y1117269D01*
Y1117633D01*
X440330Y1117707D01*
G37*
G36*
G01X473789D02*
X473760Y1117735D01*
G02X473316Y1118801I1058J1066D01*
G02X476320I1502J0D01*
G02X475876Y1117735I-1502J0D01*
G01X475847Y1117707D01*
X475817Y1117633D01*
Y1117269D01*
X475847Y1117195D01*
X475876Y1117167D01*
G02X476320Y1116101I-1058J-1066D01*
G02X475101Y1114626I-1502J0D01*
G01X475059Y1114618D01*
X474989Y1114569D01*
X474792Y1114236D01*
X474783Y1114151D01*
X474796Y1114110D01*
G02X474869Y1113648I-1429J-463D01*
G02X473872Y1112234I-1501J0D01*
G01X473825Y1112217D01*
X473758Y1112144D01*
X473651Y1111726D01*
X473674Y1111630D01*
X473707Y1111592D01*
G02X474084Y1110597I-1125J-995D01*
G02X473637Y1109528I-1502J0D01*
G01X473610Y1109501D01*
X473580Y1109433D01*
X473566Y1109081D01*
X473591Y1109011D01*
X473616Y1108982D01*
G02X473984Y1107997I-1134J-985D01*
G02X472482Y1106495I-1502J0D01*
G02X471029Y1107615I0J1503D01*
G01X471020Y1107650D01*
X470978Y1107710D01*
X470695Y1107898D01*
X470624Y1107914D01*
X470588Y1107909D01*
G02X470382Y1107895I-205J1488D01*
G02X470176Y1107909I-1J1502D01*
G01X470140Y1107914D01*
X470069Y1107898D01*
X469786Y1107710D01*
X469744Y1107650D01*
X469735Y1107615D01*
G02X468282Y1106495I-1453J383D01*
G02X466780Y1107997I0J1502D01*
G02X467310Y1109142I1502J0D01*
G03X467381Y1109295I-129J153D01*
G01Y1109599D01*
G03X467310Y1109752I-200J0D01*
G02Y1112042I972J1145D01*
G03X467381Y1112195I-129J153D01*
G01Y1112499D01*
G03X467310Y1112652I-200J0D01*
G02X466780Y1113797I972J1145D01*
G02X468282Y1115299I1502J0D01*
G02X469738Y1114167I0J-1502D01*
G01X469747Y1114130D01*
X469792Y1114068D01*
X470088Y1113880D01*
X470163Y1113865D01*
X470200Y1113872D01*
G02X470482Y1113899I284J-1475D01*
G02X471285Y1113666I0J-1502D01*
G01X471327Y1113640D01*
X471426Y1113632D01*
X471820Y1113803D01*
X471882Y1113881D01*
X471892Y1113929D01*
G02X473084Y1115123I1475J-281D01*
G01X473126Y1115131D01*
X473196Y1115180D01*
X473393Y1115513D01*
X473402Y1115598D01*
X473389Y1115639D01*
G02X473316Y1116101I1429J463D01*
G02X473760Y1117167I1502J0D01*
G01X473789Y1117195D01*
X473819Y1117269D01*
Y1117633D01*
X473789Y1117707D01*
G37*
G36*
G01X505917D02*
X505888Y1117735D01*
G02X505444Y1118801I1058J1066D01*
G02X508448I1502J0D01*
G02X508004Y1117735I-1502J0D01*
G01X507975Y1117707D01*
X507945Y1117633D01*
Y1117269D01*
X507975Y1117195D01*
X508004Y1117167D01*
G02X508448Y1116101I-1058J-1066D01*
G02X507229Y1114626I-1502J0D01*
G01X507187Y1114618D01*
X507117Y1114569D01*
X506920Y1114236D01*
X506911Y1114151D01*
X506924Y1114110D01*
G02X506997Y1113648I-1429J-463D01*
G02X506000Y1112234I-1501J0D01*
G01X505953Y1112217D01*
X505886Y1112144D01*
X505779Y1111726D01*
X505802Y1111630D01*
X505835Y1111592D01*
G02X506212Y1110597I-1125J-995D01*
G02X505765Y1109528I-1502J0D01*
G01X505738Y1109501D01*
X505708Y1109433D01*
X505694Y1109081D01*
X505719Y1109011D01*
X505744Y1108982D01*
G02X506112Y1107997I-1134J-985D01*
G02X504610Y1106495I-1502J0D01*
G02X503157Y1107615I0J1503D01*
G01X503148Y1107650D01*
X503106Y1107710D01*
X502823Y1107898D01*
X502752Y1107914D01*
X502716Y1107909D01*
G02X502510Y1107895I-205J1488D01*
G02X502304Y1107909I-1J1502D01*
G01X502268Y1107914D01*
X502197Y1107898D01*
X501914Y1107710D01*
X501872Y1107650D01*
X501863Y1107615D01*
G02X500410Y1106495I-1453J383D01*
G02X498908Y1107997I0J1502D01*
G02X499438Y1109142I1502J0D01*
G03X499509Y1109295I-129J153D01*
G01Y1109599D01*
G03X499438Y1109752I-200J0D01*
G02Y1112042I972J1145D01*
G03X499509Y1112195I-129J153D01*
G01Y1112499D01*
G03X499438Y1112652I-200J0D01*
G02X498908Y1113797I972J1145D01*
G02X500410Y1115299I1502J0D01*
G02X501866Y1114167I0J-1502D01*
G01X501875Y1114130D01*
X501920Y1114068D01*
X502216Y1113880D01*
X502291Y1113865D01*
X502328Y1113872D01*
G02X502610Y1113899I284J-1475D01*
G02X503413Y1113666I0J-1502D01*
G01X503455Y1113640D01*
X503554Y1113632D01*
X503948Y1113803D01*
X504010Y1113881D01*
X504020Y1113929D01*
G02X505212Y1115123I1475J-281D01*
G01X505254Y1115131D01*
X505324Y1115180D01*
X505521Y1115513D01*
X505530Y1115598D01*
X505517Y1115639D01*
G02X505444Y1116101I1429J463D01*
G02X505888Y1117167I1502J0D01*
G01X505917Y1117195D01*
X505947Y1117269D01*
Y1117633D01*
X505917Y1117707D01*
G37*
G36*
G01X407210Y1350944D02*
X407436Y1351209D01*
X407460Y1351293D01*
X407453Y1351336D01*
G02X407435Y1351568I1484J232D01*
G02X410439I1502J0D01*
G02X409810Y1350345I-1502J-1D01*
G03X409731Y1350226I116J-163D01*
G01X409704Y1350107D01*
G03X409725Y1349964I195J-44D01*
G02X409962Y1349072I-1566J-893D01*
G02X408159Y1347270I-1803J1D01*
G01X404759D01*
G02X402956Y1349072I-1J1802D01*
G02X403193Y1349964I1803J-1D01*
G03X403214Y1350107I-174J99D01*
G01X403187Y1350226D01*
G03X403108Y1350345I-195J-44D01*
G02X402479Y1351568I873J1222D01*
G02X405483I1502J0D01*
G02X405465Y1351336I-1502J0D01*
G01X405458Y1351293D01*
X405482Y1351209D01*
X405708Y1350944D01*
G03X405860Y1350874I152J130D01*
G01X407058D01*
G03X407210Y1350944I0J200D01*
G37*
G36*
G01X390746Y1364086D02*
X390368Y1364217D01*
X390280Y1364208D01*
X390241Y1364184D01*
G02X389458Y1363964I-783J1283D01*
G02Y1366968I0J1502D01*
G02X390867Y1365986I0J-1502D01*
G01X390883Y1365943D01*
X390946Y1365881D01*
X391324Y1365750D01*
X391412Y1365759D01*
X391451Y1365783D01*
G02X392234Y1366003I783J-1283D01*
G02Y1362999I0J-1502D01*
G02X390825Y1363981I0J1502D01*
G01X390809Y1364024D01*
X390746Y1364086D01*
G37*
G36*
G01X390545Y1368389D02*
G02X389188Y1367531I-1357J644D01*
G02Y1370535I0J1502D01*
G02X390237Y1370108I0J-1502D01*
G03X390877Y1370223I279J287D01*
G02X392234Y1371081I1357J-644D01*
G02Y1368077I0J-1502D01*
G02X391185Y1368504I0J1502D01*
G03X390545Y1368389I-279J-287D01*
G37*
G36*
G01X450902Y554990D02*
G02X452404Y556492I1502J0D01*
G02X453465Y556053I0J-1502D01*
G01X453492Y556026D01*
X453562Y555996D01*
X453914Y555985D01*
X453984Y556010D01*
X454013Y556036D01*
G02X455009Y556414I996J-1123D01*
G02X456511Y554912I0J-1502D01*
G02X456105Y553885I-1502J0D01*
G01X456079Y553858D01*
X456051Y553787D01*
Y553437D01*
X456079Y553366D01*
X456105Y553339D01*
G02Y551285I-1096J-1027D01*
G01X456079Y551258D01*
X456051Y551187D01*
Y550837D01*
X456079Y550766D01*
X456105Y550739D01*
G02X456511Y549712I-1096J-1027D01*
G02X456026Y548606I-1504J0D01*
G03X455961Y548459I135J-148D01*
G01Y548165D01*
G03X456026Y548018I200J1D01*
G02X456511Y546912I-1019J-1106D01*
G02X456105Y545885I-1502J0D01*
G01X456079Y545858D01*
X456051Y545787D01*
Y545437D01*
X456079Y545366D01*
X456105Y545339D01*
G02X456511Y544312I-1096J-1027D01*
G02X455009Y542810I-1502J0D01*
G02X453948Y543249I0J1502D01*
G01X453921Y543276D01*
X453851Y543306D01*
X453499Y543317D01*
X453429Y543292D01*
X453400Y543266D01*
G02X452404Y542888I-996J1123D01*
G02X450902Y544390I0J1502D01*
G02X451308Y545417I1502J0D01*
G01X451334Y545444D01*
X451362Y545515D01*
Y545865D01*
X451334Y545936D01*
X451308Y545963D01*
G02X450902Y546990I1096J1027D01*
G02X451387Y548096I1504J0D01*
G03X451452Y548243I-135J148D01*
G01Y548537D01*
G03X451387Y548684I-200J-1D01*
G02X450902Y549790I1019J1106D01*
G02X451308Y550817I1502J0D01*
G01X451334Y550844D01*
X451362Y550915D01*
Y551265D01*
X451334Y551336D01*
X451308Y551363D01*
G02Y553417I1096J1027D01*
G01X451334Y553444D01*
X451362Y553515D01*
Y553865D01*
X451334Y553936D01*
X451308Y553963D01*
G02X450902Y554990I1096J1027D01*
G37*
G36*
G01X441502Y555090D02*
G02X444506I1502J0D01*
G02X444100Y554063I-1502J0D01*
G01X444074Y554036D01*
X444046Y553965D01*
Y553615D01*
X444074Y553544D01*
X444100Y553517D01*
G02Y551463I-1096J-1027D01*
G01X444074Y551436D01*
X444046Y551365D01*
Y551015D01*
X444074Y550944D01*
X444100Y550917D01*
G02X444506Y549890I-1096J-1027D01*
G02X443892Y548678I-1503J0D01*
G03X443811Y548530I118J-161D01*
G01X443789Y548225D01*
G03X443849Y548068I200J-14D01*
G02X444306Y546990I-1045J-1079D01*
G02X443900Y545963I-1502J0D01*
G01X443874Y545936D01*
X443846Y545865D01*
Y545515D01*
X443874Y545444D01*
X443900Y545417D01*
G02X444306Y544390I-1096J-1027D01*
G02X441302I-1502J0D01*
G02X441708Y545417I1502J0D01*
G01X441734Y545444D01*
X441762Y545515D01*
Y545865D01*
X441734Y545936D01*
X441708Y545963D01*
G02X441302Y546990I1096J1027D01*
G02X441916Y548202I1503J0D01*
G03X441997Y548350I-118J161D01*
G01X442019Y548655D01*
G03X441959Y548812I-200J14D01*
G02X441502Y549890I1045J1079D01*
G02X441908Y550917I1502J0D01*
G01X441934Y550944D01*
X441962Y551015D01*
Y551365D01*
X441934Y551436D01*
X441908Y551463D01*
G02Y553517I1096J1027D01*
G01X441934Y553544D01*
X441962Y553615D01*
Y553965D01*
X441934Y554036D01*
X441908Y554063D01*
G02X441502Y555090I1096J1027D01*
G37*
G36*
G01X417838Y555190D02*
G02X420842I1502J0D01*
G02X420436Y554163I-1502J0D01*
G01X420410Y554136D01*
X420382Y554065D01*
Y553715D01*
X420410Y553644D01*
X420436Y553617D01*
G02Y551563I-1096J-1027D01*
G01X420410Y551536D01*
X420382Y551465D01*
Y551115D01*
X420410Y551044D01*
X420436Y551017D01*
G02X420842Y549990I-1096J-1027D01*
G02X420352Y548881I-1502J1D01*
G03X420350Y548879I140J-142D01*
G03X420287Y548748I136J-146D01*
G01X420265Y548474D01*
G03X420309Y548333I200J-15D01*
G02X420642Y547390I-1169J-943D01*
G02X420236Y546363I-1502J0D01*
G01X420210Y546336D01*
X420182Y546265D01*
Y545915D01*
X420210Y545844D01*
X420236Y545817D01*
G02X420642Y544790I-1096J-1027D01*
G02X417638I-1502J0D01*
G02X418044Y545817I1502J0D01*
G01X418070Y545844D01*
X418098Y545915D01*
Y546265D01*
X418070Y546336D01*
X418044Y546363D01*
G02X417638Y547390I1096J1027D01*
G02X418128Y548499I1502J-1D01*
G03X418130Y548501I-140J142D01*
G03X418193Y548632I-136J146D01*
G01X418215Y548906D01*
G03X418171Y549047I-200J15D01*
G02X417838Y549990I1169J943D01*
G02X418244Y551017I1502J0D01*
G01X418270Y551044D01*
X418298Y551115D01*
Y551465D01*
X418270Y551536D01*
X418244Y551563D01*
G02Y553617I1096J1027D01*
G01X418270Y553644D01*
X418298Y553715D01*
Y554065D01*
X418270Y554136D01*
X418244Y554163D01*
G02X417838Y555190I1096J1027D01*
G37*
G36*
G01X427238D02*
G02X428740Y556692I1502J0D01*
G02X429784Y556270I0J-1502D01*
G01X429813Y556242D01*
X429883Y556214D01*
X430241D01*
X430311Y556242D01*
X430340Y556270D01*
G02X431384Y556692I1044J-1080D01*
G02X432886Y555190I0J-1502D01*
G02X432480Y554163I-1502J0D01*
G01X432454Y554136D01*
X432426Y554065D01*
Y553715D01*
X432454Y553644D01*
X432480Y553617D01*
G02Y551563I-1096J-1027D01*
G01X432454Y551536D01*
X432426Y551465D01*
Y551115D01*
X432454Y551044D01*
X432480Y551017D01*
G02X432886Y549990I-1096J-1027D01*
G02X432307Y548805I-1502J0D01*
G03X432230Y548647I123J-158D01*
G01Y548333D01*
G03X432307Y548175I200J0D01*
G02X432886Y546990I-923J-1185D01*
G02X432480Y545963I-1502J0D01*
G01X432454Y545936D01*
X432426Y545865D01*
Y545515D01*
X432454Y545444D01*
X432480Y545417D01*
G02X432886Y544390I-1096J-1027D01*
G02X431384Y542888I-1502J0D01*
G02X430340Y543310I0J1502D01*
G01X430311Y543338D01*
X430241Y543366D01*
X429883D01*
X429813Y543338D01*
X429784Y543310D01*
G02X428740Y542888I-1044J1080D01*
G02X427238Y544390I0J1502D01*
G02X427644Y545417I1502J0D01*
G01X427670Y545444D01*
X427698Y545515D01*
Y545865D01*
X427670Y545936D01*
X427644Y545963D01*
G02X427238Y546990I1096J1027D01*
G02X427817Y548175I1502J0D01*
G03X427894Y548333I-123J158D01*
G01Y548647D01*
G03X427817Y548805I-200J0D01*
G02X427238Y549990I923J1185D01*
G02X427644Y551017I1502J0D01*
G01X427670Y551044D01*
X427698Y551115D01*
Y551465D01*
X427670Y551536D01*
X427644Y551563D01*
G02Y553617I1096J1027D01*
G01X427670Y553644D01*
X427698Y553715D01*
Y554065D01*
X427670Y554136D01*
X427644Y554163D01*
G02X427238Y555190I1096J1027D01*
G37*
G36*
G01X437777Y713531D02*
X437778Y713530D01*
G03X437908Y713482I130J152D01*
G01X438172D01*
G03X438302Y713530I0J200D01*
G01X438303Y713531D01*
G02X439290Y713901I987J-1131D01*
G02X440792Y712399I0J-1502D01*
G02X440386Y711372I-1502J0D01*
G01X440360Y711345D01*
X440332Y711274D01*
Y710924D01*
X440360Y710853D01*
X440386Y710826D01*
G02X440792Y709799I-1096J-1027D01*
G02X439290Y708297I-1502J0D01*
G02X438303Y708667I0J1501D01*
G01X438302D01*
Y708668D01*
G03X438172Y708716I-130J-152D01*
G01X437908D01*
G03X437778Y708668I0J-200D01*
G01X437777Y708667D01*
G02X435803I-987J1131D01*
G01X435802D01*
Y708668D01*
G03X435672Y708716I-130J-152D01*
G01X435408D01*
G03X435278Y708668I0J-200D01*
G01X435277Y708667D01*
G02X433303I-987J1131D01*
G01X433302D01*
Y708668D01*
G03X433172Y708716I-130J-152D01*
G01X432908D01*
G03X432778Y708668I0J-200D01*
G01X432777Y708667D01*
G02X430803I-987J1131D01*
G01X430802D01*
Y708668D01*
G03X430672Y708716I-130J-152D01*
G01X430408D01*
G03X430278Y708668I0J-200D01*
G01X430277Y708667D01*
G02X429290Y708297I-987J1131D01*
G02X428246Y708719I0J1502D01*
G01X428217Y708747D01*
X428145Y708775D01*
X427822Y708771D01*
G03X427682Y708711I3J-200D01*
G02X426607Y708258I-1075J1049D01*
G02X425105Y709760I0J1502D01*
G02X425511Y710787I1502J0D01*
G01X425537Y710814D01*
X425565Y710885D01*
Y711235D01*
X425537Y711306D01*
X425511Y711333D01*
G02X425105Y712360I1096J1027D01*
G02X426607Y713862I1502J0D01*
G02X427651Y713440I0J-1502D01*
G01X427680Y713412D01*
X427752Y713384D01*
X428075Y713388D01*
G03X428215Y713448I-3J200D01*
G02X429290Y713901I1075J-1049D01*
G02X430277Y713531I0J-1501D01*
G01X430278D01*
Y713530D01*
G03X430408Y713482I130J152D01*
G01X430672D01*
G03X430802Y713530I0J200D01*
G01X430803Y713531D01*
G02X432777I987J-1131D01*
G01X432778D01*
Y713530D01*
G03X432908Y713482I130J152D01*
G01X433172D01*
G03X433302Y713530I0J200D01*
G01X433303Y713531D01*
G02X435277I987J-1131D01*
G01X435278D01*
Y713530D01*
G03X435408Y713482I130J152D01*
G01X435672D01*
G03X435802Y713530I0J200D01*
G01X435803Y713531D01*
G02X437777I987J-1131D01*
G37*
G36*
G01X580465Y1142891D02*
G02X583469I1502J0D01*
G02X582908Y1141720I-1503J0D01*
G01X582872Y1141691D01*
X582833Y1141608D01*
X582838Y1141246D01*
G03X582917Y1141089I200J2D01*
G02X583514Y1139891I-905J-1199D01*
G02X580510I-1502J0D01*
G02X581071Y1141062I1503J0D01*
G01X581107Y1141091D01*
X581146Y1141174D01*
X581141Y1141536D01*
G03X581062Y1141693I-200J-2D01*
G02X580465Y1142891I905J1199D01*
G37*
G36*
G01Y1155491D02*
G02X583469I1502J0D01*
G02X582908Y1154320I-1503J0D01*
G01X582872Y1154291D01*
X582833Y1154208D01*
X582838Y1153846D01*
G03X582917Y1153689I200J2D01*
G02X583514Y1152491I-905J-1199D01*
G02X580510I-1502J0D01*
G02X581071Y1153662I1503J0D01*
G01X581107Y1153691D01*
X581146Y1153774D01*
X581141Y1154136D01*
G03X581062Y1154293I-200J-2D01*
G02X580465Y1155491I905J1199D01*
G37*
G36*
G01Y1168091D02*
G02X583469I1502J0D01*
G02X582908Y1166920I-1503J0D01*
G01X582872Y1166891D01*
X582833Y1166808D01*
X582838Y1166446D01*
G03X582917Y1166289I200J2D01*
G02X583514Y1165091I-905J-1199D01*
G02X580510I-1502J0D01*
G02X581071Y1166262I1503J0D01*
G01X581107Y1166291D01*
X581146Y1166374D01*
X581141Y1166736D01*
G03X581062Y1166893I-200J-2D01*
G02X580465Y1168091I905J1199D01*
G37*
G36*
G01X600294Y1171872D02*
X604034D01*
G02Y1169268I0J-1302D01*
G01X600294D01*
G02X599287Y1169744I0J1303D01*
G01X599259Y1169778D01*
X599182Y1169815D01*
X598791Y1169826D01*
X598712Y1169792D01*
X598683Y1169760D01*
G02X597795Y1169368I-888J810D01*
G02Y1171772I0J1202D01*
G02X598683Y1171380I0J-1202D01*
G01X598712Y1171348D01*
X598791Y1171314D01*
X599138Y1171324D01*
G03X599287Y1171396I-5J200D01*
G02X600294Y1171872I1007J-827D01*
G37*
G36*
G01Y1179354D02*
X604034D01*
G02Y1176748I0J-1303D01*
G01X600294D01*
G02X599288Y1177224I1J1303D01*
G01X599260Y1177258D01*
X599182Y1177296D01*
X598835Y1177305D01*
G03X598684Y1177241I-4J-200D01*
G01X598683Y1177240D01*
G02X597795Y1176848I-888J810D01*
G02Y1179252I0J1202D01*
G02X598682Y1178861I0J-1202D01*
G03X598835Y1178795I149J134D01*
G01X599137Y1178804D01*
G03X599287Y1178877I-4J200D01*
G02X600294Y1179354I1008J-826D01*
G37*
G36*
G01X612184Y1179921D02*
G02X614588I1202J0D01*
G02X614581Y1179796I-1202J5D01*
G01Y1179794D01*
X614577Y1179753D01*
X614603Y1179673D01*
X614830Y1179420D01*
G03X614979Y1179354I149J134D01*
G01X615256D01*
G02Y1176748I0J-1303D01*
G01X611516D01*
G02Y1179354I0J1303D01*
G01X611793D01*
G03X611942Y1179420I0J200D01*
G01X612169Y1179673D01*
X612195Y1179753D01*
X612191Y1179795D01*
G02X612184Y1179921I1195J130D01*
G37*
G36*
G01X580465Y1180691D02*
G02X583469I1502J0D01*
G02X582908Y1179520I-1503J0D01*
G01X582872Y1179491D01*
X582833Y1179408D01*
X582838Y1179046D01*
G03X582917Y1178889I200J2D01*
G02X583514Y1177691I-905J-1199D01*
G02X580510I-1502J0D01*
G02X581071Y1178862I1503J0D01*
G01X581107Y1178891D01*
X581146Y1178974D01*
X581141Y1179336D01*
G03X581062Y1179493I-200J-2D01*
G02X580465Y1180691I905J1199D01*
G37*
G36*
G01X475704Y1200821D02*
G02X478708I1502J0D01*
G02X478338Y1199834I-1501J0D01*
G01Y1199833D01*
X478337D01*
G03X478289Y1199703I152J-130D01*
G01Y1199439D01*
G03X478337Y1199309I200J0D01*
G01X478338Y1199308D01*
G02X478708Y1198321I-1131J-987D01*
G02X475704I-1502J0D01*
G02X476074Y1199308I1501J0D01*
G01Y1199309D01*
X476075D01*
G03X476123Y1199439I-152J130D01*
G01Y1199703D01*
G03X476075Y1199833I-200J0D01*
G01X476074Y1199834D01*
G02X475704Y1200821I1131J987D01*
G37*
G36*
G01X489169D02*
G02X492173I1502J0D01*
G02X491803Y1199834I-1501J0D01*
G01Y1199833D01*
X491802D01*
G03X491754Y1199703I152J-130D01*
G01Y1199439D01*
G03X491802Y1199309I200J0D01*
G01X491803Y1199308D01*
G02X492173Y1198321I-1131J-987D01*
G02X489169I-1502J0D01*
G02X489539Y1199308I1501J0D01*
G01Y1199309D01*
X489540D01*
G03X489588Y1199439I-152J130D01*
G01Y1199703D01*
G03X489540Y1199833I-200J0D01*
G01X489539Y1199834D01*
G02X489169Y1200821I1131J987D01*
G37*
G36*
G01X494634D02*
G02X497638I1502J0D01*
G02X497268Y1199834I-1501J0D01*
G01Y1199833D01*
X497267D01*
G03X497219Y1199703I152J-130D01*
G01Y1199439D01*
G03X497267Y1199309I200J0D01*
G01X497268Y1199308D01*
G02X497638Y1198321I-1131J-987D01*
G02X494634I-1502J0D01*
G02X495004Y1199308I1501J0D01*
G01Y1199309D01*
X495005D01*
G03X495053Y1199439I-152J130D01*
G01Y1199703D01*
G03X495005Y1199833I-200J0D01*
G01X495004Y1199834D01*
G02X494634Y1200821I1131J987D01*
G37*
G36*
G01X502634D02*
G02X505638I1502J0D01*
G02X505268Y1199834I-1501J0D01*
G01Y1199833D01*
X505267D01*
G03X505219Y1199703I152J-130D01*
G01Y1199439D01*
G03X505267Y1199309I200J0D01*
G01X505268Y1199308D01*
G02X505638Y1198321I-1131J-987D01*
G02X502634I-1502J0D01*
G02X503004Y1199308I1501J0D01*
G01Y1199309D01*
X503005D01*
G03X503053Y1199439I-152J130D01*
G01Y1199703D01*
G03X503005Y1199833I-200J0D01*
G01X503004Y1199834D01*
G02X502634Y1200821I1131J987D01*
G37*
G36*
G01X521564D02*
G02X524568I1502J0D01*
G02X524198Y1199834I-1501J0D01*
G01Y1199833D01*
X524197D01*
G03X524149Y1199703I152J-130D01*
G01Y1199439D01*
G03X524197Y1199309I200J0D01*
G01X524198Y1199308D01*
G02X524568Y1198321I-1131J-987D01*
G02X521564I-1502J0D01*
G02X521934Y1199308I1501J0D01*
G01Y1199309D01*
X521935D01*
G03X521983Y1199439I-152J130D01*
G01Y1199703D01*
G03X521935Y1199833I-200J0D01*
G01X521934Y1199834D01*
G02X521564Y1200821I1131J987D01*
G37*
G36*
G01X566502Y1200601D02*
G02X568004Y1202103I0J1502D01*
G02X567995Y1201941I-1502J2D01*
G01X567990Y1201897D01*
X568019Y1201813D01*
X568295Y1201527D01*
X568378Y1201496D01*
X568422Y1201499D01*
G02X568531Y1201503I110J-1498D01*
G01X568532D01*
G02X567030Y1200001I0J-1502D01*
G02X567039Y1200163I1502J-2D01*
G01X567044Y1200207D01*
X567015Y1200291D01*
X566739Y1200577D01*
X566656Y1200608D01*
X566612Y1200605D01*
G02X566503Y1200601I-110J1498D01*
G01X566502D01*
G37*
G36*
G01X478019Y1211905D02*
G02X481023I1502J0D01*
G02X480653Y1210918I-1501J0D01*
G01Y1210917D01*
X480652D01*
G03X480604Y1210787I152J-130D01*
G01Y1210523D01*
G03X480652Y1210393I200J0D01*
G01X480653Y1210392D01*
G02Y1208418I-1131J-987D01*
G01Y1208417D01*
X480652D01*
G03X480604Y1208287I152J-130D01*
G01Y1208023D01*
G03X480652Y1207893I200J0D01*
G01X480653Y1207892D01*
G02Y1205918I-1131J-987D01*
G01Y1205917D01*
X480652D01*
G03X480604Y1205787I152J-130D01*
G01Y1205523D01*
G03X480652Y1205393I200J0D01*
G01X480653Y1205392D01*
G02X481023Y1204405I-1131J-987D01*
G02X478019I-1502J0D01*
G02X478389Y1205392I1501J0D01*
G01Y1205393D01*
X478390D01*
G03X478438Y1205523I-152J130D01*
G01Y1205787D01*
G03X478390Y1205917I-200J0D01*
G01X478389Y1205918D01*
G02Y1207892I1131J987D01*
G01Y1207893D01*
X478390D01*
G03X478438Y1208023I-152J130D01*
G01Y1208287D01*
G03X478390Y1208417I-200J0D01*
G01X478389Y1208418D01*
G02Y1210392I1131J987D01*
G01Y1210393D01*
X478390D01*
G03X478438Y1210523I-152J130D01*
G01Y1210787D01*
G03X478390Y1210917I-200J0D01*
G01X478389Y1210918D01*
G02X478019Y1211905I1131J987D01*
G37*
G36*
G01X504949D02*
G02X507953I1502J0D01*
G02X507583Y1210918I-1501J0D01*
G01Y1210917D01*
X507582D01*
G03X507534Y1210787I152J-130D01*
G01Y1210523D01*
G03X507582Y1210393I200J0D01*
G01X507583Y1210392D01*
G02Y1208418I-1131J-987D01*
G01Y1208417D01*
X507582D01*
G03X507534Y1208287I152J-130D01*
G01Y1208023D01*
G03X507582Y1207893I200J0D01*
G01X507583Y1207892D01*
G02Y1205918I-1131J-987D01*
G01Y1205917D01*
X507582D01*
G03X507534Y1205787I152J-130D01*
G01Y1205523D01*
G03X507582Y1205393I200J0D01*
G01X507583Y1205392D01*
G02X507953Y1204405I-1131J-987D01*
G02X504949I-1502J0D01*
G02X505319Y1205392I1501J0D01*
G01Y1205393D01*
X505320D01*
G03X505368Y1205523I-152J130D01*
G01Y1205787D01*
G03X505320Y1205917I-200J0D01*
G01X505319Y1205918D01*
G02Y1207892I1131J987D01*
G01Y1207893D01*
X505320D01*
G03X505368Y1208023I-152J130D01*
G01Y1208287D01*
G03X505320Y1208417I-200J0D01*
G01X505319Y1208418D01*
G02Y1210392I1131J987D01*
G01Y1210393D01*
X505320D01*
G03X505368Y1210523I-152J130D01*
G01Y1210787D01*
G03X505320Y1210917I-200J0D01*
G01X505319Y1210918D01*
G02X504949Y1211905I1131J987D01*
G37*
G36*
G01X492319Y1212117D02*
G02X495323I1502J0D01*
G02X494953Y1211130I-1501J0D01*
G01Y1211129D01*
X494952D01*
G03X494904Y1210999I152J-130D01*
G01Y1210735D01*
G03X494952Y1210605I200J0D01*
G01X494953Y1210604D01*
G02Y1208630I-1131J-987D01*
G01Y1208629D01*
X494952D01*
G03X494904Y1208499I152J-130D01*
G01Y1208235D01*
G03X494952Y1208105I200J0D01*
G01X494953Y1208104D01*
G02Y1206130I-1131J-987D01*
G01Y1206129D01*
X494952D01*
G03X494904Y1205999I152J-130D01*
G01Y1205735D01*
G03X494952Y1205605I200J0D01*
G01X494953Y1205604D01*
G02X495323Y1204617I-1131J-987D01*
G02X492319I-1502J0D01*
G02X492689Y1205604I1501J0D01*
G01Y1205605D01*
X492690D01*
G03X492738Y1205735I-152J130D01*
G01Y1205999D01*
G03X492690Y1206129I-200J0D01*
G01X492689Y1206130D01*
G02Y1208104I1131J987D01*
G01Y1208105D01*
X492690D01*
G03X492738Y1208235I-152J130D01*
G01Y1208499D01*
G03X492690Y1208629I-200J0D01*
G01X492689Y1208630D01*
G02Y1210604I1131J987D01*
G01Y1210605D01*
X492690D01*
G03X492738Y1210735I-152J130D01*
G01Y1210999D01*
G03X492690Y1211129I-200J0D01*
G01X492689Y1211130D01*
G02X492319Y1212117I1131J987D01*
G37*
G36*
G01X519249D02*
G02X522253I1502J0D01*
G02X521883Y1211130I-1501J0D01*
G01Y1211129D01*
X521882D01*
G03X521834Y1210999I152J-130D01*
G01Y1210735D01*
G03X521882Y1210605I200J0D01*
G01X521883Y1210604D01*
G02Y1208630I-1131J-987D01*
G01Y1208629D01*
X521882D01*
G03X521834Y1208499I152J-130D01*
G01Y1208235D01*
G03X521882Y1208105I200J0D01*
G01X521883Y1208104D01*
G02Y1206130I-1131J-987D01*
G01Y1206129D01*
X521882D01*
G03X521834Y1205999I152J-130D01*
G01Y1205735D01*
G03X521882Y1205605I200J0D01*
G01X521883Y1205604D01*
G02X522253Y1204617I-1131J-987D01*
G02X519249I-1502J0D01*
G02X519619Y1205604I1501J0D01*
G01Y1205605D01*
X519620D01*
G03X519668Y1205735I-152J130D01*
G01Y1205999D01*
G03X519620Y1206129I-200J0D01*
G01X519619Y1206130D01*
G02Y1208104I1131J987D01*
G01Y1208105D01*
X519620D01*
G03X519668Y1208235I-152J130D01*
G01Y1208499D01*
G03X519620Y1208629I-200J0D01*
G01X519619Y1208630D01*
G02Y1210604I1131J987D01*
G01Y1210605D01*
X519620D01*
G03X519668Y1210735I-152J130D01*
G01Y1210999D01*
G03X519620Y1211129I-200J0D01*
G01X519619Y1211130D01*
G02X519249Y1212117I1131J987D01*
G37*
G36*
G01X502990Y1261006D02*
X503304D01*
G03X503462Y1261083I0J200D01*
G02X504647Y1261662I1185J-923D01*
G02X505713Y1261218I0J-1502D01*
G03X505855Y1261159I142J141D01*
G01X506139D01*
G03X506281Y1261218I0J200D01*
G02X507347Y1261662I1066J-1058D01*
G02X508849Y1260160I0J-1502D01*
G02X508270Y1258975I-1502J0D01*
G03X508193Y1258817I123J-158D01*
G01Y1258503D01*
G03X508270Y1258345I200J0D01*
G02X508849Y1257160I-923J-1185D01*
G02X507347Y1255658I-1502J0D01*
G02X506281Y1256102I0J1502D01*
G03X506139Y1256161I-142J-141D01*
G01X505855D01*
G03X505713Y1256102I0J-200D01*
G02X504647Y1255658I-1066J1058D01*
G02X503462Y1256237I0J1502D01*
G03X503304Y1256314I-158J-123D01*
G01X502990D01*
G03X502832Y1256237I0J-200D01*
G02X500462I-1185J923D01*
G03X500304Y1256314I-158J-123D01*
G01X499990D01*
G03X499832Y1256237I0J-200D01*
G02X497462I-1185J923D01*
G03X497304Y1256314I-158J-123D01*
G01X496990D01*
G03X496832Y1256237I0J-200D01*
G02X494462I-1185J923D01*
G03X494304Y1256314I-158J-123D01*
G01X493990D01*
G03X493832Y1256237I0J-200D01*
G02X491462I-1185J923D01*
G03X491304Y1256314I-158J-123D01*
G01X490990D01*
G03X490832Y1256237I0J-200D01*
G02X488462I-1185J923D01*
G03X488304Y1256314I-158J-123D01*
G01X487990D01*
G03X487832Y1256237I0J-200D01*
G02X485462I-1185J923D01*
G03X485304Y1256314I-158J-123D01*
G01X484990D01*
G03X484832Y1256237I0J-200D01*
G02X482462I-1185J923D01*
G03X482304Y1256314I-158J-123D01*
G01X481990D01*
G03X481832Y1256237I0J-200D01*
G02X479462I-1185J923D01*
G03X479304Y1256314I-158J-123D01*
G01X478990D01*
G03X478832Y1256237I0J-200D01*
G02X476462I-1185J923D01*
G03X476304Y1256314I-158J-123D01*
G01X475990D01*
G03X475832Y1256237I0J-200D01*
G02X473462I-1185J923D01*
G03X473304Y1256314I-158J-123D01*
G01X472990D01*
G03X472832Y1256237I0J-200D01*
G02X471647Y1255658I-1185J923D01*
G02X470145Y1257160I0J1502D01*
G02X470724Y1258345I1502J0D01*
G03X470801Y1258503I-123J158D01*
G01Y1258817D01*
G03X470724Y1258975I-200J0D01*
G02X470145Y1260160I923J1185D01*
G02X471647Y1261662I1502J0D01*
G02X472832Y1261083I0J-1502D01*
G03X472990Y1261006I158J123D01*
G01X473304D01*
G03X473462Y1261083I0J200D01*
G02X475832I1185J-923D01*
G03X475990Y1261006I158J123D01*
G01X476304D01*
G03X476462Y1261083I0J200D01*
G02X478832I1185J-923D01*
G03X478990Y1261006I158J123D01*
G01X479304D01*
G03X479462Y1261083I0J200D01*
G02X481832I1185J-923D01*
G03X481990Y1261006I158J123D01*
G01X482304D01*
G03X482462Y1261083I0J200D01*
G02X484832I1185J-923D01*
G03X484990Y1261006I158J123D01*
G01X485304D01*
G03X485462Y1261083I0J200D01*
G02X487832I1185J-923D01*
G03X487990Y1261006I158J123D01*
G01X488304D01*
G03X488462Y1261083I0J200D01*
G02X490832I1185J-923D01*
G03X490990Y1261006I158J123D01*
G01X491304D01*
G03X491462Y1261083I0J200D01*
G02X493832I1185J-923D01*
G03X493990Y1261006I158J123D01*
G01X494304D01*
G03X494462Y1261083I0J200D01*
G02X496832I1185J-923D01*
G03X496990Y1261006I158J123D01*
G01X497304D01*
G03X497462Y1261083I0J200D01*
G02X499832I1185J-923D01*
G03X499990Y1261006I158J123D01*
G01X500304D01*
G03X500462Y1261083I0J200D01*
G02X502832I1185J-923D01*
G03X502990Y1261006I158J123D01*
G37*
G36*
G01X628568Y1182480D02*
G02X628346Y1182459I-224J1181D01*
G02X629548Y1183661I0J1202D01*
G02X629527Y1183439I-1202J2D01*
G03X629994Y1182972I393J-74D01*
G02X630216Y1182993I224J-1181D01*
G02X629014Y1181791I0J-1202D01*
G02X629035Y1182013I1202J-2D01*
G03X628568Y1182480I-393J74D01*
G37*
G36*
G01X635827Y1193679D02*
G02X637029Y1194881I0J1202D01*
G02X637008Y1194659I-1202J2D01*
G01X636999Y1194610D01*
X637028Y1194517D01*
X637333Y1194212D01*
X637426Y1194183D01*
X637475Y1194192D01*
G02X637697Y1194213I224J-1181D01*
G02Y1191809I0J-1202D01*
G02X637475Y1191830I2J1202D01*
G01X637426Y1191839D01*
X637333Y1191810D01*
X637028Y1191505D01*
X636999Y1191412D01*
X637008Y1191363D01*
G02X637029Y1191141I-1181J-224D01*
G02X637008Y1190919I-1202J2D01*
G01X636999Y1190870D01*
X637028Y1190777D01*
X637333Y1190472D01*
X637426Y1190443D01*
X637475Y1190452D01*
G02X637697Y1190473I224J-1181D01*
G02Y1188069I0J-1202D01*
G02X637475Y1188090I2J1202D01*
G01X637426Y1188099D01*
X637333Y1188070D01*
X637028Y1187765D01*
X636999Y1187672D01*
X637008Y1187623D01*
G02X637029Y1187401I-1181J-224D01*
G02X637008Y1187179I-1202J2D01*
G01X636999Y1187130D01*
X637028Y1187037D01*
X637333Y1186732D01*
X637426Y1186703D01*
X637475Y1186712D01*
G02X637697Y1186733I224J-1181D01*
G02X636495Y1185531I0J-1202D01*
G02X636516Y1185753I1202J-2D01*
G01X636525Y1185802D01*
X636496Y1185895D01*
X636191Y1186200D01*
X636098Y1186229D01*
X636049Y1186220D01*
G02X635827Y1186199I-224J1181D01*
G02X635605Y1186220I2J1202D01*
G01X635556Y1186229D01*
X635463Y1186200D01*
X635158Y1185895D01*
X635129Y1185802D01*
X635138Y1185753D01*
G02X635159Y1185531I-1181J-224D01*
G02X632755I-1202J0D01*
G02X632776Y1185752I1202J-3D01*
G01Y1185754D01*
G03X632721Y1185931I-197J36D01*
G01X632451Y1186200D01*
X632358Y1186229D01*
X632309Y1186220D01*
G02X632086Y1186199I-224J1181D01*
G02X633288Y1187401I0J1202D01*
G02X633267Y1187180I-1202J3D01*
G01Y1187178D01*
G03X633322Y1187001I197J-36D01*
G01X633592Y1186732D01*
X633685Y1186703D01*
X633734Y1186712D01*
G02X633957Y1186733I224J-1181D01*
G02X634179Y1186712I-2J-1202D01*
G01X634228Y1186703D01*
X634321Y1186732D01*
X634626Y1187037D01*
X634655Y1187130D01*
X634646Y1187179D01*
G02X634625Y1187401I1181J224D01*
G02X635827Y1188603I1202J0D01*
G02X636049Y1188582I-2J-1202D01*
G01X636098Y1188573D01*
X636191Y1188602D01*
X636496Y1188907D01*
X636525Y1189000D01*
X636516Y1189049D01*
G02X636495Y1189271I1181J224D01*
G02X636516Y1189493I1202J-2D01*
G01X636525Y1189542D01*
X636496Y1189635D01*
X636191Y1189940D01*
X636098Y1189969D01*
X636049Y1189960D01*
G02X635827Y1189939I-224J1181D01*
G02Y1192343I0J1202D01*
G02X636049Y1192322I-2J-1202D01*
G01X636098Y1192313D01*
X636191Y1192342D01*
X636496Y1192647D01*
X636525Y1192740D01*
X636516Y1192789D01*
G02X636495Y1193011I1181J224D01*
G02X636516Y1193233I1202J-2D01*
G01X636525Y1193282D01*
X636496Y1193375D01*
X636191Y1193680D01*
X636098Y1193709D01*
X636049Y1193700D01*
G02X635827Y1193679I-224J1181D01*
G37*
G36*
G01X514363Y1285868D02*
G02Y1288872I0J1502D01*
G02X515597Y1288226I0J-1502D01*
G01X515624Y1288188D01*
X515704Y1288143D01*
X516068Y1288125D01*
G03X516230Y1288195I10J200D01*
G02X517374Y1288724I1144J-972D01*
G02X518638Y1288033I0J-1502D01*
G01X518665Y1287991D01*
X518753Y1287942D01*
X519188Y1287937D01*
X519277Y1287983D01*
X519305Y1288025D01*
G02X520548Y1288683I1243J-845D01*
G02Y1285679I0J-1502D01*
G02X519284Y1286370I0J1502D01*
G01X519257Y1286412D01*
X519169Y1286461D01*
X518734Y1286466D01*
X518645Y1286420D01*
X518617Y1286378D01*
G02X517374Y1285720I-1243J845D01*
G02X516140Y1286366I0J1502D01*
G01X516113Y1286404D01*
X516033Y1286449D01*
X515669Y1286467D01*
G03X515507Y1286397I-10J-200D01*
G02X514363Y1285868I-1144J972D01*
G37*
G36*
G01X525133Y460234D02*
Y460570D01*
X525108Y460637D01*
X525084Y460665D01*
G02X524714Y461652I1131J987D01*
G02X526216Y463154I1502J0D01*
G02X527203Y462784I0J-1501D01*
G01X527231Y462760D01*
X527298Y462735D01*
X527634D01*
X527701Y462760D01*
X527729Y462784D01*
G02X528716Y463154I987J-1131D01*
G02X530218Y461652I0J-1502D01*
G02X529848Y460665I-1501J0D01*
G01X529824Y460637D01*
X529799Y460570D01*
Y460234D01*
X529824Y460167D01*
X529848Y460139D01*
G02Y458165I-1131J-987D01*
G01X529824Y458137D01*
X529799Y458070D01*
Y457734D01*
X529824Y457667D01*
X529848Y457639D01*
G02X530218Y456652I-1131J-987D01*
G02X528716Y455150I-1502J0D01*
G02X527729Y455520I0J1501D01*
G01X527701Y455544D01*
X527634Y455569D01*
X527298D01*
X527231Y455544D01*
X527203Y455520D01*
G02X526216Y455150I-987J1131D01*
G02X524714Y456652I0J1502D01*
G02X525084Y457639I1501J0D01*
G01X525108Y457667D01*
X525133Y457734D01*
Y458070D01*
X525108Y458137D01*
X525084Y458165D01*
G02Y460139I1131J987D01*
G01X525108Y460167D01*
X525133Y460234D01*
G37*
G36*
G01X511258Y477078D02*
Y477372D01*
G03X511193Y477519I-200J-1D01*
G02X510708Y478625I1017J1105D01*
G02X513712I1502J0D01*
G02X513227Y477519I-1502J-1D01*
G03X513162Y477372I135J-148D01*
G01Y477078D01*
G03X513227Y476931I200J1D01*
G02X513712Y475825I-1017J-1105D01*
G02X510708I-1502J0D01*
G02X511193Y476931I1502J1D01*
G03X511258Y477078I-135J148D01*
G37*
G36*
G01X509407Y486221D02*
X509743D01*
X509810Y486246D01*
X509838Y486270D01*
G02X511812I987J-1131D01*
G01X511840Y486246D01*
X511907Y486221D01*
X512243D01*
X512310Y486246D01*
X512338Y486270D01*
G02X513325Y486640I987J-1131D01*
G02X514827Y485138I0J-1502D01*
G02X514560Y484283I-1502J0D01*
G01X514536Y484249D01*
X514520Y484168D01*
X514599Y483801D01*
X514647Y483734D01*
X514683Y483713D01*
G02X515412Y482425I-773J-1288D01*
G02X512408I-1502J0D01*
G02X512675Y483280I1502J0D01*
G01X512699Y483314D01*
X512715Y483395D01*
X512636Y483762D01*
X512588Y483829D01*
X512552Y483850D01*
G02X512338Y484006I774J1287D01*
G01X512310Y484030D01*
X512243Y484055D01*
X511907D01*
X511840Y484030D01*
X511812Y484006D01*
G02X509838I-987J1131D01*
G01X509810Y484030D01*
X509743Y484055D01*
X509407D01*
X509340Y484030D01*
X509312Y484006D01*
G02X508325Y483636I-987J1131D01*
G02X507204Y484139I0J1501D01*
G01X507175Y484171D01*
X507097Y484206D01*
X506711Y484205D01*
X506633Y484169D01*
X506604Y484137D01*
G02X505476Y483626I-1129J991D01*
G02Y486630I0J1502D01*
G02X506597Y486127I0J-1501D01*
G01X506626Y486095D01*
X506704Y486060D01*
X507090Y486061D01*
X507168Y486097D01*
X507197Y486129D01*
G02X508325Y486640I1129J-991D01*
G02X509312Y486270I0J-1501D01*
G01X509340Y486246D01*
X509407Y486221D01*
G37*
G36*
G01X518703Y492296D02*
Y492632D01*
X518678Y492699D01*
X518654Y492727D01*
G02X518284Y493714I1131J987D01*
G02X521288I1502J0D01*
G02X520918Y492727I-1501J0D01*
G01X520894Y492699D01*
X520869Y492632D01*
Y492296D01*
X520894Y492229D01*
X520918Y492201D01*
G02X521288Y491214I-1131J-987D01*
G02X518284I-1502J0D01*
G02X518654Y492201I1501J0D01*
G01X518678Y492229D01*
X518703Y492296D01*
G37*
G36*
G01X522406Y494069D02*
Y494405D01*
X522381Y494472D01*
X522357Y494500D01*
G02X521987Y495487I1131J987D01*
G02X524991I1502J0D01*
G02X524621Y494500I-1501J0D01*
G01X524597Y494472D01*
X524572Y494405D01*
Y494069D01*
X524597Y494002D01*
X524621Y493974D01*
G02X524991Y492987I-1131J-987D01*
G02X521987I-1502J0D01*
G02X522357Y493974I1501J0D01*
G01X522381Y494002D01*
X522406Y494069D01*
G37*
G36*
G01X534036Y497215D02*
Y497551D01*
X534011Y497618D01*
X533987Y497646D01*
G02X533617Y498633I1131J987D01*
G02X536621I1502J0D01*
G02X536251Y497646I-1501J0D01*
G01X536227Y497618D01*
X536202Y497551D01*
Y497215D01*
X536227Y497148D01*
X536251Y497120D01*
G02Y495146I-1131J-987D01*
G01X536227Y495118D01*
X536202Y495051D01*
Y494715D01*
X536227Y494648D01*
X536251Y494620D01*
G02Y492646I-1131J-987D01*
G01X536227Y492618D01*
X536202Y492551D01*
Y492215D01*
X536227Y492148D01*
X536251Y492120D01*
G02X536621Y491133I-1131J-987D01*
G02X533617I-1502J0D01*
G02X533987Y492120I1501J0D01*
G01X534011Y492148D01*
X534036Y492215D01*
Y492551D01*
X534011Y492618D01*
X533987Y492646D01*
G02Y494620I1131J987D01*
G01X534011Y494648D01*
X534036Y494715D01*
Y495051D01*
X534011Y495118D01*
X533987Y495146D01*
G02Y497120I1131J987D01*
G01X534011Y497148D01*
X534036Y497215D01*
G37*
G36*
G01X497969Y505908D02*
X498305D01*
X498372Y505933D01*
X498400Y505957D01*
G02X500374I987J-1131D01*
G01X500402Y505933D01*
X500469Y505908D01*
X500805D01*
X500872Y505933D01*
X500900Y505957D01*
G02X501887Y506327I987J-1131D01*
G02Y503323I0J-1502D01*
G02X500900Y503693I0J1501D01*
G01X500872Y503717D01*
X500805Y503742D01*
X500469D01*
X500402Y503717D01*
X500374Y503693D01*
G02X498400I-987J1131D01*
G01X498372Y503717D01*
X498305Y503742D01*
X497969D01*
X497902Y503717D01*
X497874Y503693D01*
G02X496887Y503323I-987J1131D01*
G02Y506327I0J1502D01*
G02X497874Y505957I0J-1501D01*
G01X497902Y505933D01*
X497969Y505908D01*
G37*
G36*
G01X497910Y518484D02*
X498246D01*
X498313Y518509D01*
X498341Y518533D01*
G02X500315I987J-1131D01*
G01X500343Y518509D01*
X500410Y518484D01*
X500746D01*
X500813Y518509D01*
X500841Y518533D01*
G02X501828Y518903I987J-1131D01*
G02Y515899I0J-1502D01*
G02X500841Y516269I0J1501D01*
G01X500813Y516293D01*
X500746Y516318D01*
X500410D01*
X500343Y516293D01*
X500315Y516269D01*
G02X498341I-987J1131D01*
G01X498313Y516293D01*
X498246Y516318D01*
X497910D01*
X497843Y516293D01*
X497815Y516269D01*
G02X496828Y515899I-987J1131D01*
G02Y518903I0J1502D01*
G02X497815Y518533I0J-1501D01*
G01X497843Y518509D01*
X497910Y518484D01*
G37*
G36*
G01X501427Y523822D02*
Y524116D01*
G03X501362Y524263I-200J-1D01*
G02X500877Y525369I1017J1105D01*
G02X503881I1502J0D01*
G02X503396Y524263I-1502J-1D01*
G03X503331Y524116I135J-148D01*
G01Y523822D01*
G03X503396Y523675I200J1D01*
G02X503881Y522569I-1017J-1105D01*
G02X500877I-1502J0D01*
G02X501362Y523675I1502J1D01*
G03X501427Y523822I-135J148D01*
G37*
G36*
G01X508872Y539040D02*
Y539376D01*
X508847Y539443D01*
X508823Y539471D01*
G02X508453Y540458I1131J987D01*
G02X511457I1502J0D01*
G02X511087Y539471I-1501J0D01*
G01X511063Y539443D01*
X511038Y539376D01*
Y539040D01*
X511063Y538973D01*
X511087Y538945D01*
G02X511457Y537958I-1131J-987D01*
G02X508453I-1502J0D01*
G02X508823Y538945I1501J0D01*
G01X508847Y538973D01*
X508872Y539040D01*
G37*
G36*
G01X512575Y540813D02*
Y541149D01*
X512550Y541216D01*
X512526Y541244D01*
G02X512156Y542231I1131J987D01*
G02X515160I1502J0D01*
G02X514790Y541244I-1501J0D01*
G01X514766Y541216D01*
X514741Y541149D01*
Y540813D01*
X514766Y540746D01*
X514790Y540718D01*
G02X515160Y539731I-1131J-987D01*
G02X512156I-1502J0D01*
G02X512526Y540718I1501J0D01*
G01X512550Y540746D01*
X512575Y540813D01*
G37*
G36*
G01X502476Y554242D02*
X502182D01*
G03X502035Y554177I1J-200D01*
G02X500929Y553692I-1105J1017D01*
G02Y556696I0J1502D01*
G02X502035Y556211I1J-1502D01*
G03X502182Y556146I148J135D01*
G01X502476D01*
G03X502623Y556211I-1J200D01*
G02X503729Y556696I1105J-1017D01*
G02Y553692I0J-1502D01*
G02X502623Y554177I-1J1502D01*
G03X502476Y554242I-148J-135D01*
G37*
G36*
G01Y562242D02*
X502182D01*
G03X502035Y562177I1J-200D01*
G02X500929Y561692I-1105J1017D01*
G02Y564696I0J1502D01*
G02X502035Y564211I1J-1502D01*
G03X502182Y564146I148J135D01*
G01X502476D01*
G03X502623Y564211I-1J200D01*
G02X503729Y564696I1105J-1017D01*
G02Y561692I0J-1502D01*
G02X502623Y562177I-1J1502D01*
G03X502476Y562242I-148J-135D01*
G37*
G36*
G01Y570242D02*
X502182D01*
G03X502035Y570177I1J-200D01*
G02X500929Y569692I-1105J1017D01*
G02Y572696I0J1502D01*
G02X502035Y572211I1J-1502D01*
G03X502182Y572146I148J135D01*
G01X502476D01*
G03X502623Y572211I-1J200D01*
G02X503729Y572696I1105J-1017D01*
G02Y569692I0J-1502D01*
G02X502623Y570177I-1J1502D01*
G03X502476Y570242I-148J-135D01*
G37*
G36*
G01X503739Y582174D02*
X504033D01*
G03X504180Y582239I-1J200D01*
G02X505286Y582724I1105J-1017D01*
G02X506392Y582239I1J-1502D01*
G03X506539Y582174I148J135D01*
G01X506833D01*
G03X506980Y582239I-1J200D01*
G02X508086Y582724I1105J-1017D01*
G02Y579720I0J-1502D01*
G02X506980Y580205I-1J1502D01*
G03X506833Y580270I-148J-135D01*
G01X506539D01*
G03X506392Y580205I1J-200D01*
G02X505286Y579720I-1105J1017D01*
G02X504180Y580205I-1J1502D01*
G03X504033Y580270I-148J-135D01*
G01X503739D01*
G03X503592Y580205I1J-200D01*
G02X502486Y579720I-1105J1017D01*
G02Y582724I0J1502D01*
G02X503592Y582239I1J-1502D01*
G03X503739Y582174I148J135D01*
G37*
G36*
G01Y592167D02*
X504033D01*
G03X504180Y592232I-1J200D01*
G02X505286Y592717I1105J-1017D01*
G02X506392Y592232I1J-1502D01*
G03X506539Y592167I148J135D01*
G01X506833D01*
G03X506980Y592232I-1J200D01*
G02X508086Y592717I1105J-1017D01*
G02Y589713I0J-1502D01*
G02X506980Y590198I-1J1502D01*
G03X506833Y590263I-148J-135D01*
G01X506539D01*
G03X506392Y590198I1J-200D01*
G02X505286Y589713I-1105J1017D01*
G02X504180Y590198I-1J1502D01*
G03X504033Y590263I-148J-135D01*
G01X503739D01*
G03X503592Y590198I1J-200D01*
G02X502486Y589713I-1105J1017D01*
G02Y592717I0J1502D01*
G02X503592Y592232I1J-1502D01*
G03X503739Y592167I148J135D01*
G37*
G36*
G01X506711Y611514D02*
X507005D01*
G03X507152Y611579I-1J200D01*
G02X508258Y612064I1105J-1017D01*
G02X509364Y611579I1J-1502D01*
G03X509511Y611514I148J135D01*
G01X509805D01*
G03X509952Y611579I-1J200D01*
G02X511058Y612064I1105J-1017D01*
G02X512560Y610562I0J-1502D01*
G02X512075Y609456I-1502J-1D01*
G03X512010Y609309I135J-148D01*
G01Y609015D01*
G03X512075Y608868I200J1D01*
G02X512560Y607762I-1017J-1105D01*
G02X511058Y606260I-1502J0D01*
G02X509952Y606745I-1J1502D01*
G03X509805Y606810I-148J-135D01*
G01X509511D01*
G03X509364Y606745I1J-200D01*
G02X508258Y606260I-1105J1017D01*
G02X507152Y606745I-1J1502D01*
G03X507005Y606810I-148J-135D01*
G01X506711D01*
G03X506564Y606745I1J-200D01*
G02X505458Y606260I-1105J1017D01*
G02X504352Y606745I-1J1502D01*
G03X504205Y606810I-148J-135D01*
G01X503911D01*
G03X503764Y606745I1J-200D01*
G02X502658Y606260I-1105J1017D01*
G02X501156Y607762I0J1502D01*
G02X501641Y608868I1502J1D01*
G03X501706Y609015I-135J148D01*
G01Y609309D01*
G03X501641Y609456I-200J-1D01*
G02X501156Y610562I1017J1105D01*
G02X502658Y612064I1502J0D01*
G02X503764Y611579I1J-1502D01*
G03X503911Y611514I148J135D01*
G01X504205D01*
G03X504352Y611579I-1J200D01*
G02X505458Y612064I1105J-1017D01*
G02X506564Y611579I1J-1502D01*
G03X506711Y611514I148J135D01*
G37*
G36*
G01X525804Y617966D02*
Y618260D01*
G03X525739Y618407I-200J-1D01*
G02X525254Y619513I1017J1105D01*
G02X528258I1502J0D01*
G02X527773Y618407I-1502J-1D01*
G03X527708Y618260I135J-148D01*
G01Y617966D01*
G03X527773Y617819I200J1D01*
G02X528258Y616713I-1017J-1105D01*
G02X527773Y615607I-1502J-1D01*
G03X527708Y615460I135J-148D01*
G01Y615166D01*
G03X527773Y615019I200J1D01*
G02X528258Y613913I-1017J-1105D01*
G02X525254I-1502J0D01*
G02X525739Y615019I1502J1D01*
G03X525804Y615166I-135J148D01*
G01Y615460D01*
G03X525739Y615607I-200J-1D01*
G02X525254Y616713I1017J1105D01*
G02X525739Y617819I1502J1D01*
G03X525804Y617966I-135J148D01*
G37*
G36*
G01X537874Y618211D02*
Y618505D01*
G03X537809Y618652I-200J-1D01*
G02X537324Y619758I1017J1105D01*
G02X540328I1502J0D01*
G02X539843Y618652I-1502J-1D01*
G03X539778Y618505I135J-148D01*
G01Y618211D01*
G03X539843Y618064I200J1D01*
G02X540328Y616958I-1017J-1105D01*
G02X539843Y615852I-1502J-1D01*
G03X539778Y615705I135J-148D01*
G01Y615411D01*
G03X539843Y615264I200J1D01*
G02X540328Y614158I-1017J-1105D01*
G02X537324I-1502J0D01*
G02X537809Y615264I1502J1D01*
G03X537874Y615411I-135J148D01*
G01Y615705D01*
G03X537809Y615852I-200J-1D01*
G02X537324Y616958I1017J1105D01*
G02X537809Y618064I1502J1D01*
G03X537874Y618211I-135J148D01*
G37*
G36*
G01X517988Y619106D02*
Y619400D01*
G03X517923Y619547I-200J-1D01*
G02X517438Y620653I1017J1105D01*
G02X520442I1502J0D01*
G02X519957Y619547I-1502J-1D01*
G03X519892Y619400I135J-148D01*
G01Y619106D01*
G03X519957Y618959I200J1D01*
G02X520442Y617853I-1017J-1105D01*
G02X517438I-1502J0D01*
G02X517923Y618959I1502J1D01*
G03X517988Y619106I-135J148D01*
G37*
G36*
G01X511957Y461350D02*
X511937Y461395D01*
G02X511808Y462004I1373J609D01*
G02X514812I1502J0D01*
G02X513453Y460509I-1502J0D01*
G01X513405Y460504D01*
X513324Y460452D01*
X513112Y460089D01*
X513106Y459993D01*
X513126Y459948D01*
G02X513255Y459339I-1373J-609D01*
G02X512885Y458352I-1501J0D01*
G01X512861Y458324D01*
X512836Y458257D01*
Y457921D01*
X512861Y457854D01*
X512885Y457826D01*
G02Y455852I-1131J-987D01*
G01X512861Y455824D01*
X512836Y455757D01*
Y455421D01*
X512861Y455354D01*
X512885Y455326D01*
G02X513255Y454339I-1131J-987D01*
G02X511753Y452837I-1502J0D01*
G02X510766Y453207I0J1501D01*
G01X510738Y453231D01*
X510671Y453256D01*
X510335D01*
X510268Y453231D01*
X510240Y453207D01*
G02X509253Y452837I-987J1131D01*
G02X507751Y454339I0J1502D01*
G02X508121Y455326I1501J0D01*
G01X508145Y455354D01*
X508170Y455421D01*
Y455757D01*
X508145Y455824D01*
X508121Y455852D01*
G02Y457826I1131J987D01*
G01X508145Y457854D01*
X508170Y457921D01*
Y458257D01*
X508145Y458324D01*
X508121Y458352D01*
G02X507751Y459339I1131J987D01*
G02X509253Y460841I1502J0D01*
G02X510240Y460471I0J-1501D01*
G01X510268Y460447D01*
X510335Y460422D01*
X510671D01*
X510738Y460447D01*
X510766Y460471D01*
G02X511610Y460834I987J-1132D01*
G01X511658Y460839D01*
X511739Y460891D01*
X511951Y461254D01*
X511957Y461350D01*
G37*
G36*
G01X529500Y499103D02*
X529794D01*
G03X529941Y499168I-1J200D01*
G02X531047Y499653I1105J-1017D01*
G02X532549Y498151I0J-1502D01*
G02X531970Y496966I-1502J0D01*
G03X531893Y496809I123J-158D01*
G01Y496493D01*
G03X531970Y496336I200J1D01*
G02X532549Y495151I-923J-1185D01*
G02X531047Y493649I-1502J0D01*
G02X530060Y494019I0J1501D01*
G01X530032Y494043D01*
X529965Y494068D01*
X529629D01*
X529562Y494043D01*
X529534Y494019D01*
G02X528547Y493649I-987J1131D01*
G02X527045Y495151I0J1502D01*
G02X527517Y496244I1502J0D01*
G01X527552Y496277D01*
X527584Y496363D01*
X527543Y496773D01*
X527494Y496850D01*
X527454Y496875D01*
G02X526745Y498151I794J1276D01*
G02X528247Y499653I1502J0D01*
G02X529353Y499168I1J-1502D01*
G03X529500Y499103I148J135D01*
G37*
G36*
G01X496658Y531062D02*
X496629Y531025D01*
G02X495444Y530446I-1185J923D01*
G02Y533450I0J1502D01*
G02X496668Y532819I0J-1503D01*
G01X496695Y532780D01*
X496779Y532736D01*
X497194Y532727D01*
X497280Y532768D01*
X497309Y532805D01*
G02X498494Y533384I1185J-923D01*
G02X499481Y533014I0J-1501D01*
G01X499509Y532990D01*
X499576Y532965D01*
X499912D01*
X499979Y532990D01*
X500007Y533014D01*
G02X501981I987J-1131D01*
G01X502009Y532990D01*
X502076Y532965D01*
X502412D01*
X502479Y532990D01*
X502507Y533014D01*
G02X503494Y533384I987J-1131D01*
G02X504996Y531882I0J-1502D01*
G02X504729Y531027I-1502J0D01*
G01X504705Y530993D01*
X504689Y530912D01*
X504768Y530545D01*
X504816Y530478D01*
X504852Y530457D01*
G02X505581Y529169I-773J-1288D01*
G02X502577I-1502J0D01*
G02X502844Y530024I1502J0D01*
G01X502868Y530058D01*
X502884Y530139D01*
X502805Y530506D01*
X502757Y530573D01*
X502721Y530594D01*
G02X502507Y530750I774J1287D01*
G01X502479Y530774D01*
X502412Y530799D01*
X502076D01*
X502009Y530774D01*
X501981Y530750D01*
G02X500007I-987J1131D01*
G01X499979Y530774D01*
X499912Y530799D01*
X499576D01*
X499509Y530774D01*
X499481Y530750D01*
G02X498494Y530380I-987J1131D01*
G02X497270Y531011I0J1503D01*
G01X497243Y531050D01*
X497159Y531094D01*
X496744Y531103D01*
X496658Y531062D01*
G37*
G36*
G01X519669Y545847D02*
X519963D01*
G03X520110Y545912I-1J200D01*
G02X521216Y546397I1105J-1017D01*
G02X522718Y544895I0J-1502D01*
G02X522139Y543710I-1502J0D01*
G03X522062Y543553I123J-158D01*
G01Y543237D01*
G03X522139Y543080I200J1D01*
G02X522718Y541895I-923J-1185D01*
G02X521216Y540393I-1502J0D01*
G02X520229Y540763I0J1501D01*
G01X520201Y540787D01*
X520134Y540812D01*
X519798D01*
X519731Y540787D01*
X519703Y540763D01*
G02X518716Y540393I-987J1131D01*
G02X517214Y541895I0J1502D01*
G02X517686Y542988I1502J0D01*
G01X517721Y543021D01*
X517753Y543107D01*
X517712Y543517D01*
X517663Y543594D01*
X517623Y543619D01*
G02X516914Y544895I794J1276D01*
G02X518416Y546397I1502J0D01*
G02X519522Y545912I1J-1502D01*
G03X519669Y545847I148J135D01*
G37*
G36*
G01X532070Y549427D02*
X532406D01*
X532473Y549452D01*
X532501Y549476D01*
G02X533488Y549846I987J-1131D01*
G02Y546842I0J-1502D01*
G02X532501Y547212I0J1501D01*
G01X532473Y547236D01*
X532406Y547261D01*
X532070D01*
X532003Y547236D01*
X531975Y547212D01*
G02X530001I-987J1131D01*
G01X529973Y547236D01*
X529906Y547261D01*
X529570D01*
X529503Y547236D01*
X529475Y547212D01*
G02X527501I-987J1131D01*
G01X527473Y547236D01*
X527406Y547261D01*
X527070D01*
X527003Y547236D01*
X526975Y547212D01*
G02X526586Y546966I-988J1131D01*
G01X526542Y546947D01*
X526482Y546876D01*
X526386Y546470D01*
X526408Y546379D01*
X526439Y546342D01*
G02X526790Y545377I-1151J-965D01*
G02X526420Y544390I-1501J0D01*
G01X526396Y544362D01*
X526371Y544295D01*
Y543959D01*
X526396Y543892D01*
X526420Y543864D01*
G02Y541890I-1131J-987D01*
G01X526396Y541862D01*
X526371Y541795D01*
Y541459D01*
X526396Y541392D01*
X526420Y541364D01*
G02Y539390I-1131J-987D01*
G01X526396Y539362D01*
X526371Y539295D01*
Y538959D01*
X526396Y538892D01*
X526420Y538864D01*
G02X526790Y537877I-1131J-987D01*
G02X523786I-1502J0D01*
G02X524156Y538864I1501J0D01*
G01X524180Y538892D01*
X524205Y538959D01*
Y539295D01*
X524180Y539362D01*
X524156Y539390D01*
G02Y541364I1131J987D01*
G01X524180Y541392D01*
X524205Y541459D01*
Y541795D01*
X524180Y541862D01*
X524156Y541890D01*
G02Y543864I1131J987D01*
G01X524180Y543892D01*
X524205Y543959D01*
Y544295D01*
X524180Y544362D01*
X524156Y544390D01*
G02X523786Y545377I1131J987D01*
G02X524690Y546755I1502J0D01*
G01X524734Y546774D01*
X524794Y546845D01*
X524890Y547251D01*
X524868Y547342D01*
X524837Y547379D01*
G02X524486Y548344I1151J965D01*
G02X525988Y549846I1502J0D01*
G02X526975Y549476I0J-1501D01*
G01X527003Y549452D01*
X527070Y549427D01*
X527406D01*
X527473Y549452D01*
X527501Y549476D01*
G02X529475I987J-1131D01*
G01X529503Y549452D01*
X529570Y549427D01*
X529906D01*
X529973Y549452D01*
X530001Y549476D01*
G02X531975I987J-1131D01*
G01X532003Y549452D01*
X532070Y549427D01*
G37*
G36*
G01X534349Y565573D02*
G02X533717Y566797I869J1224D01*
G02X536721I1502J0D01*
G02X536089Y565573I-1501J0D01*
G03X536005Y565410I116J-163D01*
G01Y565084D01*
G03X536089Y564921I200J0D01*
G02X536721Y563697I-869J-1224D01*
G02X536315Y562670I-1502J0D01*
G01X536289Y562642D01*
X536261Y562573D01*
Y562221D01*
X536289Y562152D01*
X536315Y562124D01*
G02Y560070I-1096J-1027D01*
G01X536289Y560042D01*
X536261Y559973D01*
Y559621D01*
X536289Y559552D01*
X536315Y559524D01*
G02Y557470I-1096J-1027D01*
G01X536289Y557442D01*
X536261Y557373D01*
Y557021D01*
X536289Y556952D01*
X536315Y556924D01*
G02Y554870I-1096J-1027D01*
G01X536289Y554842D01*
X536261Y554773D01*
Y554421D01*
X536289Y554352D01*
X536315Y554324D01*
G02X536721Y553297I-1096J-1027D01*
G02X533717I-1502J0D01*
G02X534123Y554324I1502J0D01*
G01X534149Y554352D01*
X534177Y554421D01*
Y554773D01*
X534149Y554842D01*
X534123Y554870D01*
G02Y556924I1096J1027D01*
G01X534149Y556952D01*
X534177Y557021D01*
Y557373D01*
X534149Y557442D01*
X534123Y557470D01*
G02Y559524I1096J1027D01*
G01X534149Y559552D01*
X534177Y559621D01*
Y559973D01*
X534149Y560042D01*
X534123Y560070D01*
G02Y562124I1096J1027D01*
G01X534149Y562152D01*
X534177Y562221D01*
Y562573D01*
X534149Y562642D01*
X534123Y562670D01*
G02X533717Y563697I1096J1027D01*
G02X534349Y564921I1501J0D01*
G03X534433Y565084I-116J163D01*
G01Y565410D01*
G03X534349Y565573I-200J0D01*
G37*
G36*
G01X531312Y575476D02*
X531284Y575508D01*
G02X530924Y576484I1143J976D01*
G02X533928I1502J0D01*
G02X533286Y575253I-1501J0D01*
G01X533251Y575228D01*
X533207Y575156D01*
X533159Y574778D01*
X533183Y574697D01*
X533211Y574665D01*
G02X533571Y573689I-1143J-976D01*
G02X532850Y572406I-1502J0D01*
G01X532806Y572379D01*
X532755Y572291D01*
X532747Y571849D01*
X532794Y571759D01*
X532837Y571731D01*
G02X533511Y570478I-828J-1253D01*
G02X532009Y568976I-1502J0D01*
G02X530830Y569547I0J1503D01*
G01X530803Y569581D01*
X530731Y569620D01*
X530351Y569648D01*
X530274Y569621D01*
X530242Y569591D01*
G02X529214Y569184I-1028J1095D01*
G02X527712Y570686I0J1502D01*
G02X528213Y571806I1502J0D01*
G01X528242Y571832D01*
X528276Y571900D01*
X528304Y572253D01*
X528282Y572326D01*
X528257Y572356D01*
G02X527921Y573303I1167J947D01*
G02X529423Y574805I1502J0D01*
G02X530314Y574512I0J-1501D01*
G01X530346Y574489D01*
X530421Y574470D01*
X530779Y574522D01*
X530846Y574562D01*
X530870Y574594D01*
G02X531209Y574920I1198J-906D01*
G01X531244Y574945D01*
X531288Y575017D01*
X531336Y575395D01*
X531312Y575476D01*
G37*
G36*
G01X501010Y619590D02*
G02X500448Y620661I739J1071D01*
G02X503052I1302J0D01*
G02X502490Y619590I-1301J0D01*
G03Y618932I228J-329D01*
G02X503052Y617861I-739J-1071D01*
G02X500448I-1302J0D01*
G02X501010Y618932I1301J0D01*
G03Y619590I-228J329D01*
G37*
G36*
G01X504553D02*
G02X503991Y620661I739J1071D01*
G02X506595I1302J0D01*
G02X506033Y619590I-1301J0D01*
G03Y618932I228J-329D01*
G02X506595Y617861I-739J-1071D01*
G02X503991I-1302J0D01*
G02X504553Y618932I1301J0D01*
G03Y619590I-228J329D01*
G37*
G36*
G01X508096D02*
G02X507534Y620661I739J1071D01*
G02X510138I1302J0D01*
G02X509576Y619590I-1301J0D01*
G03Y618932I228J-329D01*
G02X510138Y617861I-739J-1071D01*
G02X507534I-1302J0D01*
G02X508096Y618932I1301J0D01*
G03Y619590I-228J329D01*
G37*
G36*
G01X511640D02*
G02X511078Y620661I739J1071D01*
G02X513682I1302J0D01*
G02X513120Y619590I-1301J0D01*
G03Y618932I228J-329D01*
G02X513682Y617861I-739J-1071D01*
G02X511078I-1302J0D01*
G02X511640Y618932I1301J0D01*
G03Y619590I-228J329D01*
G37*
G36*
G01X559659Y1008703D02*
X559365D01*
G03X559218Y1008638I1J-200D01*
G02X558112Y1008153I-1105J1017D01*
G02Y1011157I0J1502D01*
G02X559218Y1010672I1J-1502D01*
G03X559365Y1010607I148J135D01*
G01X559659D01*
G03X559806Y1010672I-1J200D01*
G02X560912Y1011157I1105J-1017D01*
G02Y1008153I0J-1502D01*
G02X559806Y1008638I-1J1502D01*
G03X559659Y1008703I-148J-135D01*
G37*
G36*
G01X592792Y1010637D02*
X592786Y1011046D01*
X592745Y1011127D01*
X592708Y1011156D01*
G02X592111Y1012354I905J1199D01*
G02X595115I1502J0D01*
G02X594554Y1011183I-1503J0D01*
G01X594518Y1011154D01*
X594479Y1011071D01*
X594485Y1010662D01*
X594526Y1010581D01*
X594563Y1010552D01*
G02X595160Y1009354I-905J-1199D01*
G02X592156I-1502J0D01*
G02X592717Y1010525I1503J0D01*
G01X592753Y1010554D01*
X592792Y1010637D01*
G37*
G36*
G01Y1023237D02*
X592786Y1023646D01*
X592745Y1023727D01*
X592708Y1023756D01*
G02X592111Y1024954I905J1199D01*
G02X595115I1502J0D01*
G02X594554Y1023783I-1503J0D01*
G01X594518Y1023754D01*
X594479Y1023671D01*
X594485Y1023262D01*
X594526Y1023181D01*
X594563Y1023152D01*
G02X595160Y1021954I-905J-1199D01*
G02X592156I-1502J0D01*
G02X592717Y1023125I1503J0D01*
G01X592753Y1023154D01*
X592792Y1023237D01*
G37*
G36*
G01X563322Y1031455D02*
X563731Y1031470D01*
X563812Y1031513D01*
X563839Y1031551D01*
G02X565057Y1032174I1218J-879D01*
G02X566242Y1031595I0J-1502D01*
G03X566399Y1031518I158J123D01*
G01X566715D01*
G03X566872Y1031595I-1J200D01*
G02X568057Y1032174I1185J-923D01*
G02Y1029170I0J-1502D01*
G02X566872Y1029749I0J1502D01*
G03X566715Y1029826I-158J-123D01*
G01X566399D01*
G03X566242Y1029749I1J-200D01*
G02X565057Y1029170I-1185J923D01*
G02X563906Y1029707I0J1502D01*
G01X563876Y1029743D01*
X563792Y1029780D01*
X563383Y1029765D01*
X563302Y1029722D01*
X563275Y1029684D01*
G02X562057Y1029061I-1218J879D01*
G02X560872Y1029640I0J1502D01*
G03X560715Y1029717I-158J-123D01*
G01X560399D01*
G03X560242Y1029640I1J-200D01*
G02X559057Y1029061I-1185J923D01*
G02Y1032065I0J1502D01*
G02X560242Y1031486I0J-1502D01*
G03X560399Y1031409I158J123D01*
G01X560715D01*
G03X560872Y1031486I-1J200D01*
G02X562057Y1032065I1185J-923D01*
G02X563208Y1031528I0J-1502D01*
G01X563238Y1031492D01*
X563322Y1031455D01*
G37*
G36*
G01X581146Y1103374D02*
X581140Y1103783D01*
X581099Y1103864D01*
X581062Y1103893D01*
G02X580465Y1105091I905J1199D01*
G02X583469I1502J0D01*
G02X582908Y1103920I-1503J0D01*
G01X582872Y1103891D01*
X582833Y1103808D01*
X582839Y1103399D01*
X582880Y1103318D01*
X582917Y1103289D01*
G02X583514Y1102091I-905J-1199D01*
G02X580510I-1502J0D01*
G02X581071Y1103262I1503J0D01*
G01X581107Y1103291D01*
X581146Y1103374D01*
G37*
G36*
G01Y1115974D02*
X581140Y1116383D01*
X581099Y1116464D01*
X581062Y1116493D01*
G02X580465Y1117691I905J1199D01*
G02X583469I1502J0D01*
G02X582908Y1116520I-1503J0D01*
G01X582872Y1116491D01*
X582833Y1116408D01*
X582839Y1115999D01*
X582880Y1115918D01*
X582917Y1115889D01*
G02X583514Y1114691I-905J-1199D01*
G02X580510I-1502J0D01*
G02X581071Y1115862I1503J0D01*
G01X581107Y1115891D01*
X581146Y1115974D01*
G37*
G36*
G01X626288Y1406992D02*
G02Y1409998I0J1503D01*
G01X629688D01*
G02Y1406992I0J-1503D01*
G01X626288D01*
G37*
G36*
G01Y1395080D02*
G02Y1398086I0J1503D01*
G01X629688D01*
G02Y1395080I0J-1503D01*
G01X626288D01*
G37*
G36*
G01X638528D02*
G02Y1398086I0J1503D01*
G01X641928D01*
G02Y1395080I0J-1503D01*
G01X638528D01*
G37*
G36*
G01Y1406992D02*
G02Y1409998I0J1503D01*
G01X641928D01*
G02Y1406992I0J-1503D01*
G01X638528D01*
G37*
G36*
G01X650768D02*
G02Y1409998I0J1503D01*
G01X654168D01*
G02Y1406992I0J-1503D01*
G01X650768D01*
G37*
G36*
G01Y1395080D02*
G02Y1398086I0J1503D01*
G01X654168D01*
G02Y1395080I0J-1503D01*
G01X650768D01*
G37*
G36*
G01X663008D02*
G02Y1398086I0J1503D01*
G01X666408D01*
G02Y1395080I0J-1503D01*
G01X663008D01*
G37*
G36*
G01Y1406992D02*
G02Y1409998I0J1503D01*
G01X666408D01*
G02Y1406992I0J-1503D01*
G01X663008D01*
G37*
G36*
G01X675248D02*
G02Y1409998I0J1503D01*
G01X678648D01*
G02Y1406992I0J-1503D01*
G01X675248D01*
G37*
G36*
G01Y1395080D02*
G02Y1398086I0J1503D01*
G01X678648D01*
G02Y1395080I0J-1503D01*
G01X675248D01*
G37*
G36*
G01X687488D02*
G02Y1398086I0J1503D01*
G01X690888D01*
G02Y1395080I0J-1503D01*
G01X687488D01*
G37*
G36*
G01Y1406992D02*
G02Y1409998I0J1503D01*
G01X690888D01*
G02Y1406992I0J-1503D01*
G01X687488D01*
G37*
G36*
G01X699728D02*
G02Y1409998I0J1503D01*
G01X703128D01*
G02Y1406992I0J-1503D01*
G01X699728D01*
G37*
G36*
G01Y1395080D02*
G02Y1398086I0J1503D01*
G01X703128D01*
G02Y1395080I0J-1503D01*
G01X699728D01*
G37*
G36*
G01X711968Y1406992D02*
G02Y1409998I0J1503D01*
G01X715368D01*
G02Y1406992I0J-1503D01*
G01X711968D01*
G37*
G36*
G01Y1395080D02*
G02Y1398086I0J1503D01*
G01X715368D01*
G02Y1395080I0J-1503D01*
G01X711968D01*
G37*
G36*
G01X724208Y1406898D02*
G02Y1409904I0J1503D01*
G01X727608D01*
G02Y1406898I0J-1503D01*
G01X724208D01*
G37*
G36*
G01Y1394986D02*
G02Y1397992I0J1503D01*
G01X727608D01*
G02Y1394986I0J-1503D01*
G01X724208D01*
G37*
G36*
G01X736448Y1406898D02*
G02Y1409904I0J1503D01*
G01X739848D01*
G02Y1406898I0J-1503D01*
G01X736448D01*
G37*
G36*
G01Y1394986D02*
G02Y1397992I0J1503D01*
G01X739848D01*
G02Y1394986I0J-1503D01*
G01X736448D01*
G37*
G36*
G01X760928Y1382794D02*
G02Y1385800I0J1503D01*
G01X764328D01*
G02Y1382794I0J-1503D01*
G01X760928D01*
G37*
G36*
G01Y1370882D02*
G02Y1373888I0J1503D01*
G01X764328D01*
G02Y1370882I0J-1503D01*
G01X760928D01*
G37*
G36*
G01X748688D02*
G02Y1373888I0J1503D01*
G01X752088D01*
G02Y1370882I0J-1503D01*
G01X748688D01*
G37*
G36*
G01Y1382794D02*
G02Y1385800I0J1503D01*
G01X752088D01*
G02Y1382794I0J-1503D01*
G01X748688D01*
G37*
G36*
G01X736448D02*
G02Y1385800I0J1503D01*
G01X739848D01*
G02Y1382794I0J-1503D01*
G01X736448D01*
G37*
G36*
G01Y1370882D02*
G02Y1373888I0J1503D01*
G01X739848D01*
G02Y1370882I0J-1503D01*
G01X736448D01*
G37*
G36*
G01X724208D02*
G02Y1373888I0J1503D01*
G01X727608D01*
G02Y1370882I0J-1503D01*
G01X724208D01*
G37*
G36*
G01Y1382794D02*
G02Y1385800I0J1503D01*
G01X727608D01*
G02Y1382794I0J-1503D01*
G01X724208D01*
G37*
G36*
G01X711968D02*
G02Y1385800I0J1503D01*
G01X715368D01*
G02Y1382794I0J-1503D01*
G01X711968D01*
G37*
G36*
G01Y1370882D02*
G02Y1373888I0J1503D01*
G01X715368D01*
G02Y1370882I0J-1503D01*
G01X711968D01*
G37*
G36*
G01X699728D02*
G02Y1373888I0J1503D01*
G01X703128D01*
G02Y1370882I0J-1503D01*
G01X699728D01*
G37*
G36*
G01Y1382794D02*
G02Y1385800I0J1503D01*
G01X703128D01*
G02Y1382794I0J-1503D01*
G01X699728D01*
G37*
G36*
G01X687488D02*
G02Y1385800I0J1503D01*
G01X690888D01*
G02Y1382794I0J-1503D01*
G01X687488D01*
G37*
G36*
G01Y1370882D02*
G02Y1373888I0J1503D01*
G01X690888D01*
G02Y1370882I0J-1503D01*
G01X687488D01*
G37*
G36*
G01X675248D02*
G02Y1373888I0J1503D01*
G01X678648D01*
G02Y1370882I0J-1503D01*
G01X675248D01*
G37*
G36*
G01Y1382794D02*
G02Y1385800I0J1503D01*
G01X678648D01*
G02Y1382794I0J-1503D01*
G01X675248D01*
G37*
G36*
G01X663008Y1370882D02*
G02Y1373888I0J1503D01*
G01X666408D01*
G02Y1370882I0J-1503D01*
G01X663008D01*
G37*
G36*
G01Y1382794D02*
G02Y1385800I0J1503D01*
G01X666408D01*
G02Y1382794I0J-1503D01*
G01X663008D01*
G37*
G36*
G01X650768D02*
G02Y1385800I0J1503D01*
G01X654168D01*
G02Y1382794I0J-1503D01*
G01X650768D01*
G37*
G36*
G01Y1370882D02*
G02Y1373888I0J1503D01*
G01X654168D01*
G02Y1370882I0J-1503D01*
G01X650768D01*
G37*
G36*
G01X638528D02*
G02Y1373888I0J1503D01*
G01X641928D01*
G02Y1370882I0J-1503D01*
G01X638528D01*
G37*
G36*
G01Y1382794D02*
G02Y1385800I0J1503D01*
G01X641928D01*
G02Y1382794I0J-1503D01*
G01X638528D01*
G37*
G36*
G01X650768Y1358596D02*
G02Y1361602I0J1503D01*
G01X654168D01*
G02Y1358596I0J-1503D01*
G01X650768D01*
G37*
G36*
G01Y1346684D02*
G02Y1349690I0J1503D01*
G01X654168D01*
G02Y1346684I0J-1503D01*
G01X650768D01*
G37*
G36*
G01X663008D02*
G02Y1349690I0J1503D01*
G01X666408D01*
G02Y1346684I0J-1503D01*
G01X663008D01*
G37*
G36*
G01Y1358596D02*
G02Y1361602I0J1503D01*
G01X666408D01*
G02Y1358596I0J-1503D01*
G01X663008D01*
G37*
G36*
G01X675248D02*
G02Y1361602I0J1503D01*
G01X678648D01*
G02Y1358596I0J-1503D01*
G01X675248D01*
G37*
G36*
G01Y1346684D02*
G02Y1349690I0J1503D01*
G01X678648D01*
G02Y1346684I0J-1503D01*
G01X675248D01*
G37*
G36*
G01X687488Y1358596D02*
G02Y1361602I0J1503D01*
G01X690888D01*
G02Y1358596I0J-1503D01*
G01X687488D01*
G37*
G36*
G01Y1346684D02*
G02Y1349690I0J1503D01*
G01X690888D01*
G02Y1346684I0J-1503D01*
G01X687488D01*
G37*
G36*
G01X699728D02*
G02Y1349690I0J1503D01*
G01X703128D01*
G02Y1346684I0J-1503D01*
G01X699728D01*
G37*
G36*
G01Y1358596D02*
G02Y1361602I0J1503D01*
G01X703128D01*
G02Y1358596I0J-1503D01*
G01X699728D01*
G37*
G36*
G01X711968D02*
G02Y1361602I0J1503D01*
G01X715368D01*
G02Y1358596I0J-1503D01*
G01X711968D01*
G37*
G36*
G01Y1346684D02*
G02Y1349690I0J1503D01*
G01X715368D01*
G02Y1346684I0J-1503D01*
G01X711968D01*
G37*
G36*
G01X724208D02*
G02Y1349690I0J1503D01*
G01X727608D01*
G02Y1346684I0J-1503D01*
G01X724208D01*
G37*
G36*
G01Y1358596D02*
G02Y1361602I0J1503D01*
G01X727608D01*
G02Y1358596I0J-1503D01*
G01X724208D01*
G37*
G36*
G01X736448D02*
G02Y1361602I0J1503D01*
G01X739848D01*
G02Y1358596I0J-1503D01*
G01X736448D01*
G37*
G36*
G01Y1346684D02*
G02Y1349690I0J1503D01*
G01X739848D01*
G02Y1346684I0J-1503D01*
G01X736448D01*
G37*
G36*
G01X748688Y1358596D02*
G02Y1361602I0J1503D01*
G01X752088D01*
G02Y1358596I0J-1503D01*
G01X748688D01*
G37*
G36*
G01Y1346684D02*
G02Y1349690I0J1503D01*
G01X752088D01*
G02Y1346684I0J-1503D01*
G01X748688D01*
G37*
G36*
G01X760928D02*
G02Y1349690I0J1503D01*
G01X764328D01*
G02Y1346684I0J-1503D01*
G01X760928D01*
G37*
G36*
G01Y1358596D02*
G02Y1361602I0J1503D01*
G01X764328D01*
G02Y1358596I0J-1503D01*
G01X760928D01*
G37*
G36*
G01X773168D02*
G02Y1361602I0J1503D01*
G01X776568D01*
G02Y1358596I0J-1503D01*
G01X773168D01*
G37*
G36*
G01Y1346684D02*
G02Y1349690I0J1503D01*
G01X776568D01*
G02Y1346684I0J-1503D01*
G01X773168D01*
G37*
G36*
G01X1066953Y1406992D02*
G02Y1409998I0J1503D01*
G01X1070353D01*
G02Y1406992I0J-1503D01*
G01X1066953D01*
G37*
G36*
G01Y1395080D02*
G02Y1398086I0J1503D01*
G01X1070353D01*
G02Y1395080I0J-1503D01*
G01X1066953D01*
G37*
G36*
G01X1079193D02*
G02Y1398086I0J1503D01*
G01X1082593D01*
G02Y1395080I0J-1503D01*
G01X1079193D01*
G37*
G36*
G01Y1406992D02*
G02Y1409998I0J1503D01*
G01X1082593D01*
G02Y1406992I0J-1503D01*
G01X1079193D01*
G37*
G36*
G01X1091433D02*
G02Y1409998I0J1503D01*
G01X1094833D01*
G02Y1406992I0J-1503D01*
G01X1091433D01*
G37*
G36*
G01Y1395080D02*
G02Y1398086I0J1503D01*
G01X1094833D01*
G02Y1395080I0J-1503D01*
G01X1091433D01*
G37*
G36*
G01X1103673Y1406992D02*
G02Y1409998I0J1503D01*
G01X1107073D01*
G02Y1406992I0J-1503D01*
G01X1103673D01*
G37*
G36*
G01Y1395080D02*
G02Y1398086I0J1503D01*
G01X1107073D01*
G02Y1395080I0J-1503D01*
G01X1103673D01*
G37*
G36*
G01X1115913Y1406992D02*
G02Y1409998I0J1503D01*
G01X1119313D01*
G02Y1406992I0J-1503D01*
G01X1115913D01*
G37*
G36*
G01Y1395080D02*
G02Y1398086I0J1503D01*
G01X1119313D01*
G02Y1395080I0J-1503D01*
G01X1115913D01*
G37*
G36*
G01X1128153Y1406992D02*
G02Y1409998I0J1503D01*
G01X1131553D01*
G02Y1406992I0J-1503D01*
G01X1128153D01*
G37*
G36*
G01Y1395080D02*
G02Y1398086I0J1503D01*
G01X1131553D01*
G02Y1395080I0J-1503D01*
G01X1128153D01*
G37*
G36*
G01X1140393D02*
G02Y1398086I0J1503D01*
G01X1143793D01*
G02Y1395080I0J-1503D01*
G01X1140393D01*
G37*
G36*
G01Y1406992D02*
G02Y1409998I0J1503D01*
G01X1143793D01*
G02Y1406992I0J-1503D01*
G01X1140393D01*
G37*
G36*
G01X1152633D02*
G02Y1409998I0J1503D01*
G01X1156033D01*
G02Y1406992I0J-1503D01*
G01X1152633D01*
G37*
G36*
G01Y1395080D02*
G02Y1398086I0J1503D01*
G01X1156033D01*
G02Y1395080I0J-1503D01*
G01X1152633D01*
G37*
G36*
G01X1164873Y1406992D02*
G02Y1409998I0J1503D01*
G01X1168273D01*
G02Y1406992I0J-1503D01*
G01X1164873D01*
G37*
G36*
G01Y1395080D02*
G02Y1398086I0J1503D01*
G01X1168273D01*
G02Y1395080I0J-1503D01*
G01X1164873D01*
G37*
G36*
G01X1177113D02*
G02Y1398086I0J1503D01*
G01X1180513D01*
G02Y1395080I0J-1503D01*
G01X1177113D01*
G37*
G36*
G01Y1406992D02*
G02Y1409998I0J1503D01*
G01X1180513D01*
G02Y1406992I0J-1503D01*
G01X1177113D01*
G37*
G36*
G01Y1382794D02*
G02Y1385800I0J1503D01*
G01X1180513D01*
G02Y1382794I0J-1503D01*
G01X1177113D01*
G37*
G36*
G01Y1370882D02*
G02Y1373888I0J1503D01*
G01X1180513D01*
G02Y1370882I0J-1503D01*
G01X1177113D01*
G37*
G36*
G01X1164873D02*
G02Y1373888I0J1503D01*
G01X1168273D01*
G02Y1370882I0J-1503D01*
G01X1164873D01*
G37*
G36*
G01Y1382794D02*
G02Y1385800I0J1503D01*
G01X1168273D01*
G02Y1382794I0J-1503D01*
G01X1164873D01*
G37*
G36*
G01X1152633D02*
G02Y1385800I0J1503D01*
G01X1156033D01*
G02Y1382794I0J-1503D01*
G01X1152633D01*
G37*
G36*
G01Y1370882D02*
G02Y1373888I0J1503D01*
G01X1156033D01*
G02Y1370882I0J-1503D01*
G01X1152633D01*
G37*
G36*
G01X1140393D02*
G02Y1373888I0J1503D01*
G01X1143793D01*
G02Y1370882I0J-1503D01*
G01X1140393D01*
G37*
G36*
G01Y1382794D02*
G02Y1385800I0J1503D01*
G01X1143793D01*
G02Y1382794I0J-1503D01*
G01X1140393D01*
G37*
G36*
G01X1128153D02*
G02Y1385800I0J1503D01*
G01X1131553D01*
G02Y1382794I0J-1503D01*
G01X1128153D01*
G37*
G36*
G01Y1370882D02*
G02Y1373888I0J1503D01*
G01X1131553D01*
G02Y1370882I0J-1503D01*
G01X1128153D01*
G37*
G36*
G01X1115913D02*
G02Y1373888I0J1503D01*
G01X1119313D01*
G02Y1370882I0J-1503D01*
G01X1115913D01*
G37*
G36*
G01Y1382794D02*
G02Y1385800I0J1503D01*
G01X1119313D01*
G02Y1382794I0J-1503D01*
G01X1115913D01*
G37*
G36*
G01X1103673D02*
G02Y1385800I0J1503D01*
G01X1107073D01*
G02Y1382794I0J-1503D01*
G01X1103673D01*
G37*
G36*
G01Y1370882D02*
G02Y1373888I0J1503D01*
G01X1107073D01*
G02Y1370882I0J-1503D01*
G01X1103673D01*
G37*
G36*
G01X1091433D02*
G02Y1373888I0J1503D01*
G01X1094833D01*
G02Y1370882I0J-1503D01*
G01X1091433D01*
G37*
G36*
G01Y1382794D02*
G02Y1385800I0J1503D01*
G01X1094833D01*
G02Y1382794I0J-1503D01*
G01X1091433D01*
G37*
G36*
G01X1079193D02*
G02Y1385800I0J1503D01*
G01X1082593D01*
G02Y1382794I0J-1503D01*
G01X1079193D01*
G37*
G36*
G01Y1370882D02*
G02Y1373888I0J1503D01*
G01X1082593D01*
G02Y1370882I0J-1503D01*
G01X1079193D01*
G37*
G36*
G01X1066953D02*
G02Y1373888I0J1503D01*
G01X1070353D01*
G02Y1370882I0J-1503D01*
G01X1066953D01*
G37*
G36*
G01Y1382794D02*
G02Y1385800I0J1503D01*
G01X1070353D01*
G02Y1382794I0J-1503D01*
G01X1066953D01*
G37*
G36*
G01X1054713D02*
G02Y1385800I0J1503D01*
G01X1058113D01*
G02Y1382794I0J-1503D01*
G01X1054713D01*
G37*
G36*
G01Y1370882D02*
G02Y1373888I0J1503D01*
G01X1058113D01*
G02Y1370882I0J-1503D01*
G01X1054713D01*
G37*
G36*
G01Y1358596D02*
G02Y1361602I0J1503D01*
G01X1058113D01*
G02Y1358596I0J-1503D01*
G01X1054713D01*
G37*
G36*
G01Y1346684D02*
G02Y1349690I0J1503D01*
G01X1058113D01*
G02Y1346684I0J-1503D01*
G01X1054713D01*
G37*
G36*
G01X1066953D02*
G02Y1349690I0J1503D01*
G01X1070353D01*
G02Y1346684I0J-1503D01*
G01X1066953D01*
G37*
G36*
G01Y1358596D02*
G02Y1361602I0J1503D01*
G01X1070353D01*
G02Y1358596I0J-1503D01*
G01X1066953D01*
G37*
G36*
G01X1079193D02*
G02Y1361602I0J1503D01*
G01X1082593D01*
G02Y1358596I0J-1503D01*
G01X1079193D01*
G37*
G36*
G01Y1346684D02*
G02Y1349690I0J1503D01*
G01X1082593D01*
G02Y1346684I0J-1503D01*
G01X1079193D01*
G37*
G36*
G01X1091433D02*
G02Y1349690I0J1503D01*
G01X1094833D01*
G02Y1346684I0J-1503D01*
G01X1091433D01*
G37*
G36*
G01Y1358596D02*
G02Y1361602I0J1503D01*
G01X1094833D01*
G02Y1358596I0J-1503D01*
G01X1091433D01*
G37*
G36*
G01X1103673D02*
G02Y1361602I0J1503D01*
G01X1107073D01*
G02Y1358596I0J-1503D01*
G01X1103673D01*
G37*
G36*
G01Y1346684D02*
G02Y1349690I0J1503D01*
G01X1107073D01*
G02Y1346684I0J-1503D01*
G01X1103673D01*
G37*
G36*
G01X1115913D02*
G02Y1349690I0J1503D01*
G01X1119313D01*
G02Y1346684I0J-1503D01*
G01X1115913D01*
G37*
G36*
G01Y1358596D02*
G02Y1361602I0J1503D01*
G01X1119313D01*
G02Y1358596I0J-1503D01*
G01X1115913D01*
G37*
G36*
G01X1128153D02*
G02Y1361602I0J1503D01*
G01X1131553D01*
G02Y1358596I0J-1503D01*
G01X1128153D01*
G37*
G36*
G01Y1346684D02*
G02Y1349690I0J1503D01*
G01X1131553D01*
G02Y1346684I0J-1503D01*
G01X1128153D01*
G37*
G36*
G01X1140393Y1358596D02*
G02Y1361602I0J1503D01*
G01X1143793D01*
G02Y1358596I0J-1503D01*
G01X1140393D01*
G37*
G36*
G01Y1346684D02*
G02Y1349690I0J1503D01*
G01X1143793D01*
G02Y1346684I0J-1503D01*
G01X1140393D01*
G37*
G36*
G01X1152633Y1358596D02*
G02Y1361602I0J1503D01*
G01X1156033D01*
G02Y1358596I0J-1503D01*
G01X1152633D01*
G37*
G36*
G01Y1346684D02*
G02Y1349690I0J1503D01*
G01X1156033D01*
G02Y1346684I0J-1503D01*
G01X1152633D01*
G37*
G36*
G01X1164873D02*
G02Y1349690I0J1503D01*
G01X1168273D01*
G02Y1346684I0J-1503D01*
G01X1164873D01*
G37*
G36*
G01Y1358596D02*
G02Y1361602I0J1503D01*
G01X1168273D01*
G02Y1358596I0J-1503D01*
G01X1164873D01*
G37*
G36*
G01X1177113D02*
G02Y1361602I0J1503D01*
G01X1180513D01*
G02Y1358596I0J-1503D01*
G01X1177113D01*
G37*
G36*
G01Y1346684D02*
G02Y1349690I0J1503D01*
G01X1180513D01*
G02Y1346684I0J-1503D01*
G01X1177113D01*
G37*
G36*
G01X887970Y1264141D02*
X888306D01*
X888373Y1264166D01*
X888401Y1264190D01*
G02X890375I987J-1131D01*
G01X890403Y1264166D01*
X890470Y1264141D01*
X890806D01*
X890873Y1264166D01*
X890901Y1264190D01*
G02X891888Y1264560I987J-1131D01*
G02X893390Y1263058I0J-1502D01*
G02X893020Y1262071I-1501J0D01*
G01X892996Y1262043D01*
X892971Y1261976D01*
Y1261640D01*
X892996Y1261573D01*
X893020Y1261545D01*
G02X893390Y1260558I-1131J-987D01*
G02X891888Y1259056I-1502J0D01*
G02X890901Y1259426I0J1501D01*
G01X890873Y1259450D01*
X890806Y1259475D01*
X890470D01*
X890403Y1259450D01*
X890375Y1259426D01*
G02X888401I-987J1131D01*
G01X888373Y1259450D01*
X888306Y1259475D01*
X887970D01*
X887903Y1259450D01*
X887875Y1259426D01*
G02X886888Y1259056I-987J1131D01*
G02X885386Y1260558I0J1502D01*
G02X885756Y1261545I1501J0D01*
G01X885780Y1261573D01*
X885805Y1261640D01*
Y1261976D01*
X885780Y1262043D01*
X885756Y1262071D01*
G02X885386Y1263058I1131J987D01*
G02X886888Y1264560I1502J0D01*
G02X887875Y1264190I0J-1501D01*
G01X887903Y1264166D01*
X887970Y1264141D01*
G37*
G36*
G01X951947D02*
X952283D01*
X952350Y1264166D01*
X952378Y1264190D01*
G02X954352I987J-1131D01*
G01X954380Y1264166D01*
X954447Y1264141D01*
X954783D01*
X954850Y1264166D01*
X954878Y1264190D01*
G02X955865Y1264560I987J-1131D01*
G02X957367Y1263058I0J-1502D01*
G02X956997Y1262071I-1501J0D01*
G01X956973Y1262043D01*
X956948Y1261976D01*
Y1261640D01*
X956973Y1261573D01*
X956997Y1261545D01*
G02X957367Y1260558I-1131J-987D01*
G02X955865Y1259056I-1502J0D01*
G02X954878Y1259426I0J1501D01*
G01X954850Y1259450D01*
X954783Y1259475D01*
X954447D01*
X954380Y1259450D01*
X954352Y1259426D01*
G02X952378I-987J1131D01*
G01X952350Y1259450D01*
X952283Y1259475D01*
X951947D01*
X951880Y1259450D01*
X951852Y1259426D01*
G02X950865Y1259056I-987J1131D01*
G02X949363Y1260558I0J1502D01*
G02X949733Y1261545I1501J0D01*
G01X949757Y1261573D01*
X949782Y1261640D01*
Y1261976D01*
X949757Y1262043D01*
X949733Y1262071D01*
G02X949363Y1263058I1131J987D01*
G02X950865Y1264560I1502J0D01*
G02X951852Y1264190I0J-1501D01*
G01X951880Y1264166D01*
X951947Y1264141D01*
G37*
G36*
G01X1051500Y1292251D02*
X1051142Y1292254D01*
X1051070Y1292226D01*
X1051041Y1292198D01*
G02X1050002Y1291781I-1039J1086D01*
G02Y1294785I0J1502D01*
G02X1051062Y1294347I0J-1502D01*
G01X1051090Y1294319D01*
X1051162Y1294289D01*
X1051520Y1294286D01*
X1051592Y1294314D01*
X1051621Y1294342D01*
G02X1052660Y1294759I1039J-1086D01*
G02Y1291755I0J-1502D01*
G02X1051600Y1292193I0J1502D01*
G01X1051572Y1292221D01*
X1051500Y1292251D01*
G37*
G36*
G01X871517Y1299415D02*
Y1299751D01*
X871492Y1299818D01*
X871468Y1299846D01*
G02X871098Y1300833I1131J987D01*
G02X874102I1502J0D01*
G02X873732Y1299846I-1501J0D01*
G01X873708Y1299818D01*
X873683Y1299751D01*
Y1299415D01*
X873708Y1299348D01*
X873732Y1299320D01*
G02X874102Y1298333I-1131J-987D01*
G02X871098I-1502J0D01*
G02X871468Y1299320I1501J0D01*
G01X871492Y1299348D01*
X871517Y1299415D01*
G37*
G36*
G01X794031Y1332483D02*
Y1332777D01*
G03X793966Y1332924I-200J-1D01*
G02X793481Y1334030I1017J1105D01*
G02X796485I1502J0D01*
G02X796000Y1332924I-1502J-1D01*
G03X795935Y1332777I135J-148D01*
G01Y1332483D01*
G03X796000Y1332336I200J1D01*
G02X796485Y1331230I-1017J-1105D01*
G02X793481I-1502J0D01*
G02X793966Y1332336I1502J1D01*
G03X794031Y1332483I-135J148D01*
G37*
G36*
G01X912797Y1344688D02*
X912404Y1344681D01*
X912325Y1344643D01*
X912297Y1344608D01*
G02X911135Y1344058I-1162J952D01*
G02Y1347062I0J1502D01*
G02X912262Y1346553I0J-1502D01*
G01X912291Y1346520D01*
X912371Y1346485D01*
X912764Y1346492D01*
X912843Y1346530D01*
X912871Y1346565D01*
G02X914033Y1347115I1162J-952D01*
G02Y1344111I0J-1502D01*
G02X912906Y1344620I0J1502D01*
G01X912877Y1344653D01*
X912797Y1344688D01*
G37*
G36*
G01X950490Y1370808D02*
X950174D01*
G03X950017Y1370731I1J-200D01*
G02X948832Y1370152I-1185J923D01*
G02Y1373156I0J1502D01*
G02X950017Y1372577I0J-1502D01*
G03X950174Y1372500I158J123D01*
G01X950490D01*
G03X950647Y1372577I-1J200D01*
G02X951832Y1373156I1185J-923D01*
G02Y1370152I0J-1502D01*
G02X950647Y1370731I0J1502D01*
G03X950490Y1370808I-158J-123D01*
G37*
G36*
G01X951043Y1374745D02*
X950727D01*
G03X950570Y1374668I1J-200D01*
G02X949385Y1374089I-1185J923D01*
G02Y1377093I0J1502D01*
G02X950570Y1376514I0J-1502D01*
G03X950727Y1376437I158J123D01*
G01X951043D01*
G03X951200Y1376514I-1J200D01*
G02X952385Y1377093I1185J-923D01*
G02Y1374089I0J-1502D01*
G02X951200Y1374668I0J1502D01*
G03X951043Y1374745I-158J-123D01*
G37*
G36*
G01X951098Y1378652D02*
X950788D01*
G03X950633Y1378579I-1J-200D01*
G02X949469Y1378026I-1164J949D01*
G02Y1381030I0J1502D01*
G02X950633Y1380477I0J-1502D01*
G03X950788Y1380404I154J127D01*
G01X951098D01*
G03X951253Y1380477I1J200D01*
G02X952417Y1381030I1164J-949D01*
G02Y1378026I0J-1502D01*
G02X951253Y1378579I0J1502D01*
G03X951098Y1378652I-154J-127D01*
G37*
G36*
G01X985794Y1400790D02*
X985478D01*
G03X985321Y1400713I1J-200D01*
G02X984136Y1400134I-1185J923D01*
G02Y1403138I0J1502D01*
G02X985321Y1402559I0J-1502D01*
G03X985478Y1402482I158J123D01*
G01X985794D01*
G03X985951Y1402559I-1J200D01*
G02X987136Y1403138I1185J-923D01*
G02Y1400134I0J-1502D01*
G02X985951Y1400713I0J1502D01*
G03X985794Y1400790I-158J-123D01*
G37*
G36*
G01X627954Y1464825D02*
Y1465951D01*
G02X628157Y1466154I203J0D01*
G01X630977D01*
G02X631180Y1465951I0J-203D01*
G01Y1464825D01*
G03X631208Y1464722I200J-1D01*
G02Y1462760I-1640J-981D01*
G03X631180Y1462657I172J-102D01*
G01Y1459706D01*
G03X631208Y1459603I200J-1D01*
G02Y1457641I-1640J-981D01*
G03X631180Y1457538I172J-102D01*
G01Y1456413D01*
G02X630977Y1456210I-203J0D01*
G01X628157D01*
G02X627954Y1456413I0J203D01*
G01Y1457538D01*
G03X627926Y1457641I-200J1D01*
G02Y1459603I1640J981D01*
G03X627954Y1459706I-172J102D01*
G01Y1462657D01*
G03X627926Y1462760I-200J1D01*
G02Y1464722I1640J981D01*
G03X627954Y1464825I-172J102D01*
G37*
G36*
G01X645278D02*
Y1465951D01*
G02X645480Y1466154I202J1D01*
G01X648300D01*
G02X648502Y1465951I-1J-203D01*
G01Y1464825D01*
G03X648531Y1464722I200J1D01*
G02Y1462760I-1640J-981D01*
G03X648502Y1462657I171J-104D01*
G01Y1459706D01*
G03X648531Y1459603I200J1D01*
G02Y1457641I-1640J-981D01*
G03X648502Y1457538I171J-104D01*
G01Y1456413D01*
G02X648300Y1456210I-202J-1D01*
G01X645480D01*
G02X645278Y1456413I1J203D01*
G01Y1457538D01*
G03X645249Y1457641I-200J-1D01*
G02Y1459603I1640J981D01*
G03X645278Y1459706I-171J104D01*
G01Y1462657D01*
G03X645249Y1462760I-200J-1D01*
G02Y1464722I1640J981D01*
G03X645278Y1464825I-171J104D01*
G37*
G36*
G01X662600D02*
Y1465951D01*
G02X662803Y1466154I203J0D01*
G01X665623D01*
G02X665826Y1465951I0J-203D01*
G01Y1464825D01*
G03X665854Y1464722I200J-1D01*
G02Y1462760I-1640J-981D01*
G03X665826Y1462657I172J-102D01*
G01Y1459706D01*
G03X665854Y1459603I200J-1D01*
G02Y1457641I-1640J-981D01*
G03X665826Y1457538I172J-102D01*
G01Y1456413D01*
G02X665623Y1456210I-203J0D01*
G01X662803D01*
G02X662600Y1456413I0J203D01*
G01Y1457538D01*
G03X662572Y1457641I-200J1D01*
G02Y1459603I1640J981D01*
G03X662600Y1459706I-172J102D01*
G01Y1462657D01*
G03X662572Y1462760I-200J1D01*
G02Y1464722I1640J981D01*
G03X662600Y1464825I-172J102D01*
G37*
G36*
G01X679922D02*
Y1465951D01*
G02X680125Y1466154I203J0D01*
G01X682945D01*
G02X683148Y1465951I0J-203D01*
G01Y1464825D01*
G03X683176Y1464722I200J-1D01*
G02Y1462760I-1640J-981D01*
G03X683148Y1462657I172J-102D01*
G01Y1459706D01*
G03X683176Y1459603I200J-1D01*
G02Y1457641I-1640J-981D01*
G03X683148Y1457538I172J-102D01*
G01Y1456413D01*
G02X682945Y1456210I-203J0D01*
G01X680125D01*
G02X679922Y1456413I0J203D01*
G01Y1457538D01*
G03X679894Y1457641I-200J1D01*
G02Y1459603I1640J981D01*
G03X679922Y1459706I-172J102D01*
G01Y1462657D01*
G03X679894Y1462760I-200J1D01*
G02Y1464722I1640J981D01*
G03X679922Y1464825I-172J102D01*
G37*
G36*
G01X1130238D02*
Y1465951D01*
G02X1130440Y1466154I202J1D01*
G01X1133260D01*
G02X1133462Y1465951I-1J-203D01*
G01Y1464825D01*
G03X1133491Y1464722I200J1D01*
G02Y1462760I-1640J-981D01*
G03X1133462Y1462657I171J-104D01*
G01Y1459706D01*
G03X1133491Y1459603I200J1D01*
G02Y1457641I-1640J-981D01*
G03X1133462Y1457538I171J-104D01*
G01Y1456413D01*
G02X1133260Y1456210I-202J-1D01*
G01X1130440D01*
G02X1130238Y1456413I1J203D01*
G01Y1457538D01*
G03X1130209Y1457641I-200J-1D01*
G02Y1459603I1640J981D01*
G03X1130238Y1459706I-171J104D01*
G01Y1462657D01*
G03X1130209Y1462760I-200J-1D01*
G02Y1464722I1640J981D01*
G03X1130238Y1464825I-171J104D01*
G37*
G36*
G01X1147560D02*
Y1465951D01*
G02X1147763Y1466154I203J0D01*
G01X1150583D01*
G02X1150786Y1465951I0J-203D01*
G01Y1464825D01*
G03X1150814Y1464722I200J-1D01*
G02Y1462760I-1640J-981D01*
G03X1150786Y1462657I172J-102D01*
G01Y1459706D01*
G03X1150814Y1459603I200J-1D01*
G02Y1457641I-1640J-981D01*
G03X1150786Y1457538I172J-102D01*
G01Y1456413D01*
G02X1150583Y1456210I-203J0D01*
G01X1147763D01*
G02X1147560Y1456413I0J203D01*
G01Y1457538D01*
G03X1147532Y1457641I-200J1D01*
G02Y1459603I1640J981D01*
G03X1147560Y1459706I-172J102D01*
G01Y1462657D01*
G03X1147532Y1462760I-200J1D01*
G02Y1464722I1640J981D01*
G03X1147560Y1464825I-172J102D01*
G37*
G36*
G01X1164884D02*
Y1465951D01*
G02X1165086Y1466154I202J1D01*
G01X1167906D01*
G02X1168108Y1465951I-1J-203D01*
G01Y1464825D01*
G03X1168137Y1464722I200J1D01*
G02Y1462760I-1640J-981D01*
G03X1168108Y1462657I171J-104D01*
G01Y1459706D01*
G03X1168137Y1459603I200J1D01*
G02Y1457641I-1640J-981D01*
G03X1168108Y1457538I171J-104D01*
G01Y1456413D01*
G02X1167906Y1456210I-202J-1D01*
G01X1165086D01*
G02X1164884Y1456413I1J203D01*
G01Y1457538D01*
G03X1164855Y1457641I-200J-1D01*
G02Y1459603I1640J981D01*
G03X1164884Y1459706I-171J104D01*
G01Y1462657D01*
G03X1164855Y1462760I-200J-1D01*
G02Y1464722I1640J981D01*
G03X1164884Y1464825I-171J104D01*
G37*
G36*
G01X1182206D02*
Y1465951D01*
G02X1182408Y1466154I202J1D01*
G01X1185228D01*
G02X1185430Y1465951I-1J-203D01*
G01Y1464825D01*
G03X1185459Y1464722I200J1D01*
G02Y1462760I-1640J-981D01*
G03X1185430Y1462657I171J-104D01*
G01Y1459706D01*
G03X1185459Y1459603I200J1D01*
G02Y1457641I-1640J-981D01*
G03X1185430Y1457538I171J-104D01*
G01Y1456413D01*
G02X1185228Y1456210I-202J-1D01*
G01X1182408D01*
G02X1182206Y1456413I1J203D01*
G01Y1457538D01*
G03X1182177Y1457641I-200J-1D01*
G02Y1459603I1640J981D01*
G03X1182206Y1459706I-171J104D01*
G01Y1462657D01*
G03X1182177Y1462760I-200J-1D01*
G02Y1464722I1640J981D01*
G03X1182206Y1464825I-171J104D01*
G37*
G36*
G01X636616Y1469155D02*
Y1470281D01*
G02X636818Y1470484I202J1D01*
G01X639638D01*
G02X639840Y1470281I-1J-203D01*
G01Y1469155D01*
G03X639869Y1469052I200J1D01*
G02Y1467090I-1640J-981D01*
G03X639840Y1466987I171J-104D01*
G01Y1464037D01*
G03X639869Y1463934I200J1D01*
G02Y1461972I-1640J-981D01*
G03X639840Y1461869I171J-104D01*
G01Y1460743D01*
G02X639638Y1460540I-202J-1D01*
G01X636818D01*
G02X636616Y1460743I1J203D01*
G01Y1461869D01*
G03X636587Y1461972I-200J-1D01*
G02Y1463934I1640J981D01*
G03X636616Y1464037I-171J104D01*
G01Y1466987D01*
G03X636587Y1467090I-200J-1D01*
G02Y1469052I1640J981D01*
G03X636616Y1469155I-171J104D01*
G37*
G36*
G01X653938D02*
Y1470281D01*
G02X654141Y1470484I203J0D01*
G01X656961D01*
G02X657164Y1470281I0J-203D01*
G01Y1469155D01*
G03X657192Y1469052I200J-1D01*
G02Y1467090I-1640J-981D01*
G03X657164Y1466987I172J-102D01*
G01Y1464037D01*
G03X657192Y1463934I200J-1D01*
G02Y1461972I-1640J-981D01*
G03X657164Y1461869I172J-102D01*
G01Y1460743D01*
G02X656961Y1460540I-203J0D01*
G01X654141D01*
G02X653938Y1460743I0J203D01*
G01Y1461869D01*
G03X653910Y1461972I-200J1D01*
G02Y1463934I1640J981D01*
G03X653938Y1464037I-172J102D01*
G01Y1466987D01*
G03X653910Y1467090I-200J1D01*
G02Y1469052I1640J981D01*
G03X653938Y1469155I-172J102D01*
G37*
G36*
G01X671262D02*
Y1470281D01*
G02X671464Y1470484I202J1D01*
G01X674284D01*
G02X674486Y1470281I-1J-203D01*
G01Y1469155D01*
G03X674515Y1469052I200J1D01*
G02Y1467090I-1640J-981D01*
G03X674486Y1466987I171J-104D01*
G01Y1464037D01*
G03X674515Y1463934I200J1D01*
G02Y1461972I-1640J-981D01*
G03X674486Y1461869I171J-104D01*
G01Y1460743D01*
G02X674284Y1460540I-202J-1D01*
G01X671464D01*
G02X671262Y1460743I1J203D01*
G01Y1461869D01*
G03X671233Y1461972I-200J-1D01*
G02Y1463934I1640J981D01*
G03X671262Y1464037I-171J104D01*
G01Y1466987D01*
G03X671233Y1467090I-200J-1D01*
G02Y1469052I1640J981D01*
G03X671262Y1469155I-171J104D01*
G37*
G36*
G01X688584D02*
Y1470281D01*
G02X688787Y1470484I203J0D01*
G01X691607D01*
G02X691810Y1470281I0J-203D01*
G01Y1469155D01*
G03X691838Y1469052I200J-1D01*
G02Y1467090I-1640J-981D01*
G03X691810Y1466987I172J-102D01*
G01Y1464037D01*
G03X691838Y1463934I200J-1D01*
G02Y1461972I-1640J-981D01*
G03X691810Y1461869I172J-102D01*
G01Y1460743D01*
G02X691607Y1460540I-203J0D01*
G01X688787D01*
G02X688584Y1460743I0J203D01*
G01Y1461869D01*
G03X688556Y1461972I-200J1D01*
G02Y1463934I1640J981D01*
G03X688584Y1464037I-172J102D01*
G01Y1466987D01*
G03X688556Y1467090I-200J1D01*
G02Y1469052I1640J981D01*
G03X688584Y1469155I-172J102D01*
G37*
G36*
G01X1138898D02*
Y1470281D01*
G02X1139101Y1470484I203J0D01*
G01X1141921D01*
G02X1142124Y1470281I0J-203D01*
G01Y1469155D01*
G03X1142152Y1469052I200J-1D01*
G02Y1467090I-1640J-981D01*
G03X1142124Y1466987I172J-102D01*
G01Y1464037D01*
G03X1142152Y1463934I200J-1D01*
G02Y1461972I-1640J-981D01*
G03X1142124Y1461869I172J-102D01*
G01Y1460743D01*
G02X1141921Y1460540I-203J0D01*
G01X1139101D01*
G02X1138898Y1460743I0J203D01*
G01Y1461869D01*
G03X1138870Y1461972I-200J1D01*
G02Y1463934I1640J981D01*
G03X1138898Y1464037I-172J102D01*
G01Y1466987D01*
G03X1138870Y1467090I-200J1D01*
G02Y1469052I1640J981D01*
G03X1138898Y1469155I-172J102D01*
G37*
G36*
G01X1156222D02*
Y1470281D01*
G02X1156424Y1470484I202J1D01*
G01X1159244D01*
G02X1159446Y1470281I-1J-203D01*
G01Y1469155D01*
G03X1159475Y1469052I200J1D01*
G02Y1467090I-1640J-981D01*
G03X1159446Y1466987I171J-104D01*
G01Y1464037D01*
G03X1159475Y1463934I200J1D01*
G02Y1461972I-1640J-981D01*
G03X1159446Y1461869I171J-104D01*
G01Y1460743D01*
G02X1159244Y1460540I-202J-1D01*
G01X1156424D01*
G02X1156222Y1460743I1J203D01*
G01Y1461869D01*
G03X1156193Y1461972I-200J-1D01*
G02Y1463934I1640J981D01*
G03X1156222Y1464037I-171J104D01*
G01Y1466987D01*
G03X1156193Y1467090I-200J-1D01*
G02Y1469052I1640J981D01*
G03X1156222Y1469155I-171J104D01*
G37*
G36*
G01X1173544D02*
Y1470281D01*
G02X1173747Y1470484I203J0D01*
G01X1176567D01*
G02X1176770Y1470281I0J-203D01*
G01Y1469155D01*
G03X1176798Y1469052I200J-1D01*
G02Y1467090I-1640J-981D01*
G03X1176770Y1466987I172J-102D01*
G01Y1464037D01*
G03X1176798Y1463934I200J-1D01*
G02Y1461972I-1640J-981D01*
G03X1176770Y1461869I172J-102D01*
G01Y1460743D01*
G02X1176567Y1460540I-203J0D01*
G01X1173747D01*
G02X1173544Y1460743I0J203D01*
G01Y1461869D01*
G03X1173516Y1461972I-200J1D01*
G02Y1463934I1640J981D01*
G03X1173544Y1464037I-172J102D01*
G01Y1466987D01*
G03X1173516Y1467090I-200J1D01*
G02Y1469052I1640J981D01*
G03X1173544Y1469155I-172J102D01*
G37*
G36*
G01X1190868D02*
Y1470281D01*
G02X1191070Y1470484I202J1D01*
G01X1193890D01*
G02X1194092Y1470281I-1J-203D01*
G01Y1469155D01*
G03X1194121Y1469052I200J1D01*
G02Y1467090I-1640J-981D01*
G03X1194092Y1466987I171J-104D01*
G01Y1464037D01*
G03X1194121Y1463934I200J1D01*
G02Y1461972I-1640J-981D01*
G03X1194092Y1461869I171J-104D01*
G01Y1460743D01*
G02X1193890Y1460540I-202J-1D01*
G01X1191070D01*
G02X1190868Y1460743I1J203D01*
G01Y1461869D01*
G03X1190839Y1461972I-200J-1D01*
G02Y1463934I1640J981D01*
G03X1190868Y1464037I-171J104D01*
G01Y1466987D01*
G03X1190839Y1467090I-200J-1D01*
G02Y1469052I1640J981D01*
G03X1190868Y1469155I-171J104D01*
G37*
G36*
G01X627954Y1480179D02*
Y1481305D01*
G02X628157Y1481508I203J0D01*
G01X630977D01*
G02X631180Y1481305I0J-203D01*
G01Y1480179D01*
G03X631208Y1480076I200J-1D01*
G02Y1478114I-1640J-981D01*
G03X631180Y1478011I172J-102D01*
G01Y1475061D01*
G03X631208Y1474958I200J-1D01*
G02Y1472996I-1640J-981D01*
G03X631180Y1472893I172J-102D01*
G01Y1471767D01*
G02X630977Y1471564I-203J0D01*
G01X628157D01*
G02X627954Y1471767I0J203D01*
G01Y1472893D01*
G03X627926Y1472996I-200J1D01*
G02Y1474958I1640J981D01*
G03X627954Y1475061I-172J102D01*
G01Y1478011D01*
G03X627926Y1478114I-200J1D01*
G02Y1480076I1640J981D01*
G03X627954Y1480179I-172J102D01*
G37*
G36*
G01X645278D02*
Y1481305D01*
G02X645480Y1481508I202J1D01*
G01X648300D01*
G02X648502Y1481305I-1J-203D01*
G01Y1480179D01*
G03X648531Y1480076I200J1D01*
G02Y1478114I-1640J-981D01*
G03X648502Y1478011I171J-104D01*
G01Y1475061D01*
G03X648531Y1474958I200J1D01*
G02Y1472996I-1640J-981D01*
G03X648502Y1472893I171J-104D01*
G01Y1471767D01*
G02X648300Y1471564I-202J-1D01*
G01X645480D01*
G02X645278Y1471767I1J203D01*
G01Y1472893D01*
G03X645249Y1472996I-200J-1D01*
G02Y1474958I1640J981D01*
G03X645278Y1475061I-171J104D01*
G01Y1478011D01*
G03X645249Y1478114I-200J-1D01*
G02Y1480076I1640J981D01*
G03X645278Y1480179I-171J104D01*
G37*
G36*
G01X662600D02*
Y1481305D01*
G02X662803Y1481508I203J0D01*
G01X665623D01*
G02X665826Y1481305I0J-203D01*
G01Y1480179D01*
G03X665854Y1480076I200J-1D01*
G02Y1478114I-1640J-981D01*
G03X665826Y1478011I172J-102D01*
G01Y1475061D01*
G03X665854Y1474958I200J-1D01*
G02Y1472996I-1640J-981D01*
G03X665826Y1472893I172J-102D01*
G01Y1471767D01*
G02X665623Y1471564I-203J0D01*
G01X662803D01*
G02X662600Y1471767I0J203D01*
G01Y1472893D01*
G03X662572Y1472996I-200J1D01*
G02Y1474958I1640J981D01*
G03X662600Y1475061I-172J102D01*
G01Y1478011D01*
G03X662572Y1478114I-200J1D01*
G02Y1480076I1640J981D01*
G03X662600Y1480179I-172J102D01*
G37*
G36*
G01X679922D02*
Y1481305D01*
G02X680125Y1481508I203J0D01*
G01X682945D01*
G02X683148Y1481305I0J-203D01*
G01Y1480179D01*
G03X683176Y1480076I200J-1D01*
G02Y1478114I-1640J-981D01*
G03X683148Y1478011I172J-102D01*
G01Y1475061D01*
G03X683176Y1474958I200J-1D01*
G02Y1472996I-1640J-981D01*
G03X683148Y1472893I172J-102D01*
G01Y1471767D01*
G02X682945Y1471564I-203J0D01*
G01X680125D01*
G02X679922Y1471767I0J203D01*
G01Y1472893D01*
G03X679894Y1472996I-200J1D01*
G02Y1474958I1640J981D01*
G03X679922Y1475061I-172J102D01*
G01Y1478011D01*
G03X679894Y1478114I-200J1D01*
G02Y1480076I1640J981D01*
G03X679922Y1480179I-172J102D01*
G37*
G36*
G01X1130238D02*
Y1481305D01*
G02X1130440Y1481508I202J1D01*
G01X1133260D01*
G02X1133462Y1481305I-1J-203D01*
G01Y1480179D01*
G03X1133491Y1480076I200J1D01*
G02Y1478114I-1640J-981D01*
G03X1133462Y1478011I171J-104D01*
G01Y1475061D01*
G03X1133491Y1474958I200J1D01*
G02Y1472996I-1640J-981D01*
G03X1133462Y1472893I171J-104D01*
G01Y1471767D01*
G02X1133260Y1471564I-202J-1D01*
G01X1130440D01*
G02X1130238Y1471767I1J203D01*
G01Y1472893D01*
G03X1130209Y1472996I-200J-1D01*
G02Y1474958I1640J981D01*
G03X1130238Y1475061I-171J104D01*
G01Y1478011D01*
G03X1130209Y1478114I-200J-1D01*
G02Y1480076I1640J981D01*
G03X1130238Y1480179I-171J104D01*
G37*
G36*
G01X1147560D02*
Y1481305D01*
G02X1147763Y1481508I203J0D01*
G01X1150583D01*
G02X1150786Y1481305I0J-203D01*
G01Y1480179D01*
G03X1150814Y1480076I200J-1D01*
G02Y1478114I-1640J-981D01*
G03X1150786Y1478011I172J-102D01*
G01Y1475061D01*
G03X1150814Y1474958I200J-1D01*
G02Y1472996I-1640J-981D01*
G03X1150786Y1472893I172J-102D01*
G01Y1471767D01*
G02X1150583Y1471564I-203J0D01*
G01X1147763D01*
G02X1147560Y1471767I0J203D01*
G01Y1472893D01*
G03X1147532Y1472996I-200J1D01*
G02Y1474958I1640J981D01*
G03X1147560Y1475061I-172J102D01*
G01Y1478011D01*
G03X1147532Y1478114I-200J1D01*
G02Y1480076I1640J981D01*
G03X1147560Y1480179I-172J102D01*
G37*
G36*
G01X1164884D02*
Y1481305D01*
G02X1165086Y1481508I202J1D01*
G01X1167906D01*
G02X1168108Y1481305I-1J-203D01*
G01Y1480179D01*
G03X1168137Y1480076I200J1D01*
G02Y1478114I-1640J-981D01*
G03X1168108Y1478011I171J-104D01*
G01Y1475061D01*
G03X1168137Y1474958I200J1D01*
G02Y1472996I-1640J-981D01*
G03X1168108Y1472893I171J-104D01*
G01Y1471767D01*
G02X1167906Y1471564I-202J-1D01*
G01X1165086D01*
G02X1164884Y1471767I1J203D01*
G01Y1472893D01*
G03X1164855Y1472996I-200J-1D01*
G02Y1474958I1640J981D01*
G03X1164884Y1475061I-171J104D01*
G01Y1478011D01*
G03X1164855Y1478114I-200J-1D01*
G02Y1480076I1640J981D01*
G03X1164884Y1480179I-171J104D01*
G37*
G36*
G01X1182206D02*
Y1481305D01*
G02X1182408Y1481508I202J1D01*
G01X1185228D01*
G02X1185430Y1481305I-1J-203D01*
G01Y1480179D01*
G03X1185459Y1480076I200J1D01*
G02Y1478114I-1640J-981D01*
G03X1185430Y1478011I171J-104D01*
G01Y1475061D01*
G03X1185459Y1474958I200J1D01*
G02Y1472996I-1640J-981D01*
G03X1185430Y1472893I171J-104D01*
G01Y1471767D01*
G02X1185228Y1471564I-202J-1D01*
G01X1182408D01*
G02X1182206Y1471767I1J203D01*
G01Y1472893D01*
G03X1182177Y1472996I-200J-1D01*
G02Y1474958I1640J981D01*
G03X1182206Y1475061I-171J104D01*
G01Y1478011D01*
G03X1182177Y1478114I-200J-1D01*
G02Y1480076I1640J981D01*
G03X1182206Y1480179I-171J104D01*
G37*
G36*
G01X636616Y1484510D02*
Y1485635D01*
G02X636818Y1485838I202J1D01*
G01X639638D01*
G02X639840Y1485635I-1J-203D01*
G01Y1484510D01*
G03X639869Y1484407I200J1D01*
G02Y1482445I-1640J-981D01*
G03X639840Y1482342I171J-104D01*
G01Y1479392D01*
G03X639869Y1479289I200J1D01*
G02Y1477327I-1640J-981D01*
G03X639840Y1477224I171J-104D01*
G01Y1476097D01*
G02X639638Y1475894I-202J-1D01*
G01X636818D01*
G02X636616Y1476097I1J203D01*
G01Y1477224D01*
G03X636587Y1477327I-200J-1D01*
G02Y1479289I1640J981D01*
G03X636616Y1479392I-171J104D01*
G01Y1482342D01*
G03X636587Y1482445I-200J-1D01*
G02Y1484407I1640J981D01*
G03X636616Y1484510I-171J104D01*
G37*
G36*
G01X653938D02*
Y1485635D01*
G02X654141Y1485838I203J0D01*
G01X656961D01*
G02X657164Y1485635I0J-203D01*
G01Y1484510D01*
G03X657192Y1484407I200J-1D01*
G02Y1482445I-1640J-981D01*
G03X657164Y1482342I172J-102D01*
G01Y1479392D01*
G03X657192Y1479289I200J-1D01*
G02Y1477327I-1640J-981D01*
G03X657164Y1477224I172J-102D01*
G01Y1476097D01*
G02X656961Y1475894I-203J0D01*
G01X654141D01*
G02X653938Y1476097I0J203D01*
G01Y1477224D01*
G03X653910Y1477327I-200J1D01*
G02Y1479289I1640J981D01*
G03X653938Y1479392I-172J102D01*
G01Y1482342D01*
G03X653910Y1482445I-200J1D01*
G02Y1484407I1640J981D01*
G03X653938Y1484510I-172J102D01*
G37*
G36*
G01X671262D02*
Y1485635D01*
G02X671464Y1485838I202J1D01*
G01X674284D01*
G02X674486Y1485635I-1J-203D01*
G01Y1484510D01*
G03X674515Y1484407I200J1D01*
G02Y1482445I-1640J-981D01*
G03X674486Y1482342I171J-104D01*
G01Y1479392D01*
G03X674515Y1479289I200J1D01*
G02Y1477327I-1640J-981D01*
G03X674486Y1477224I171J-104D01*
G01Y1476097D01*
G02X674284Y1475894I-202J-1D01*
G01X671464D01*
G02X671262Y1476097I1J203D01*
G01Y1477224D01*
G03X671233Y1477327I-200J-1D01*
G02Y1479289I1640J981D01*
G03X671262Y1479392I-171J104D01*
G01Y1482342D01*
G03X671233Y1482445I-200J-1D01*
G02Y1484407I1640J981D01*
G03X671262Y1484510I-171J104D01*
G37*
G36*
G01X688584D02*
Y1485635D01*
G02X688787Y1485838I203J0D01*
G01X691607D01*
G02X691810Y1485635I0J-203D01*
G01Y1484510D01*
G03X691838Y1484407I200J-1D01*
G02Y1482445I-1640J-981D01*
G03X691810Y1482342I172J-102D01*
G01Y1479392D01*
G03X691838Y1479289I200J-1D01*
G02Y1477327I-1640J-981D01*
G03X691810Y1477224I172J-102D01*
G01Y1476097D01*
G02X691607Y1475894I-203J0D01*
G01X688787D01*
G02X688584Y1476097I0J203D01*
G01Y1477224D01*
G03X688556Y1477327I-200J1D01*
G02Y1479289I1640J981D01*
G03X688584Y1479392I-172J102D01*
G01Y1482342D01*
G03X688556Y1482445I-200J1D01*
G02Y1484407I1640J981D01*
G03X688584Y1484510I-172J102D01*
G37*
G36*
G01X1138898D02*
Y1485635D01*
G02X1139101Y1485838I203J0D01*
G01X1141921D01*
G02X1142124Y1485635I0J-203D01*
G01Y1484510D01*
G03X1142152Y1484407I200J-1D01*
G02Y1482445I-1640J-981D01*
G03X1142124Y1482342I172J-102D01*
G01Y1479392D01*
G03X1142152Y1479289I200J-1D01*
G02Y1477327I-1640J-981D01*
G03X1142124Y1477224I172J-102D01*
G01Y1476097D01*
G02X1141921Y1475894I-203J0D01*
G01X1139101D01*
G02X1138898Y1476097I0J203D01*
G01Y1477224D01*
G03X1138870Y1477327I-200J1D01*
G02Y1479289I1640J981D01*
G03X1138898Y1479392I-172J102D01*
G01Y1482342D01*
G03X1138870Y1482445I-200J1D01*
G02Y1484407I1640J981D01*
G03X1138898Y1484510I-172J102D01*
G37*
G36*
G01X1156222D02*
Y1485635D01*
G02X1156424Y1485838I202J1D01*
G01X1159244D01*
G02X1159446Y1485635I-1J-203D01*
G01Y1484510D01*
G03X1159475Y1484407I200J1D01*
G02Y1482445I-1640J-981D01*
G03X1159446Y1482342I171J-104D01*
G01Y1479392D01*
G03X1159475Y1479289I200J1D01*
G02Y1477327I-1640J-981D01*
G03X1159446Y1477224I171J-104D01*
G01Y1476097D01*
G02X1159244Y1475894I-202J-1D01*
G01X1156424D01*
G02X1156222Y1476097I1J203D01*
G01Y1477224D01*
G03X1156193Y1477327I-200J-1D01*
G02Y1479289I1640J981D01*
G03X1156222Y1479392I-171J104D01*
G01Y1482342D01*
G03X1156193Y1482445I-200J-1D01*
G02Y1484407I1640J981D01*
G03X1156222Y1484510I-171J104D01*
G37*
G36*
G01X1173544D02*
Y1485635D01*
G02X1173747Y1485838I203J0D01*
G01X1176567D01*
G02X1176770Y1485635I0J-203D01*
G01Y1484510D01*
G03X1176798Y1484407I200J-1D01*
G02Y1482445I-1640J-981D01*
G03X1176770Y1482342I172J-102D01*
G01Y1479392D01*
G03X1176798Y1479289I200J-1D01*
G02Y1477327I-1640J-981D01*
G03X1176770Y1477224I172J-102D01*
G01Y1476097D01*
G02X1176567Y1475894I-203J0D01*
G01X1173747D01*
G02X1173544Y1476097I0J203D01*
G01Y1477224D01*
G03X1173516Y1477327I-200J1D01*
G02Y1479289I1640J981D01*
G03X1173544Y1479392I-172J102D01*
G01Y1482342D01*
G03X1173516Y1482445I-200J1D01*
G02Y1484407I1640J981D01*
G03X1173544Y1484510I-172J102D01*
G37*
G36*
G01X1190868D02*
Y1485635D01*
G02X1191070Y1485838I202J1D01*
G01X1193890D01*
G02X1194092Y1485635I-1J-203D01*
G01Y1484510D01*
G03X1194121Y1484407I200J1D01*
G02Y1482445I-1640J-981D01*
G03X1194092Y1482342I171J-104D01*
G01Y1479392D01*
G03X1194121Y1479289I200J1D01*
G02Y1477327I-1640J-981D01*
G03X1194092Y1477224I171J-104D01*
G01Y1476097D01*
G02X1193890Y1475894I-202J-1D01*
G01X1191070D01*
G02X1190868Y1476097I1J203D01*
G01Y1477224D01*
G03X1190839Y1477327I-200J-1D01*
G02Y1479289I1640J981D01*
G03X1190868Y1479392I-171J104D01*
G01Y1482342D01*
G03X1190839Y1482445I-200J-1D01*
G02Y1484407I1640J981D01*
G03X1190868Y1484510I-171J104D01*
G37*
G36*
G01X627954Y1495533D02*
Y1496659D01*
G02X628157Y1496862I203J0D01*
G01X630977D01*
G02X631180Y1496659I0J-203D01*
G01Y1495533D01*
G03X631208Y1495430I200J-1D01*
G02Y1493468I-1640J-981D01*
G03X631180Y1493365I172J-102D01*
G01Y1490415D01*
G03X631208Y1490312I200J-1D01*
G02Y1488350I-1640J-981D01*
G03X631180Y1488247I172J-102D01*
G01Y1487121D01*
G02X630977Y1486918I-203J0D01*
G01X628157D01*
G02X627954Y1487121I0J203D01*
G01Y1488247D01*
G03X627926Y1488350I-200J1D01*
G02Y1490312I1640J981D01*
G03X627954Y1490415I-172J102D01*
G01Y1493365D01*
G03X627926Y1493468I-200J1D01*
G02Y1495430I1640J981D01*
G03X627954Y1495533I-172J102D01*
G37*
G36*
G01X645278D02*
Y1496659D01*
G02X645480Y1496862I202J1D01*
G01X648300D01*
G02X648502Y1496659I-1J-203D01*
G01Y1495533D01*
G03X648531Y1495430I200J1D01*
G02Y1493468I-1640J-981D01*
G03X648502Y1493365I171J-104D01*
G01Y1490415D01*
G03X648531Y1490312I200J1D01*
G02Y1488350I-1640J-981D01*
G03X648502Y1488247I171J-104D01*
G01Y1487121D01*
G02X648300Y1486918I-202J-1D01*
G01X645480D01*
G02X645278Y1487121I1J203D01*
G01Y1488247D01*
G03X645249Y1488350I-200J-1D01*
G02Y1490312I1640J981D01*
G03X645278Y1490415I-171J104D01*
G01Y1493365D01*
G03X645249Y1493468I-200J-1D01*
G02Y1495430I1640J981D01*
G03X645278Y1495533I-171J104D01*
G37*
G36*
G01X662600D02*
Y1496659D01*
G02X662803Y1496862I203J0D01*
G01X665623D01*
G02X665826Y1496659I0J-203D01*
G01Y1495533D01*
G03X665854Y1495430I200J-1D01*
G02Y1493468I-1640J-981D01*
G03X665826Y1493365I172J-102D01*
G01Y1490415D01*
G03X665854Y1490312I200J-1D01*
G02Y1488350I-1640J-981D01*
G03X665826Y1488247I172J-102D01*
G01Y1487121D01*
G02X665623Y1486918I-203J0D01*
G01X662803D01*
G02X662600Y1487121I0J203D01*
G01Y1488247D01*
G03X662572Y1488350I-200J1D01*
G02Y1490312I1640J981D01*
G03X662600Y1490415I-172J102D01*
G01Y1493365D01*
G03X662572Y1493468I-200J1D01*
G02Y1495430I1640J981D01*
G03X662600Y1495533I-172J102D01*
G37*
G36*
G01X679922D02*
Y1496659D01*
G02X680125Y1496862I203J0D01*
G01X682945D01*
G02X683148Y1496659I0J-203D01*
G01Y1495533D01*
G03X683176Y1495430I200J-1D01*
G02Y1493468I-1640J-981D01*
G03X683148Y1493365I172J-102D01*
G01Y1490415D01*
G03X683176Y1490312I200J-1D01*
G02Y1488350I-1640J-981D01*
G03X683148Y1488247I172J-102D01*
G01Y1487121D01*
G02X682945Y1486918I-203J0D01*
G01X680125D01*
G02X679922Y1487121I0J203D01*
G01Y1488247D01*
G03X679894Y1488350I-200J1D01*
G02Y1490312I1640J981D01*
G03X679922Y1490415I-172J102D01*
G01Y1493365D01*
G03X679894Y1493468I-200J1D01*
G02Y1495430I1640J981D01*
G03X679922Y1495533I-172J102D01*
G37*
G36*
G01X1130238D02*
Y1496659D01*
G02X1130440Y1496862I202J1D01*
G01X1133260D01*
G02X1133462Y1496659I-1J-203D01*
G01Y1495533D01*
G03X1133491Y1495430I200J1D01*
G02Y1493468I-1640J-981D01*
G03X1133462Y1493365I171J-104D01*
G01Y1490415D01*
G03X1133491Y1490312I200J1D01*
G02Y1488350I-1640J-981D01*
G03X1133462Y1488247I171J-104D01*
G01Y1487121D01*
G02X1133260Y1486918I-202J-1D01*
G01X1130440D01*
G02X1130238Y1487121I1J203D01*
G01Y1488247D01*
G03X1130209Y1488350I-200J-1D01*
G02Y1490312I1640J981D01*
G03X1130238Y1490415I-171J104D01*
G01Y1493365D01*
G03X1130209Y1493468I-200J-1D01*
G02Y1495430I1640J981D01*
G03X1130238Y1495533I-171J104D01*
G37*
G36*
G01X1147560D02*
Y1496659D01*
G02X1147763Y1496862I203J0D01*
G01X1150583D01*
G02X1150786Y1496659I0J-203D01*
G01Y1495533D01*
G03X1150814Y1495430I200J-1D01*
G02Y1493468I-1640J-981D01*
G03X1150786Y1493365I172J-102D01*
G01Y1490415D01*
G03X1150814Y1490312I200J-1D01*
G02Y1488350I-1640J-981D01*
G03X1150786Y1488247I172J-102D01*
G01Y1487121D01*
G02X1150583Y1486918I-203J0D01*
G01X1147763D01*
G02X1147560Y1487121I0J203D01*
G01Y1488247D01*
G03X1147532Y1488350I-200J1D01*
G02Y1490312I1640J981D01*
G03X1147560Y1490415I-172J102D01*
G01Y1493365D01*
G03X1147532Y1493468I-200J1D01*
G02Y1495430I1640J981D01*
G03X1147560Y1495533I-172J102D01*
G37*
G36*
G01X1164884D02*
Y1496659D01*
G02X1165086Y1496862I202J1D01*
G01X1167906D01*
G02X1168108Y1496659I-1J-203D01*
G01Y1495533D01*
G03X1168137Y1495430I200J1D01*
G02Y1493468I-1640J-981D01*
G03X1168108Y1493365I171J-104D01*
G01Y1490415D01*
G03X1168137Y1490312I200J1D01*
G02Y1488350I-1640J-981D01*
G03X1168108Y1488247I171J-104D01*
G01Y1487121D01*
G02X1167906Y1486918I-202J-1D01*
G01X1165086D01*
G02X1164884Y1487121I1J203D01*
G01Y1488247D01*
G03X1164855Y1488350I-200J-1D01*
G02Y1490312I1640J981D01*
G03X1164884Y1490415I-171J104D01*
G01Y1493365D01*
G03X1164855Y1493468I-200J-1D01*
G02Y1495430I1640J981D01*
G03X1164884Y1495533I-171J104D01*
G37*
G36*
G01X1182206D02*
Y1496659D01*
G02X1182408Y1496862I202J1D01*
G01X1185228D01*
G02X1185430Y1496659I-1J-203D01*
G01Y1495533D01*
G03X1185459Y1495430I200J1D01*
G02Y1493468I-1640J-981D01*
G03X1185430Y1493365I171J-104D01*
G01Y1490415D01*
G03X1185459Y1490312I200J1D01*
G02Y1488350I-1640J-981D01*
G03X1185430Y1488247I171J-104D01*
G01Y1487121D01*
G02X1185228Y1486918I-202J-1D01*
G01X1182408D01*
G02X1182206Y1487121I1J203D01*
G01Y1488247D01*
G03X1182177Y1488350I-200J-1D01*
G02Y1490312I1640J981D01*
G03X1182206Y1490415I-171J104D01*
G01Y1493365D01*
G03X1182177Y1493468I-200J-1D01*
G02Y1495430I1640J981D01*
G03X1182206Y1495533I-171J104D01*
G37*
G36*
G01X636616Y1499864D02*
Y1500989D01*
G02X636818Y1501192I202J1D01*
G01X639638D01*
G02X639840Y1500989I-1J-203D01*
G01Y1499864D01*
G03X639869Y1499761I200J1D01*
G02Y1497799I-1640J-981D01*
G03X639840Y1497696I171J-104D01*
G01Y1494746D01*
G03X639869Y1494643I200J1D01*
G02Y1492681I-1640J-981D01*
G03X639840Y1492578I171J-104D01*
G01Y1491451D01*
G02X639638Y1491248I-202J-1D01*
G01X636818D01*
G02X636616Y1491451I1J203D01*
G01Y1492578D01*
G03X636587Y1492681I-200J-1D01*
G02Y1494643I1640J981D01*
G03X636616Y1494746I-171J104D01*
G01Y1497696D01*
G03X636587Y1497799I-200J-1D01*
G02Y1499761I1640J981D01*
G03X636616Y1499864I-171J104D01*
G37*
G36*
G01X653938D02*
Y1500989D01*
G02X654141Y1501192I203J0D01*
G01X656961D01*
G02X657164Y1500989I0J-203D01*
G01Y1499864D01*
G03X657192Y1499761I200J-1D01*
G02Y1497799I-1640J-981D01*
G03X657164Y1497696I172J-102D01*
G01Y1494746D01*
G03X657192Y1494643I200J-1D01*
G02Y1492681I-1640J-981D01*
G03X657164Y1492578I172J-102D01*
G01Y1491451D01*
G02X656961Y1491248I-203J0D01*
G01X654141D01*
G02X653938Y1491451I0J203D01*
G01Y1492578D01*
G03X653910Y1492681I-200J1D01*
G02Y1494643I1640J981D01*
G03X653938Y1494746I-172J102D01*
G01Y1497696D01*
G03X653910Y1497799I-200J1D01*
G02Y1499761I1640J981D01*
G03X653938Y1499864I-172J102D01*
G37*
G36*
G01X671262D02*
Y1500989D01*
G02X671464Y1501192I202J1D01*
G01X674284D01*
G02X674486Y1500989I-1J-203D01*
G01Y1499864D01*
G03X674515Y1499761I200J1D01*
G02Y1497799I-1640J-981D01*
G03X674486Y1497696I171J-104D01*
G01Y1494746D01*
G03X674515Y1494643I200J1D01*
G02Y1492681I-1640J-981D01*
G03X674486Y1492578I171J-104D01*
G01Y1491451D01*
G02X674284Y1491248I-202J-1D01*
G01X671464D01*
G02X671262Y1491451I1J203D01*
G01Y1492578D01*
G03X671233Y1492681I-200J-1D01*
G02Y1494643I1640J981D01*
G03X671262Y1494746I-171J104D01*
G01Y1497696D01*
G03X671233Y1497799I-200J-1D01*
G02Y1499761I1640J981D01*
G03X671262Y1499864I-171J104D01*
G37*
G36*
G01X688584D02*
Y1500989D01*
G02X688787Y1501192I203J0D01*
G01X691607D01*
G02X691810Y1500989I0J-203D01*
G01Y1499864D01*
G03X691838Y1499761I200J-1D01*
G02Y1497799I-1640J-981D01*
G03X691810Y1497696I172J-102D01*
G01Y1494746D01*
G03X691838Y1494643I200J-1D01*
G02Y1492681I-1640J-981D01*
G03X691810Y1492578I172J-102D01*
G01Y1491451D01*
G02X691607Y1491248I-203J0D01*
G01X688787D01*
G02X688584Y1491451I0J203D01*
G01Y1492578D01*
G03X688556Y1492681I-200J1D01*
G02Y1494643I1640J981D01*
G03X688584Y1494746I-172J102D01*
G01Y1497696D01*
G03X688556Y1497799I-200J1D01*
G02Y1499761I1640J981D01*
G03X688584Y1499864I-172J102D01*
G37*
G36*
G01X1138898D02*
Y1500989D01*
G02X1139101Y1501192I203J0D01*
G01X1141921D01*
G02X1142124Y1500989I0J-203D01*
G01Y1499864D01*
G03X1142152Y1499761I200J-1D01*
G02Y1497799I-1640J-981D01*
G03X1142124Y1497696I172J-102D01*
G01Y1494746D01*
G03X1142152Y1494643I200J-1D01*
G02Y1492681I-1640J-981D01*
G03X1142124Y1492578I172J-102D01*
G01Y1491451D01*
G02X1141921Y1491248I-203J0D01*
G01X1139101D01*
G02X1138898Y1491451I0J203D01*
G01Y1492578D01*
G03X1138870Y1492681I-200J1D01*
G02Y1494643I1640J981D01*
G03X1138898Y1494746I-172J102D01*
G01Y1497696D01*
G03X1138870Y1497799I-200J1D01*
G02Y1499761I1640J981D01*
G03X1138898Y1499864I-172J102D01*
G37*
G36*
G01X1156222D02*
Y1500989D01*
G02X1156424Y1501192I202J1D01*
G01X1159244D01*
G02X1159446Y1500989I-1J-203D01*
G01Y1499864D01*
G03X1159475Y1499761I200J1D01*
G02Y1497799I-1640J-981D01*
G03X1159446Y1497696I171J-104D01*
G01Y1494746D01*
G03X1159475Y1494643I200J1D01*
G02Y1492681I-1640J-981D01*
G03X1159446Y1492578I171J-104D01*
G01Y1491451D01*
G02X1159244Y1491248I-202J-1D01*
G01X1156424D01*
G02X1156222Y1491451I1J203D01*
G01Y1492578D01*
G03X1156193Y1492681I-200J-1D01*
G02Y1494643I1640J981D01*
G03X1156222Y1494746I-171J104D01*
G01Y1497696D01*
G03X1156193Y1497799I-200J-1D01*
G02Y1499761I1640J981D01*
G03X1156222Y1499864I-171J104D01*
G37*
G36*
G01X1173544D02*
Y1500989D01*
G02X1173747Y1501192I203J0D01*
G01X1176567D01*
G02X1176770Y1500989I0J-203D01*
G01Y1499864D01*
G03X1176798Y1499761I200J-1D01*
G02Y1497799I-1640J-981D01*
G03X1176770Y1497696I172J-102D01*
G01Y1494746D01*
G03X1176798Y1494643I200J-1D01*
G02Y1492681I-1640J-981D01*
G03X1176770Y1492578I172J-102D01*
G01Y1491451D01*
G02X1176567Y1491248I-203J0D01*
G01X1173747D01*
G02X1173544Y1491451I0J203D01*
G01Y1492578D01*
G03X1173516Y1492681I-200J1D01*
G02Y1494643I1640J981D01*
G03X1173544Y1494746I-172J102D01*
G01Y1497696D01*
G03X1173516Y1497799I-200J1D01*
G02Y1499761I1640J981D01*
G03X1173544Y1499864I-172J102D01*
G37*
G36*
G01X1190868D02*
Y1500989D01*
G02X1191070Y1501192I202J1D01*
G01X1193890D01*
G02X1194092Y1500989I-1J-203D01*
G01Y1499864D01*
G03X1194121Y1499761I200J1D01*
G02Y1497799I-1640J-981D01*
G03X1194092Y1497696I171J-104D01*
G01Y1494746D01*
G03X1194121Y1494643I200J1D01*
G02Y1492681I-1640J-981D01*
G03X1194092Y1492578I171J-104D01*
G01Y1491451D01*
G02X1193890Y1491248I-202J-1D01*
G01X1191070D01*
G02X1190868Y1491451I1J203D01*
G01Y1492578D01*
G03X1190839Y1492681I-200J-1D01*
G02Y1494643I1640J981D01*
G03X1190868Y1494746I-171J104D01*
G01Y1497696D01*
G03X1190839Y1497799I-200J-1D01*
G02Y1499761I1640J981D01*
G03X1190868Y1499864I-171J104D01*
G37*
G36*
G01X627954Y1510888D02*
Y1512014D01*
G02X628157Y1512216I203J-1D01*
G01X630977D01*
G02X631180Y1512014I1J-202D01*
G01Y1510888D01*
G03X631208Y1510785I200J-1D01*
G02Y1508823I-1640J-981D01*
G03X631180Y1508720I172J-102D01*
G01Y1505769D01*
G03X631208Y1505666I200J-1D01*
G02Y1503704I-1640J-981D01*
G03X631180Y1503601I172J-102D01*
G01Y1502476D01*
G02X630977Y1502274I-203J1D01*
G01X628157D01*
G02X627954Y1502476I-1J202D01*
G01Y1503601D01*
G03X627926Y1503704I-200J1D01*
G02Y1505666I1640J981D01*
G03X627954Y1505769I-172J102D01*
G01Y1508720D01*
G03X627926Y1508823I-200J1D01*
G02Y1510785I1640J981D01*
G03X627954Y1510888I-172J102D01*
G37*
G36*
G01X645278D02*
Y1512014D01*
G02X645480Y1512216I202J0D01*
G01X648300D01*
G02X648502Y1512014I0J-202D01*
G01Y1510888D01*
G03X648531Y1510785I200J1D01*
G02Y1508823I-1640J-981D01*
G03X648502Y1508720I171J-104D01*
G01Y1505769D01*
G03X648531Y1505666I200J1D01*
G02Y1503704I-1640J-981D01*
G03X648502Y1503601I171J-104D01*
G01Y1502476D01*
G02X648300Y1502274I-202J0D01*
G01X645480D01*
G02X645278Y1502476I0J202D01*
G01Y1503601D01*
G03X645249Y1503704I-200J-1D01*
G02Y1505666I1640J981D01*
G03X645278Y1505769I-171J104D01*
G01Y1508720D01*
G03X645249Y1508823I-200J-1D01*
G02Y1510785I1640J981D01*
G03X645278Y1510888I-171J104D01*
G37*
G36*
G01X662600D02*
Y1512014D01*
G02X662803Y1512216I203J-1D01*
G01X665623D01*
G02X665826Y1512014I1J-202D01*
G01Y1510888D01*
G03X665854Y1510785I200J-1D01*
G02Y1508823I-1640J-981D01*
G03X665826Y1508720I172J-102D01*
G01Y1505769D01*
G03X665854Y1505666I200J-1D01*
G02Y1503704I-1640J-981D01*
G03X665826Y1503601I172J-102D01*
G01Y1502476D01*
G02X665623Y1502274I-203J1D01*
G01X662803D01*
G02X662600Y1502476I-1J202D01*
G01Y1503601D01*
G03X662572Y1503704I-200J1D01*
G02Y1505666I1640J981D01*
G03X662600Y1505769I-172J102D01*
G01Y1508720D01*
G03X662572Y1508823I-200J1D01*
G02Y1510785I1640J981D01*
G03X662600Y1510888I-172J102D01*
G37*
G36*
G01X679922D02*
Y1512014D01*
G02X680125Y1512216I203J-1D01*
G01X682945D01*
G02X683148Y1512014I1J-202D01*
G01Y1510888D01*
G03X683176Y1510785I200J-1D01*
G02Y1508823I-1640J-981D01*
G03X683148Y1508720I172J-102D01*
G01Y1505769D01*
G03X683176Y1505666I200J-1D01*
G02Y1503704I-1640J-981D01*
G03X683148Y1503601I172J-102D01*
G01Y1502476D01*
G02X682945Y1502274I-203J1D01*
G01X680125D01*
G02X679922Y1502476I-1J202D01*
G01Y1503601D01*
G03X679894Y1503704I-200J1D01*
G02Y1505666I1640J981D01*
G03X679922Y1505769I-172J102D01*
G01Y1508720D01*
G03X679894Y1508823I-200J1D01*
G02Y1510785I1640J981D01*
G03X679922Y1510888I-172J102D01*
G37*
G36*
G01X1130238D02*
Y1512014D01*
G02X1130440Y1512216I202J0D01*
G01X1133260D01*
G02X1133462Y1512014I0J-202D01*
G01Y1510888D01*
G03X1133491Y1510785I200J1D01*
G02Y1508823I-1640J-981D01*
G03X1133462Y1508720I171J-104D01*
G01Y1505769D01*
G03X1133491Y1505666I200J1D01*
G02Y1503704I-1640J-981D01*
G03X1133462Y1503601I171J-104D01*
G01Y1502476D01*
G02X1133260Y1502274I-202J0D01*
G01X1130440D01*
G02X1130238Y1502476I0J202D01*
G01Y1503601D01*
G03X1130209Y1503704I-200J-1D01*
G02Y1505666I1640J981D01*
G03X1130238Y1505769I-171J104D01*
G01Y1508720D01*
G03X1130209Y1508823I-200J-1D01*
G02Y1510785I1640J981D01*
G03X1130238Y1510888I-171J104D01*
G37*
G36*
G01X1147560D02*
Y1512014D01*
G02X1147763Y1512216I203J-1D01*
G01X1150583D01*
G02X1150786Y1512014I1J-202D01*
G01Y1510888D01*
G03X1150814Y1510785I200J-1D01*
G02Y1508823I-1640J-981D01*
G03X1150786Y1508720I172J-102D01*
G01Y1505769D01*
G03X1150814Y1505666I200J-1D01*
G02Y1503704I-1640J-981D01*
G03X1150786Y1503601I172J-102D01*
G01Y1502476D01*
G02X1150583Y1502274I-203J1D01*
G01X1147763D01*
G02X1147560Y1502476I-1J202D01*
G01Y1503601D01*
G03X1147532Y1503704I-200J1D01*
G02Y1505666I1640J981D01*
G03X1147560Y1505769I-172J102D01*
G01Y1508720D01*
G03X1147532Y1508823I-200J1D01*
G02Y1510785I1640J981D01*
G03X1147560Y1510888I-172J102D01*
G37*
G36*
G01X1164884D02*
Y1512014D01*
G02X1165086Y1512216I202J0D01*
G01X1167906D01*
G02X1168108Y1512014I0J-202D01*
G01Y1510888D01*
G03X1168137Y1510785I200J1D01*
G02Y1508823I-1640J-981D01*
G03X1168108Y1508720I171J-104D01*
G01Y1505769D01*
G03X1168137Y1505666I200J1D01*
G02Y1503704I-1640J-981D01*
G03X1168108Y1503601I171J-104D01*
G01Y1502476D01*
G02X1167906Y1502274I-202J0D01*
G01X1165086D01*
G02X1164884Y1502476I0J202D01*
G01Y1503601D01*
G03X1164855Y1503704I-200J-1D01*
G02Y1505666I1640J981D01*
G03X1164884Y1505769I-171J104D01*
G01Y1508720D01*
G03X1164855Y1508823I-200J-1D01*
G02Y1510785I1640J981D01*
G03X1164884Y1510888I-171J104D01*
G37*
G36*
G01X1182206D02*
Y1512014D01*
G02X1182408Y1512216I202J0D01*
G01X1185228D01*
G02X1185430Y1512014I0J-202D01*
G01Y1510888D01*
G03X1185459Y1510785I200J1D01*
G02Y1508823I-1640J-981D01*
G03X1185430Y1508720I171J-104D01*
G01Y1505769D01*
G03X1185459Y1505666I200J1D01*
G02Y1503704I-1640J-981D01*
G03X1185430Y1503601I171J-104D01*
G01Y1502476D01*
G02X1185228Y1502274I-202J0D01*
G01X1182408D01*
G02X1182206Y1502476I0J202D01*
G01Y1503601D01*
G03X1182177Y1503704I-200J-1D01*
G02Y1505666I1640J981D01*
G03X1182206Y1505769I-171J104D01*
G01Y1508720D01*
G03X1182177Y1508823I-200J-1D01*
G02Y1510785I1640J981D01*
G03X1182206Y1510888I-171J104D01*
G37*
G36*
G01X636616Y1515218D02*
Y1516344D01*
G02X636818Y1516546I202J0D01*
G01X639638D01*
G02X639840Y1516344I0J-202D01*
G01Y1515218D01*
G03X639869Y1515115I200J1D01*
G02Y1513153I-1640J-981D01*
G03X639840Y1513050I171J-104D01*
G01Y1510100D01*
G03X639869Y1509997I200J1D01*
G02Y1508035I-1640J-981D01*
G03X639840Y1507932I171J-104D01*
G01Y1506806D01*
G02X639638Y1506604I-202J0D01*
G01X636818D01*
G02X636616Y1506806I0J202D01*
G01Y1507932D01*
G03X636587Y1508035I-200J-1D01*
G02Y1509997I1640J981D01*
G03X636616Y1510100I-171J104D01*
G01Y1513050D01*
G03X636587Y1513153I-200J-1D01*
G02Y1515115I1640J981D01*
G03X636616Y1515218I-171J104D01*
G37*
G36*
G01X653938D02*
Y1516344D01*
G02X654141Y1516546I203J-1D01*
G01X656961D01*
G02X657164Y1516344I1J-202D01*
G01Y1515218D01*
G03X657192Y1515115I200J-1D01*
G02Y1513153I-1640J-981D01*
G03X657164Y1513050I172J-102D01*
G01Y1510100D01*
G03X657192Y1509997I200J-1D01*
G02Y1508035I-1640J-981D01*
G03X657164Y1507932I172J-102D01*
G01Y1506806D01*
G02X656961Y1506604I-203J1D01*
G01X654141D01*
G02X653938Y1506806I-1J202D01*
G01Y1507932D01*
G03X653910Y1508035I-200J1D01*
G02Y1509997I1640J981D01*
G03X653938Y1510100I-172J102D01*
G01Y1513050D01*
G03X653910Y1513153I-200J1D01*
G02Y1515115I1640J981D01*
G03X653938Y1515218I-172J102D01*
G37*
G36*
G01X671262D02*
Y1516344D01*
G02X671464Y1516546I202J0D01*
G01X674284D01*
G02X674486Y1516344I0J-202D01*
G01Y1515218D01*
G03X674515Y1515115I200J1D01*
G02Y1513153I-1640J-981D01*
G03X674486Y1513050I171J-104D01*
G01Y1510100D01*
G03X674515Y1509997I200J1D01*
G02Y1508035I-1640J-981D01*
G03X674486Y1507932I171J-104D01*
G01Y1506806D01*
G02X674284Y1506604I-202J0D01*
G01X671464D01*
G02X671262Y1506806I0J202D01*
G01Y1507932D01*
G03X671233Y1508035I-200J-1D01*
G02Y1509997I1640J981D01*
G03X671262Y1510100I-171J104D01*
G01Y1513050D01*
G03X671233Y1513153I-200J-1D01*
G02Y1515115I1640J981D01*
G03X671262Y1515218I-171J104D01*
G37*
G36*
G01X688584D02*
Y1516344D01*
G02X688787Y1516546I203J-1D01*
G01X691607D01*
G02X691810Y1516344I1J-202D01*
G01Y1515218D01*
G03X691838Y1515115I200J-1D01*
G02Y1513153I-1640J-981D01*
G03X691810Y1513050I172J-102D01*
G01Y1510100D01*
G03X691838Y1509997I200J-1D01*
G02Y1508035I-1640J-981D01*
G03X691810Y1507932I172J-102D01*
G01Y1506806D01*
G02X691607Y1506604I-203J1D01*
G01X688787D01*
G02X688584Y1506806I-1J202D01*
G01Y1507932D01*
G03X688556Y1508035I-200J1D01*
G02Y1509997I1640J981D01*
G03X688584Y1510100I-172J102D01*
G01Y1513050D01*
G03X688556Y1513153I-200J1D01*
G02Y1515115I1640J981D01*
G03X688584Y1515218I-172J102D01*
G37*
G36*
G01X1138898D02*
Y1516344D01*
G02X1139101Y1516546I203J-1D01*
G01X1141921D01*
G02X1142124Y1516344I1J-202D01*
G01Y1515218D01*
G03X1142152Y1515115I200J-1D01*
G02Y1513153I-1640J-981D01*
G03X1142124Y1513050I172J-102D01*
G01Y1510100D01*
G03X1142152Y1509997I200J-1D01*
G02Y1508035I-1640J-981D01*
G03X1142124Y1507932I172J-102D01*
G01Y1506806D01*
G02X1141921Y1506604I-203J1D01*
G01X1139101D01*
G02X1138898Y1506806I-1J202D01*
G01Y1507932D01*
G03X1138870Y1508035I-200J1D01*
G02Y1509997I1640J981D01*
G03X1138898Y1510100I-172J102D01*
G01Y1513050D01*
G03X1138870Y1513153I-200J1D01*
G02Y1515115I1640J981D01*
G03X1138898Y1515218I-172J102D01*
G37*
G36*
G01X1156222D02*
Y1516344D01*
G02X1156424Y1516546I202J0D01*
G01X1159244D01*
G02X1159446Y1516344I0J-202D01*
G01Y1515218D01*
G03X1159475Y1515115I200J1D01*
G02Y1513153I-1640J-981D01*
G03X1159446Y1513050I171J-104D01*
G01Y1510100D01*
G03X1159475Y1509997I200J1D01*
G02Y1508035I-1640J-981D01*
G03X1159446Y1507932I171J-104D01*
G01Y1506806D01*
G02X1159244Y1506604I-202J0D01*
G01X1156424D01*
G02X1156222Y1506806I0J202D01*
G01Y1507932D01*
G03X1156193Y1508035I-200J-1D01*
G02Y1509997I1640J981D01*
G03X1156222Y1510100I-171J104D01*
G01Y1513050D01*
G03X1156193Y1513153I-200J-1D01*
G02Y1515115I1640J981D01*
G03X1156222Y1515218I-171J104D01*
G37*
G36*
G01X1173544D02*
Y1516344D01*
G02X1173747Y1516546I203J-1D01*
G01X1176567D01*
G02X1176770Y1516344I1J-202D01*
G01Y1515218D01*
G03X1176798Y1515115I200J-1D01*
G02Y1513153I-1640J-981D01*
G03X1176770Y1513050I172J-102D01*
G01Y1510100D01*
G03X1176798Y1509997I200J-1D01*
G02Y1508035I-1640J-981D01*
G03X1176770Y1507932I172J-102D01*
G01Y1506806D01*
G02X1176567Y1506604I-203J1D01*
G01X1173747D01*
G02X1173544Y1506806I-1J202D01*
G01Y1507932D01*
G03X1173516Y1508035I-200J1D01*
G02Y1509997I1640J981D01*
G03X1173544Y1510100I-172J102D01*
G01Y1513050D01*
G03X1173516Y1513153I-200J1D01*
G02Y1515115I1640J981D01*
G03X1173544Y1515218I-172J102D01*
G37*
G36*
G01X1190868D02*
Y1516344D01*
G02X1191070Y1516546I202J0D01*
G01X1193890D01*
G02X1194092Y1516344I0J-202D01*
G01Y1515218D01*
G03X1194121Y1515115I200J1D01*
G02Y1513153I-1640J-981D01*
G03X1194092Y1513050I171J-104D01*
G01Y1510100D01*
G03X1194121Y1509997I200J1D01*
G02Y1508035I-1640J-981D01*
G03X1194092Y1507932I171J-104D01*
G01Y1506806D01*
G02X1193890Y1506604I-202J0D01*
G01X1191070D01*
G02X1190868Y1506806I0J202D01*
G01Y1507932D01*
G03X1190839Y1508035I-200J-1D01*
G02Y1509997I1640J981D01*
G03X1190868Y1510100I-171J104D01*
G01Y1513050D01*
G03X1190839Y1513153I-200J-1D01*
G02Y1515115I1640J981D01*
G03X1190868Y1515218I-171J104D01*
G37*
G36*
G01X571723Y1519752D02*
X571667Y1520126D01*
X571623Y1520196D01*
X571588Y1520220D01*
G02X570930Y1521462I843J1242D01*
G02X573934I1502J0D01*
G02X573606Y1520525I-1502J0D01*
G01X573579Y1520492D01*
X573558Y1520412D01*
X573614Y1520038D01*
X573658Y1519968D01*
X573693Y1519944D01*
G02X574351Y1518702I-843J-1242D01*
G02X571347I-1502J0D01*
G02X571675Y1519639I1502J0D01*
G01X571702Y1519672D01*
X571723Y1519752D01*
G37*
G36*
G01X627954Y1567187D02*
Y1568313D01*
G02X628157Y1568516I203J0D01*
G01X630977D01*
G02X631180Y1568313I0J-203D01*
G01Y1567187D01*
G03X631208Y1567084I200J-1D01*
G02Y1565122I-1640J-981D01*
G03X631180Y1565019I172J-102D01*
G01Y1562069D01*
G03X631208Y1561966I200J-1D01*
G02Y1560004I-1640J-981D01*
G03X631180Y1559901I172J-102D01*
G01Y1558775D01*
G02X630977Y1558572I-203J0D01*
G01X628157D01*
G02X627954Y1558775I0J203D01*
G01Y1559901D01*
G03X627926Y1560004I-200J1D01*
G02Y1561966I1640J981D01*
G03X627954Y1562069I-172J102D01*
G01Y1565019D01*
G03X627926Y1565122I-200J1D01*
G02Y1567084I1640J981D01*
G03X627954Y1567187I-172J102D01*
G37*
G36*
G01X645278D02*
Y1568313D01*
G02X645480Y1568516I202J1D01*
G01X648300D01*
G02X648502Y1568313I-1J-203D01*
G01Y1567187D01*
G03X648531Y1567084I200J1D01*
G02Y1565122I-1640J-981D01*
G03X648502Y1565019I171J-104D01*
G01Y1562069D01*
G03X648531Y1561966I200J1D01*
G02Y1560004I-1640J-981D01*
G03X648502Y1559901I171J-104D01*
G01Y1558775D01*
G02X648300Y1558572I-202J-1D01*
G01X645480D01*
G02X645278Y1558775I1J203D01*
G01Y1559901D01*
G03X645249Y1560004I-200J-1D01*
G02Y1561966I1640J981D01*
G03X645278Y1562069I-171J104D01*
G01Y1565019D01*
G03X645249Y1565122I-200J-1D01*
G02Y1567084I1640J981D01*
G03X645278Y1567187I-171J104D01*
G37*
G36*
G01X662600D02*
Y1568313D01*
G02X662803Y1568516I203J0D01*
G01X665623D01*
G02X665826Y1568313I0J-203D01*
G01Y1567187D01*
G03X665854Y1567084I200J-1D01*
G02Y1565122I-1640J-981D01*
G03X665826Y1565019I172J-102D01*
G01Y1562069D01*
G03X665854Y1561966I200J-1D01*
G02Y1560004I-1640J-981D01*
G03X665826Y1559901I172J-102D01*
G01Y1558775D01*
G02X665623Y1558572I-203J0D01*
G01X662803D01*
G02X662600Y1558775I0J203D01*
G01Y1559901D01*
G03X662572Y1560004I-200J1D01*
G02Y1561966I1640J981D01*
G03X662600Y1562069I-172J102D01*
G01Y1565019D01*
G03X662572Y1565122I-200J1D01*
G02Y1567084I1640J981D01*
G03X662600Y1567187I-172J102D01*
G37*
G36*
G01X679922D02*
Y1568313D01*
G02X680125Y1568516I203J0D01*
G01X682945D01*
G02X683148Y1568313I0J-203D01*
G01Y1567187D01*
G03X683176Y1567084I200J-1D01*
G02Y1565122I-1640J-981D01*
G03X683148Y1565019I172J-102D01*
G01Y1562069D01*
G03X683176Y1561966I200J-1D01*
G02Y1560004I-1640J-981D01*
G03X683148Y1559901I172J-102D01*
G01Y1558775D01*
G02X682945Y1558572I-203J0D01*
G01X680125D01*
G02X679922Y1558775I0J203D01*
G01Y1559901D01*
G03X679894Y1560004I-200J1D01*
G02Y1561966I1640J981D01*
G03X679922Y1562069I-172J102D01*
G01Y1565019D01*
G03X679894Y1565122I-200J1D01*
G02Y1567084I1640J981D01*
G03X679922Y1567187I-172J102D01*
G37*
G36*
G01X1130238D02*
Y1568313D01*
G02X1130440Y1568516I202J1D01*
G01X1133260D01*
G02X1133462Y1568313I-1J-203D01*
G01Y1567187D01*
G03X1133491Y1567084I200J1D01*
G02Y1565122I-1640J-981D01*
G03X1133462Y1565019I171J-104D01*
G01Y1562069D01*
G03X1133491Y1561966I200J1D01*
G02Y1560004I-1640J-981D01*
G03X1133462Y1559901I171J-104D01*
G01Y1558775D01*
G02X1133260Y1558572I-202J-1D01*
G01X1130440D01*
G02X1130238Y1558775I1J203D01*
G01Y1559901D01*
G03X1130209Y1560004I-200J-1D01*
G02Y1561966I1640J981D01*
G03X1130238Y1562069I-171J104D01*
G01Y1565019D01*
G03X1130209Y1565122I-200J-1D01*
G02Y1567084I1640J981D01*
G03X1130238Y1567187I-171J104D01*
G37*
G36*
G01X1147560D02*
Y1568313D01*
G02X1147763Y1568516I203J0D01*
G01X1150583D01*
G02X1150786Y1568313I0J-203D01*
G01Y1567187D01*
G03X1150814Y1567084I200J-1D01*
G02Y1565122I-1640J-981D01*
G03X1150786Y1565019I172J-102D01*
G01Y1562069D01*
G03X1150814Y1561966I200J-1D01*
G02Y1560004I-1640J-981D01*
G03X1150786Y1559901I172J-102D01*
G01Y1558775D01*
G02X1150583Y1558572I-203J0D01*
G01X1147763D01*
G02X1147560Y1558775I0J203D01*
G01Y1559901D01*
G03X1147532Y1560004I-200J1D01*
G02Y1561966I1640J981D01*
G03X1147560Y1562069I-172J102D01*
G01Y1565019D01*
G03X1147532Y1565122I-200J1D01*
G02Y1567084I1640J981D01*
G03X1147560Y1567187I-172J102D01*
G37*
G36*
G01X1164884D02*
Y1568313D01*
G02X1165086Y1568516I202J1D01*
G01X1167906D01*
G02X1168108Y1568313I-1J-203D01*
G01Y1567187D01*
G03X1168137Y1567084I200J1D01*
G02Y1565122I-1640J-981D01*
G03X1168108Y1565019I171J-104D01*
G01Y1562069D01*
G03X1168137Y1561966I200J1D01*
G02Y1560004I-1640J-981D01*
G03X1168108Y1559901I171J-104D01*
G01Y1558775D01*
G02X1167906Y1558572I-202J-1D01*
G01X1165086D01*
G02X1164884Y1558775I1J203D01*
G01Y1559901D01*
G03X1164855Y1560004I-200J-1D01*
G02Y1561966I1640J981D01*
G03X1164884Y1562069I-171J104D01*
G01Y1565019D01*
G03X1164855Y1565122I-200J-1D01*
G02Y1567084I1640J981D01*
G03X1164884Y1567187I-171J104D01*
G37*
G36*
G01X1182206D02*
Y1568313D01*
G02X1182408Y1568516I202J1D01*
G01X1185228D01*
G02X1185430Y1568313I-1J-203D01*
G01Y1567187D01*
G03X1185459Y1567084I200J1D01*
G02Y1565122I-1640J-981D01*
G03X1185430Y1565019I171J-104D01*
G01Y1562069D01*
G03X1185459Y1561966I200J1D01*
G02Y1560004I-1640J-981D01*
G03X1185430Y1559901I171J-104D01*
G01Y1558775D01*
G02X1185228Y1558572I-202J-1D01*
G01X1182408D01*
G02X1182206Y1558775I1J203D01*
G01Y1559901D01*
G03X1182177Y1560004I-200J-1D01*
G02Y1561966I1640J981D01*
G03X1182206Y1562069I-171J104D01*
G01Y1565019D01*
G03X1182177Y1565122I-200J-1D01*
G02Y1567084I1640J981D01*
G03X1182206Y1567187I-171J104D01*
G37*
G36*
G01X636616Y1571518D02*
Y1572644D01*
G02X636818Y1572846I202J0D01*
G01X639638D01*
G02X639840Y1572644I0J-202D01*
G01Y1571518D01*
G03X639869Y1571415I200J1D01*
G02Y1569453I-1640J-981D01*
G03X639840Y1569350I171J-104D01*
G01Y1566399D01*
G03X639869Y1566296I200J1D01*
G02Y1564334I-1640J-981D01*
G03X639840Y1564231I171J-104D01*
G01Y1563106D01*
G02X639638Y1562904I-202J0D01*
G01X636818D01*
G02X636616Y1563106I0J202D01*
G01Y1564231D01*
G03X636587Y1564334I-200J-1D01*
G02Y1566296I1640J981D01*
G03X636616Y1566399I-171J104D01*
G01Y1569350D01*
G03X636587Y1569453I-200J-1D01*
G02Y1571415I1640J981D01*
G03X636616Y1571518I-171J104D01*
G37*
G36*
G01X653938D02*
Y1572644D01*
G02X654141Y1572846I203J-1D01*
G01X656961D01*
G02X657164Y1572644I1J-202D01*
G01Y1571518D01*
G03X657192Y1571415I200J-1D01*
G02Y1569453I-1640J-981D01*
G03X657164Y1569350I172J-102D01*
G01Y1566399D01*
G03X657192Y1566296I200J-1D01*
G02Y1564334I-1640J-981D01*
G03X657164Y1564231I172J-102D01*
G01Y1563106D01*
G02X656961Y1562904I-203J1D01*
G01X654141D01*
G02X653938Y1563106I-1J202D01*
G01Y1564231D01*
G03X653910Y1564334I-200J1D01*
G02Y1566296I1640J981D01*
G03X653938Y1566399I-172J102D01*
G01Y1569350D01*
G03X653910Y1569453I-200J1D01*
G02Y1571415I1640J981D01*
G03X653938Y1571518I-172J102D01*
G37*
G36*
G01X671262D02*
Y1572644D01*
G02X671464Y1572846I202J0D01*
G01X674284D01*
G02X674486Y1572644I0J-202D01*
G01Y1571518D01*
G03X674515Y1571415I200J1D01*
G02Y1569453I-1640J-981D01*
G03X674486Y1569350I171J-104D01*
G01Y1566399D01*
G03X674515Y1566296I200J1D01*
G02Y1564334I-1640J-981D01*
G03X674486Y1564231I171J-104D01*
G01Y1563106D01*
G02X674284Y1562904I-202J0D01*
G01X671464D01*
G02X671262Y1563106I0J202D01*
G01Y1564231D01*
G03X671233Y1564334I-200J-1D01*
G02Y1566296I1640J981D01*
G03X671262Y1566399I-171J104D01*
G01Y1569350D01*
G03X671233Y1569453I-200J-1D01*
G02Y1571415I1640J981D01*
G03X671262Y1571518I-171J104D01*
G37*
G36*
G01X688584D02*
Y1572644D01*
G02X688787Y1572846I203J-1D01*
G01X691607D01*
G02X691810Y1572644I1J-202D01*
G01Y1571518D01*
G03X691838Y1571415I200J-1D01*
G02Y1569453I-1640J-981D01*
G03X691810Y1569350I172J-102D01*
G01Y1566399D01*
G03X691838Y1566296I200J-1D01*
G02Y1564334I-1640J-981D01*
G03X691810Y1564231I172J-102D01*
G01Y1563106D01*
G02X691607Y1562904I-203J1D01*
G01X688787D01*
G02X688584Y1563106I-1J202D01*
G01Y1564231D01*
G03X688556Y1564334I-200J1D01*
G02Y1566296I1640J981D01*
G03X688584Y1566399I-172J102D01*
G01Y1569350D01*
G03X688556Y1569453I-200J1D01*
G02Y1571415I1640J981D01*
G03X688584Y1571518I-172J102D01*
G37*
G36*
G01X1138898D02*
Y1572644D01*
G02X1139101Y1572846I203J-1D01*
G01X1141921D01*
G02X1142124Y1572644I1J-202D01*
G01Y1571518D01*
G03X1142152Y1571415I200J-1D01*
G02Y1569453I-1640J-981D01*
G03X1142124Y1569350I172J-102D01*
G01Y1566399D01*
G03X1142152Y1566296I200J-1D01*
G02Y1564334I-1640J-981D01*
G03X1142124Y1564231I172J-102D01*
G01Y1563106D01*
G02X1141921Y1562904I-203J1D01*
G01X1139101D01*
G02X1138898Y1563106I-1J202D01*
G01Y1564231D01*
G03X1138870Y1564334I-200J1D01*
G02Y1566296I1640J981D01*
G03X1138898Y1566399I-172J102D01*
G01Y1569350D01*
G03X1138870Y1569453I-200J1D01*
G02Y1571415I1640J981D01*
G03X1138898Y1571518I-172J102D01*
G37*
G36*
G01X1156222D02*
Y1572644D01*
G02X1156424Y1572846I202J0D01*
G01X1159244D01*
G02X1159446Y1572644I0J-202D01*
G01Y1571518D01*
G03X1159475Y1571415I200J1D01*
G02Y1569453I-1640J-981D01*
G03X1159446Y1569350I171J-104D01*
G01Y1566399D01*
G03X1159475Y1566296I200J1D01*
G02Y1564334I-1640J-981D01*
G03X1159446Y1564231I171J-104D01*
G01Y1563106D01*
G02X1159244Y1562904I-202J0D01*
G01X1156424D01*
G02X1156222Y1563106I0J202D01*
G01Y1564231D01*
G03X1156193Y1564334I-200J-1D01*
G02Y1566296I1640J981D01*
G03X1156222Y1566399I-171J104D01*
G01Y1569350D01*
G03X1156193Y1569453I-200J-1D01*
G02Y1571415I1640J981D01*
G03X1156222Y1571518I-171J104D01*
G37*
G36*
G01X1173544D02*
Y1572644D01*
G02X1173747Y1572846I203J-1D01*
G01X1176567D01*
G02X1176770Y1572644I1J-202D01*
G01Y1571518D01*
G03X1176798Y1571415I200J-1D01*
G02Y1569453I-1640J-981D01*
G03X1176770Y1569350I172J-102D01*
G01Y1566399D01*
G03X1176798Y1566296I200J-1D01*
G02Y1564334I-1640J-981D01*
G03X1176770Y1564231I172J-102D01*
G01Y1563106D01*
G02X1176567Y1562904I-203J1D01*
G01X1173747D01*
G02X1173544Y1563106I-1J202D01*
G01Y1564231D01*
G03X1173516Y1564334I-200J1D01*
G02Y1566296I1640J981D01*
G03X1173544Y1566399I-172J102D01*
G01Y1569350D01*
G03X1173516Y1569453I-200J1D01*
G02Y1571415I1640J981D01*
G03X1173544Y1571518I-172J102D01*
G37*
G36*
G01X1190868D02*
Y1572644D01*
G02X1191070Y1572846I202J0D01*
G01X1193890D01*
G02X1194092Y1572644I0J-202D01*
G01Y1571518D01*
G03X1194121Y1571415I200J1D01*
G02Y1569453I-1640J-981D01*
G03X1194092Y1569350I171J-104D01*
G01Y1566399D01*
G03X1194121Y1566296I200J1D01*
G02Y1564334I-1640J-981D01*
G03X1194092Y1564231I171J-104D01*
G01Y1563106D01*
G02X1193890Y1562904I-202J0D01*
G01X1191070D01*
G02X1190868Y1563106I0J202D01*
G01Y1564231D01*
G03X1190839Y1564334I-200J-1D01*
G02Y1566296I1640J981D01*
G03X1190868Y1566399I-171J104D01*
G01Y1569350D01*
G03X1190839Y1569453I-200J-1D01*
G02Y1571415I1640J981D01*
G03X1190868Y1571518I-171J104D01*
G37*
G36*
G01X627954Y1582541D02*
Y1583667D01*
G02X628157Y1583870I203J0D01*
G01X630977D01*
G02X631180Y1583667I0J-203D01*
G01Y1582541D01*
G03X631208Y1582438I200J-1D01*
G02Y1580476I-1640J-981D01*
G03X631180Y1580373I172J-102D01*
G01Y1577423D01*
G03X631208Y1577320I200J-1D01*
G02Y1575358I-1640J-981D01*
G03X631180Y1575255I172J-102D01*
G01Y1574129D01*
G02X630977Y1573926I-203J0D01*
G01X628157D01*
G02X627954Y1574129I0J203D01*
G01Y1575255D01*
G03X627926Y1575358I-200J1D01*
G02Y1577320I1640J981D01*
G03X627954Y1577423I-172J102D01*
G01Y1580373D01*
G03X627926Y1580476I-200J1D01*
G02Y1582438I1640J981D01*
G03X627954Y1582541I-172J102D01*
G37*
G36*
G01X645278D02*
Y1583667D01*
G02X645480Y1583870I202J1D01*
G01X648300D01*
G02X648502Y1583667I-1J-203D01*
G01Y1582541D01*
G03X648531Y1582438I200J1D01*
G02Y1580476I-1640J-981D01*
G03X648502Y1580373I171J-104D01*
G01Y1577423D01*
G03X648531Y1577320I200J1D01*
G02Y1575358I-1640J-981D01*
G03X648502Y1575255I171J-104D01*
G01Y1574129D01*
G02X648300Y1573926I-202J-1D01*
G01X645480D01*
G02X645278Y1574129I1J203D01*
G01Y1575255D01*
G03X645249Y1575358I-200J-1D01*
G02Y1577320I1640J981D01*
G03X645278Y1577423I-171J104D01*
G01Y1580373D01*
G03X645249Y1580476I-200J-1D01*
G02Y1582438I1640J981D01*
G03X645278Y1582541I-171J104D01*
G37*
G36*
G01X662600D02*
Y1583667D01*
G02X662803Y1583870I203J0D01*
G01X665623D01*
G02X665826Y1583667I0J-203D01*
G01Y1582541D01*
G03X665854Y1582438I200J-1D01*
G02Y1580476I-1640J-981D01*
G03X665826Y1580373I172J-102D01*
G01Y1577423D01*
G03X665854Y1577320I200J-1D01*
G02Y1575358I-1640J-981D01*
G03X665826Y1575255I172J-102D01*
G01Y1574129D01*
G02X665623Y1573926I-203J0D01*
G01X662803D01*
G02X662600Y1574129I0J203D01*
G01Y1575255D01*
G03X662572Y1575358I-200J1D01*
G02Y1577320I1640J981D01*
G03X662600Y1577423I-172J102D01*
G01Y1580373D01*
G03X662572Y1580476I-200J1D01*
G02Y1582438I1640J981D01*
G03X662600Y1582541I-172J102D01*
G37*
G36*
G01X679922D02*
Y1583667D01*
G02X680125Y1583870I203J0D01*
G01X682945D01*
G02X683148Y1583667I0J-203D01*
G01Y1582541D01*
G03X683176Y1582438I200J-1D01*
G02Y1580476I-1640J-981D01*
G03X683148Y1580373I172J-102D01*
G01Y1577423D01*
G03X683176Y1577320I200J-1D01*
G02Y1575358I-1640J-981D01*
G03X683148Y1575255I172J-102D01*
G01Y1574129D01*
G02X682945Y1573926I-203J0D01*
G01X680125D01*
G02X679922Y1574129I0J203D01*
G01Y1575255D01*
G03X679894Y1575358I-200J1D01*
G02Y1577320I1640J981D01*
G03X679922Y1577423I-172J102D01*
G01Y1580373D01*
G03X679894Y1580476I-200J1D01*
G02Y1582438I1640J981D01*
G03X679922Y1582541I-172J102D01*
G37*
G36*
G01X1130238D02*
Y1583667D01*
G02X1130440Y1583870I202J1D01*
G01X1133260D01*
G02X1133462Y1583667I-1J-203D01*
G01Y1582541D01*
G03X1133491Y1582438I200J1D01*
G02Y1580476I-1640J-981D01*
G03X1133462Y1580373I171J-104D01*
G01Y1577423D01*
G03X1133491Y1577320I200J1D01*
G02Y1575358I-1640J-981D01*
G03X1133462Y1575255I171J-104D01*
G01Y1574129D01*
G02X1133260Y1573926I-202J-1D01*
G01X1130440D01*
G02X1130238Y1574129I1J203D01*
G01Y1575255D01*
G03X1130209Y1575358I-200J-1D01*
G02Y1577320I1640J981D01*
G03X1130238Y1577423I-171J104D01*
G01Y1580373D01*
G03X1130209Y1580476I-200J-1D01*
G02Y1582438I1640J981D01*
G03X1130238Y1582541I-171J104D01*
G37*
G36*
G01X1147560D02*
Y1583667D01*
G02X1147763Y1583870I203J0D01*
G01X1150583D01*
G02X1150786Y1583667I0J-203D01*
G01Y1582541D01*
G03X1150814Y1582438I200J-1D01*
G02Y1580476I-1640J-981D01*
G03X1150786Y1580373I172J-102D01*
G01Y1577423D01*
G03X1150814Y1577320I200J-1D01*
G02Y1575358I-1640J-981D01*
G03X1150786Y1575255I172J-102D01*
G01Y1574129D01*
G02X1150583Y1573926I-203J0D01*
G01X1147763D01*
G02X1147560Y1574129I0J203D01*
G01Y1575255D01*
G03X1147532Y1575358I-200J1D01*
G02Y1577320I1640J981D01*
G03X1147560Y1577423I-172J102D01*
G01Y1580373D01*
G03X1147532Y1580476I-200J1D01*
G02Y1582438I1640J981D01*
G03X1147560Y1582541I-172J102D01*
G37*
G36*
G01X1164884D02*
Y1583667D01*
G02X1165086Y1583870I202J1D01*
G01X1167906D01*
G02X1168108Y1583667I-1J-203D01*
G01Y1582541D01*
G03X1168137Y1582438I200J1D01*
G02Y1580476I-1640J-981D01*
G03X1168108Y1580373I171J-104D01*
G01Y1577423D01*
G03X1168137Y1577320I200J1D01*
G02Y1575358I-1640J-981D01*
G03X1168108Y1575255I171J-104D01*
G01Y1574129D01*
G02X1167906Y1573926I-202J-1D01*
G01X1165086D01*
G02X1164884Y1574129I1J203D01*
G01Y1575255D01*
G03X1164855Y1575358I-200J-1D01*
G02Y1577320I1640J981D01*
G03X1164884Y1577423I-171J104D01*
G01Y1580373D01*
G03X1164855Y1580476I-200J-1D01*
G02Y1582438I1640J981D01*
G03X1164884Y1582541I-171J104D01*
G37*
G36*
G01X1182206D02*
Y1583667D01*
G02X1182408Y1583870I202J1D01*
G01X1185228D01*
G02X1185430Y1583667I-1J-203D01*
G01Y1582541D01*
G03X1185459Y1582438I200J1D01*
G02Y1580476I-1640J-981D01*
G03X1185430Y1580373I171J-104D01*
G01Y1577423D01*
G03X1185459Y1577320I200J1D01*
G02Y1575358I-1640J-981D01*
G03X1185430Y1575255I171J-104D01*
G01Y1574129D01*
G02X1185228Y1573926I-202J-1D01*
G01X1182408D01*
G02X1182206Y1574129I1J203D01*
G01Y1575255D01*
G03X1182177Y1575358I-200J-1D01*
G02Y1577320I1640J981D01*
G03X1182206Y1577423I-171J104D01*
G01Y1580373D01*
G03X1182177Y1580476I-200J-1D01*
G02Y1582438I1640J981D01*
G03X1182206Y1582541I-171J104D01*
G37*
G36*
G01X636616Y1586872D02*
Y1587998D01*
G02X636818Y1588200I202J0D01*
G01X639638D01*
G02X639840Y1587998I0J-202D01*
G01Y1586872D01*
G03X639869Y1586769I200J1D01*
G02Y1584807I-1640J-981D01*
G03X639840Y1584704I171J-104D01*
G01Y1581754D01*
G03X639869Y1581651I200J1D01*
G02Y1579689I-1640J-981D01*
G03X639840Y1579586I171J-104D01*
G01Y1578460D01*
G02X639638Y1578258I-202J0D01*
G01X636818D01*
G02X636616Y1578460I0J202D01*
G01Y1579586D01*
G03X636587Y1579689I-200J-1D01*
G02Y1581651I1640J981D01*
G03X636616Y1581754I-171J104D01*
G01Y1584704D01*
G03X636587Y1584807I-200J-1D01*
G02Y1586769I1640J981D01*
G03X636616Y1586872I-171J104D01*
G37*
G36*
G01X653938D02*
Y1587998D01*
G02X654141Y1588200I203J-1D01*
G01X656961D01*
G02X657164Y1587998I1J-202D01*
G01Y1586872D01*
G03X657192Y1586769I200J-1D01*
G02Y1584807I-1640J-981D01*
G03X657164Y1584704I172J-102D01*
G01Y1581754D01*
G03X657192Y1581651I200J-1D01*
G02Y1579689I-1640J-981D01*
G03X657164Y1579586I172J-102D01*
G01Y1578460D01*
G02X656961Y1578258I-203J1D01*
G01X654141D01*
G02X653938Y1578460I-1J202D01*
G01Y1579586D01*
G03X653910Y1579689I-200J1D01*
G02Y1581651I1640J981D01*
G03X653938Y1581754I-172J102D01*
G01Y1584704D01*
G03X653910Y1584807I-200J1D01*
G02Y1586769I1640J981D01*
G03X653938Y1586872I-172J102D01*
G37*
G36*
G01X671262D02*
Y1587998D01*
G02X671464Y1588200I202J0D01*
G01X674284D01*
G02X674486Y1587998I0J-202D01*
G01Y1586872D01*
G03X674515Y1586769I200J1D01*
G02Y1584807I-1640J-981D01*
G03X674486Y1584704I171J-104D01*
G01Y1581754D01*
G03X674515Y1581651I200J1D01*
G02Y1579689I-1640J-981D01*
G03X674486Y1579586I171J-104D01*
G01Y1578460D01*
G02X674284Y1578258I-202J0D01*
G01X671464D01*
G02X671262Y1578460I0J202D01*
G01Y1579586D01*
G03X671233Y1579689I-200J-1D01*
G02Y1581651I1640J981D01*
G03X671262Y1581754I-171J104D01*
G01Y1584704D01*
G03X671233Y1584807I-200J-1D01*
G02Y1586769I1640J981D01*
G03X671262Y1586872I-171J104D01*
G37*
G36*
G01X688584D02*
Y1587998D01*
G02X688787Y1588200I203J-1D01*
G01X691607D01*
G02X691810Y1587998I1J-202D01*
G01Y1586872D01*
G03X691838Y1586769I200J-1D01*
G02Y1584807I-1640J-981D01*
G03X691810Y1584704I172J-102D01*
G01Y1581754D01*
G03X691838Y1581651I200J-1D01*
G02Y1579689I-1640J-981D01*
G03X691810Y1579586I172J-102D01*
G01Y1578460D01*
G02X691607Y1578258I-203J1D01*
G01X688787D01*
G02X688584Y1578460I-1J202D01*
G01Y1579586D01*
G03X688556Y1579689I-200J1D01*
G02Y1581651I1640J981D01*
G03X688584Y1581754I-172J102D01*
G01Y1584704D01*
G03X688556Y1584807I-200J1D01*
G02Y1586769I1640J981D01*
G03X688584Y1586872I-172J102D01*
G37*
G36*
G01X1138898D02*
Y1587998D01*
G02X1139101Y1588200I203J-1D01*
G01X1141921D01*
G02X1142124Y1587998I1J-202D01*
G01Y1586872D01*
G03X1142152Y1586769I200J-1D01*
G02Y1584807I-1640J-981D01*
G03X1142124Y1584704I172J-102D01*
G01Y1581754D01*
G03X1142152Y1581651I200J-1D01*
G02Y1579689I-1640J-981D01*
G03X1142124Y1579586I172J-102D01*
G01Y1578460D01*
G02X1141921Y1578258I-203J1D01*
G01X1139101D01*
G02X1138898Y1578460I-1J202D01*
G01Y1579586D01*
G03X1138870Y1579689I-200J1D01*
G02Y1581651I1640J981D01*
G03X1138898Y1581754I-172J102D01*
G01Y1584704D01*
G03X1138870Y1584807I-200J1D01*
G02Y1586769I1640J981D01*
G03X1138898Y1586872I-172J102D01*
G37*
G36*
G01X1156222D02*
Y1587998D01*
G02X1156424Y1588200I202J0D01*
G01X1159244D01*
G02X1159446Y1587998I0J-202D01*
G01Y1586872D01*
G03X1159475Y1586769I200J1D01*
G02Y1584807I-1640J-981D01*
G03X1159446Y1584704I171J-104D01*
G01Y1581754D01*
G03X1159475Y1581651I200J1D01*
G02Y1579689I-1640J-981D01*
G03X1159446Y1579586I171J-104D01*
G01Y1578460D01*
G02X1159244Y1578258I-202J0D01*
G01X1156424D01*
G02X1156222Y1578460I0J202D01*
G01Y1579586D01*
G03X1156193Y1579689I-200J-1D01*
G02Y1581651I1640J981D01*
G03X1156222Y1581754I-171J104D01*
G01Y1584704D01*
G03X1156193Y1584807I-200J-1D01*
G02Y1586769I1640J981D01*
G03X1156222Y1586872I-171J104D01*
G37*
G36*
G01X1173544D02*
Y1587998D01*
G02X1173747Y1588200I203J-1D01*
G01X1176567D01*
G02X1176770Y1587998I1J-202D01*
G01Y1586872D01*
G03X1176798Y1586769I200J-1D01*
G02Y1584807I-1640J-981D01*
G03X1176770Y1584704I172J-102D01*
G01Y1581754D01*
G03X1176798Y1581651I200J-1D01*
G02Y1579689I-1640J-981D01*
G03X1176770Y1579586I172J-102D01*
G01Y1578460D01*
G02X1176567Y1578258I-203J1D01*
G01X1173747D01*
G02X1173544Y1578460I-1J202D01*
G01Y1579586D01*
G03X1173516Y1579689I-200J1D01*
G02Y1581651I1640J981D01*
G03X1173544Y1581754I-172J102D01*
G01Y1584704D01*
G03X1173516Y1584807I-200J1D01*
G02Y1586769I1640J981D01*
G03X1173544Y1586872I-172J102D01*
G37*
G36*
G01X1190868D02*
Y1587998D01*
G02X1191070Y1588200I202J0D01*
G01X1193890D01*
G02X1194092Y1587998I0J-202D01*
G01Y1586872D01*
G03X1194121Y1586769I200J1D01*
G02Y1584807I-1640J-981D01*
G03X1194092Y1584704I171J-104D01*
G01Y1581754D01*
G03X1194121Y1581651I200J1D01*
G02Y1579689I-1640J-981D01*
G03X1194092Y1579586I171J-104D01*
G01Y1578460D01*
G02X1193890Y1578258I-202J0D01*
G01X1191070D01*
G02X1190868Y1578460I0J202D01*
G01Y1579586D01*
G03X1190839Y1579689I-200J-1D01*
G02Y1581651I1640J981D01*
G03X1190868Y1581754I-171J104D01*
G01Y1584704D01*
G03X1190839Y1584807I-200J-1D01*
G02Y1586769I1640J981D01*
G03X1190868Y1586872I-171J104D01*
G37*
G36*
G01X627954Y1597895D02*
Y1599021D01*
G02X628157Y1599224I203J0D01*
G01X630977D01*
G02X631180Y1599021I0J-203D01*
G01Y1597895D01*
G03X631208Y1597792I200J-1D01*
G02Y1595830I-1640J-981D01*
G03X631180Y1595727I172J-102D01*
G01Y1592777D01*
G03X631208Y1592674I200J-1D01*
G02Y1590712I-1640J-981D01*
G03X631180Y1590609I172J-102D01*
G01Y1589483D01*
G02X630977Y1589280I-203J0D01*
G01X628157D01*
G02X627954Y1589483I0J203D01*
G01Y1590609D01*
G03X627926Y1590712I-200J1D01*
G02Y1592674I1640J981D01*
G03X627954Y1592777I-172J102D01*
G01Y1595727D01*
G03X627926Y1595830I-200J1D01*
G02Y1597792I1640J981D01*
G03X627954Y1597895I-172J102D01*
G37*
G36*
G01X645278D02*
Y1599021D01*
G02X645480Y1599224I202J1D01*
G01X648300D01*
G02X648502Y1599021I-1J-203D01*
G01Y1597895D01*
G03X648531Y1597792I200J1D01*
G02Y1595830I-1640J-981D01*
G03X648502Y1595727I171J-104D01*
G01Y1592777D01*
G03X648531Y1592674I200J1D01*
G02Y1590712I-1640J-981D01*
G03X648502Y1590609I171J-104D01*
G01Y1589483D01*
G02X648300Y1589280I-202J-1D01*
G01X645480D01*
G02X645278Y1589483I1J203D01*
G01Y1590609D01*
G03X645249Y1590712I-200J-1D01*
G02Y1592674I1640J981D01*
G03X645278Y1592777I-171J104D01*
G01Y1595727D01*
G03X645249Y1595830I-200J-1D01*
G02Y1597792I1640J981D01*
G03X645278Y1597895I-171J104D01*
G37*
G36*
G01X662600D02*
Y1599021D01*
G02X662803Y1599224I203J0D01*
G01X665623D01*
G02X665826Y1599021I0J-203D01*
G01Y1597895D01*
G03X665854Y1597792I200J-1D01*
G02Y1595830I-1640J-981D01*
G03X665826Y1595727I172J-102D01*
G01Y1592777D01*
G03X665854Y1592674I200J-1D01*
G02Y1590712I-1640J-981D01*
G03X665826Y1590609I172J-102D01*
G01Y1589483D01*
G02X665623Y1589280I-203J0D01*
G01X662803D01*
G02X662600Y1589483I0J203D01*
G01Y1590609D01*
G03X662572Y1590712I-200J1D01*
G02Y1592674I1640J981D01*
G03X662600Y1592777I-172J102D01*
G01Y1595727D01*
G03X662572Y1595830I-200J1D01*
G02Y1597792I1640J981D01*
G03X662600Y1597895I-172J102D01*
G37*
G36*
G01X679922D02*
Y1599021D01*
G02X680125Y1599224I203J0D01*
G01X682945D01*
G02X683148Y1599021I0J-203D01*
G01Y1597895D01*
G03X683176Y1597792I200J-1D01*
G02Y1595830I-1640J-981D01*
G03X683148Y1595727I172J-102D01*
G01Y1592777D01*
G03X683176Y1592674I200J-1D01*
G02Y1590712I-1640J-981D01*
G03X683148Y1590609I172J-102D01*
G01Y1589483D01*
G02X682945Y1589280I-203J0D01*
G01X680125D01*
G02X679922Y1589483I0J203D01*
G01Y1590609D01*
G03X679894Y1590712I-200J1D01*
G02Y1592674I1640J981D01*
G03X679922Y1592777I-172J102D01*
G01Y1595727D01*
G03X679894Y1595830I-200J1D01*
G02Y1597792I1640J981D01*
G03X679922Y1597895I-172J102D01*
G37*
G36*
G01X1130238D02*
Y1599021D01*
G02X1130440Y1599224I202J1D01*
G01X1133260D01*
G02X1133462Y1599021I-1J-203D01*
G01Y1597895D01*
G03X1133491Y1597792I200J1D01*
G02Y1595830I-1640J-981D01*
G03X1133462Y1595727I171J-104D01*
G01Y1592777D01*
G03X1133491Y1592674I200J1D01*
G02Y1590712I-1640J-981D01*
G03X1133462Y1590609I171J-104D01*
G01Y1589483D01*
G02X1133260Y1589280I-202J-1D01*
G01X1130440D01*
G02X1130238Y1589483I1J203D01*
G01Y1590609D01*
G03X1130209Y1590712I-200J-1D01*
G02Y1592674I1640J981D01*
G03X1130238Y1592777I-171J104D01*
G01Y1595727D01*
G03X1130209Y1595830I-200J-1D01*
G02Y1597792I1640J981D01*
G03X1130238Y1597895I-171J104D01*
G37*
G36*
G01X1147560D02*
Y1599021D01*
G02X1147763Y1599224I203J0D01*
G01X1150583D01*
G02X1150786Y1599021I0J-203D01*
G01Y1597895D01*
G03X1150814Y1597792I200J-1D01*
G02Y1595830I-1640J-981D01*
G03X1150786Y1595727I172J-102D01*
G01Y1592777D01*
G03X1150814Y1592674I200J-1D01*
G02Y1590712I-1640J-981D01*
G03X1150786Y1590609I172J-102D01*
G01Y1589483D01*
G02X1150583Y1589280I-203J0D01*
G01X1147763D01*
G02X1147560Y1589483I0J203D01*
G01Y1590609D01*
G03X1147532Y1590712I-200J1D01*
G02Y1592674I1640J981D01*
G03X1147560Y1592777I-172J102D01*
G01Y1595727D01*
G03X1147532Y1595830I-200J1D01*
G02Y1597792I1640J981D01*
G03X1147560Y1597895I-172J102D01*
G37*
G36*
G01X1164884D02*
Y1599021D01*
G02X1165086Y1599224I202J1D01*
G01X1167906D01*
G02X1168108Y1599021I-1J-203D01*
G01Y1597895D01*
G03X1168137Y1597792I200J1D01*
G02Y1595830I-1640J-981D01*
G03X1168108Y1595727I171J-104D01*
G01Y1592777D01*
G03X1168137Y1592674I200J1D01*
G02Y1590712I-1640J-981D01*
G03X1168108Y1590609I171J-104D01*
G01Y1589483D01*
G02X1167906Y1589280I-202J-1D01*
G01X1165086D01*
G02X1164884Y1589483I1J203D01*
G01Y1590609D01*
G03X1164855Y1590712I-200J-1D01*
G02Y1592674I1640J981D01*
G03X1164884Y1592777I-171J104D01*
G01Y1595727D01*
G03X1164855Y1595830I-200J-1D01*
G02Y1597792I1640J981D01*
G03X1164884Y1597895I-171J104D01*
G37*
G36*
G01X1182206D02*
Y1599021D01*
G02X1182408Y1599224I202J1D01*
G01X1185228D01*
G02X1185430Y1599021I-1J-203D01*
G01Y1597895D01*
G03X1185459Y1597792I200J1D01*
G02Y1595830I-1640J-981D01*
G03X1185430Y1595727I171J-104D01*
G01Y1592777D01*
G03X1185459Y1592674I200J1D01*
G02Y1590712I-1640J-981D01*
G03X1185430Y1590609I171J-104D01*
G01Y1589483D01*
G02X1185228Y1589280I-202J-1D01*
G01X1182408D01*
G02X1182206Y1589483I1J203D01*
G01Y1590609D01*
G03X1182177Y1590712I-200J-1D01*
G02Y1592674I1640J981D01*
G03X1182206Y1592777I-171J104D01*
G01Y1595727D01*
G03X1182177Y1595830I-200J-1D01*
G02Y1597792I1640J981D01*
G03X1182206Y1597895I-171J104D01*
G37*
G36*
G01X636616Y1602226D02*
Y1603352D01*
G02X636818Y1603554I202J0D01*
G01X639638D01*
G02X639840Y1603352I0J-202D01*
G01Y1602226D01*
G03X639869Y1602123I200J1D01*
G02Y1600161I-1640J-981D01*
G03X639840Y1600058I171J-104D01*
G01Y1597108D01*
G03X639869Y1597005I200J1D01*
G02Y1595043I-1640J-981D01*
G03X639840Y1594940I171J-104D01*
G01Y1593814D01*
G02X639638Y1593612I-202J0D01*
G01X636818D01*
G02X636616Y1593814I0J202D01*
G01Y1594940D01*
G03X636587Y1595043I-200J-1D01*
G02Y1597005I1640J981D01*
G03X636616Y1597108I-171J104D01*
G01Y1600058D01*
G03X636587Y1600161I-200J-1D01*
G02Y1602123I1640J981D01*
G03X636616Y1602226I-171J104D01*
G37*
G36*
G01X653938D02*
Y1603352D01*
G02X654141Y1603554I203J-1D01*
G01X656961D01*
G02X657164Y1603352I1J-202D01*
G01Y1602226D01*
G03X657192Y1602123I200J-1D01*
G02Y1600161I-1640J-981D01*
G03X657164Y1600058I172J-102D01*
G01Y1597108D01*
G03X657192Y1597005I200J-1D01*
G02Y1595043I-1640J-981D01*
G03X657164Y1594940I172J-102D01*
G01Y1593814D01*
G02X656961Y1593612I-203J1D01*
G01X654141D01*
G02X653938Y1593814I-1J202D01*
G01Y1594940D01*
G03X653910Y1595043I-200J1D01*
G02Y1597005I1640J981D01*
G03X653938Y1597108I-172J102D01*
G01Y1600058D01*
G03X653910Y1600161I-200J1D01*
G02Y1602123I1640J981D01*
G03X653938Y1602226I-172J102D01*
G37*
G36*
G01X671262D02*
Y1603352D01*
G02X671464Y1603554I202J0D01*
G01X674284D01*
G02X674486Y1603352I0J-202D01*
G01Y1602226D01*
G03X674515Y1602123I200J1D01*
G02Y1600161I-1640J-981D01*
G03X674486Y1600058I171J-104D01*
G01Y1597108D01*
G03X674515Y1597005I200J1D01*
G02Y1595043I-1640J-981D01*
G03X674486Y1594940I171J-104D01*
G01Y1593814D01*
G02X674284Y1593612I-202J0D01*
G01X671464D01*
G02X671262Y1593814I0J202D01*
G01Y1594940D01*
G03X671233Y1595043I-200J-1D01*
G02Y1597005I1640J981D01*
G03X671262Y1597108I-171J104D01*
G01Y1600058D01*
G03X671233Y1600161I-200J-1D01*
G02Y1602123I1640J981D01*
G03X671262Y1602226I-171J104D01*
G37*
G36*
G01X688584D02*
Y1603352D01*
G02X688787Y1603554I203J-1D01*
G01X691607D01*
G02X691810Y1603352I1J-202D01*
G01Y1602226D01*
G03X691838Y1602123I200J-1D01*
G02Y1600161I-1640J-981D01*
G03X691810Y1600058I172J-102D01*
G01Y1597108D01*
G03X691838Y1597005I200J-1D01*
G02Y1595043I-1640J-981D01*
G03X691810Y1594940I172J-102D01*
G01Y1593814D01*
G02X691607Y1593612I-203J1D01*
G01X688787D01*
G02X688584Y1593814I-1J202D01*
G01Y1594940D01*
G03X688556Y1595043I-200J1D01*
G02Y1597005I1640J981D01*
G03X688584Y1597108I-172J102D01*
G01Y1600058D01*
G03X688556Y1600161I-200J1D01*
G02Y1602123I1640J981D01*
G03X688584Y1602226I-172J102D01*
G37*
G36*
G01X1138898D02*
Y1603352D01*
G02X1139101Y1603554I203J-1D01*
G01X1141921D01*
G02X1142124Y1603352I1J-202D01*
G01Y1602226D01*
G03X1142152Y1602123I200J-1D01*
G02Y1600161I-1640J-981D01*
G03X1142124Y1600058I172J-102D01*
G01Y1597108D01*
G03X1142152Y1597005I200J-1D01*
G02Y1595043I-1640J-981D01*
G03X1142124Y1594940I172J-102D01*
G01Y1593814D01*
G02X1141921Y1593612I-203J1D01*
G01X1139101D01*
G02X1138898Y1593814I-1J202D01*
G01Y1594940D01*
G03X1138870Y1595043I-200J1D01*
G02Y1597005I1640J981D01*
G03X1138898Y1597108I-172J102D01*
G01Y1600058D01*
G03X1138870Y1600161I-200J1D01*
G02Y1602123I1640J981D01*
G03X1138898Y1602226I-172J102D01*
G37*
G36*
G01X1156222D02*
Y1603352D01*
G02X1156424Y1603554I202J0D01*
G01X1159244D01*
G02X1159446Y1603352I0J-202D01*
G01Y1602226D01*
G03X1159475Y1602123I200J1D01*
G02Y1600161I-1640J-981D01*
G03X1159446Y1600058I171J-104D01*
G01Y1597108D01*
G03X1159475Y1597005I200J1D01*
G02Y1595043I-1640J-981D01*
G03X1159446Y1594940I171J-104D01*
G01Y1593814D01*
G02X1159244Y1593612I-202J0D01*
G01X1156424D01*
G02X1156222Y1593814I0J202D01*
G01Y1594940D01*
G03X1156193Y1595043I-200J-1D01*
G02Y1597005I1640J981D01*
G03X1156222Y1597108I-171J104D01*
G01Y1600058D01*
G03X1156193Y1600161I-200J-1D01*
G02Y1602123I1640J981D01*
G03X1156222Y1602226I-171J104D01*
G37*
G36*
G01X1173544D02*
Y1603352D01*
G02X1173747Y1603554I203J-1D01*
G01X1176567D01*
G02X1176770Y1603352I1J-202D01*
G01Y1602226D01*
G03X1176798Y1602123I200J-1D01*
G02Y1600161I-1640J-981D01*
G03X1176770Y1600058I172J-102D01*
G01Y1597108D01*
G03X1176798Y1597005I200J-1D01*
G02Y1595043I-1640J-981D01*
G03X1176770Y1594940I172J-102D01*
G01Y1593814D01*
G02X1176567Y1593612I-203J1D01*
G01X1173747D01*
G02X1173544Y1593814I-1J202D01*
G01Y1594940D01*
G03X1173516Y1595043I-200J1D01*
G02Y1597005I1640J981D01*
G03X1173544Y1597108I-172J102D01*
G01Y1600058D01*
G03X1173516Y1600161I-200J1D01*
G02Y1602123I1640J981D01*
G03X1173544Y1602226I-172J102D01*
G37*
G36*
G01X1190868D02*
Y1603352D01*
G02X1191070Y1603554I202J0D01*
G01X1193890D01*
G02X1194092Y1603352I0J-202D01*
G01Y1602226D01*
G03X1194121Y1602123I200J1D01*
G02Y1600161I-1640J-981D01*
G03X1194092Y1600058I171J-104D01*
G01Y1597108D01*
G03X1194121Y1597005I200J1D01*
G02Y1595043I-1640J-981D01*
G03X1194092Y1594940I171J-104D01*
G01Y1593814D01*
G02X1193890Y1593612I-202J0D01*
G01X1191070D01*
G02X1190868Y1593814I0J202D01*
G01Y1594940D01*
G03X1190839Y1595043I-200J-1D01*
G02Y1597005I1640J981D01*
G03X1190868Y1597108I-171J104D01*
G01Y1600058D01*
G03X1190839Y1600161I-200J-1D01*
G02Y1602123I1640J981D01*
G03X1190868Y1602226I-171J104D01*
G37*
G36*
G01X627954Y1613250D02*
Y1614376D01*
G02X628157Y1614578I203J-1D01*
G01X630977D01*
G02X631180Y1614376I1J-202D01*
G01Y1613250D01*
G03X631208Y1613147I200J-1D01*
G02Y1611185I-1640J-981D01*
G03X631180Y1611082I172J-102D01*
G01Y1608132D01*
G03X631208Y1608029I200J-1D01*
G02Y1606067I-1640J-981D01*
G03X631180Y1605964I172J-102D01*
G01Y1604838D01*
G02X630977Y1604636I-203J1D01*
G01X628157D01*
G02X627954Y1604838I-1J202D01*
G01Y1605964D01*
G03X627926Y1606067I-200J1D01*
G02Y1608029I1640J981D01*
G03X627954Y1608132I-172J102D01*
G01Y1611082D01*
G03X627926Y1611185I-200J1D01*
G02Y1613147I1640J981D01*
G03X627954Y1613250I-172J102D01*
G37*
G36*
G01X645278D02*
Y1614376D01*
G02X645480Y1614578I202J0D01*
G01X648300D01*
G02X648502Y1614376I0J-202D01*
G01Y1613250D01*
G03X648531Y1613147I200J1D01*
G02Y1611185I-1640J-981D01*
G03X648502Y1611082I171J-104D01*
G01Y1608132D01*
G03X648531Y1608029I200J1D01*
G02Y1606067I-1640J-981D01*
G03X648502Y1605964I171J-104D01*
G01Y1604838D01*
G02X648300Y1604636I-202J0D01*
G01X645480D01*
G02X645278Y1604838I0J202D01*
G01Y1605964D01*
G03X645249Y1606067I-200J-1D01*
G02Y1608029I1640J981D01*
G03X645278Y1608132I-171J104D01*
G01Y1611082D01*
G03X645249Y1611185I-200J-1D01*
G02Y1613147I1640J981D01*
G03X645278Y1613250I-171J104D01*
G37*
G36*
G01X662600D02*
Y1614376D01*
G02X662803Y1614578I203J-1D01*
G01X665623D01*
G02X665826Y1614376I1J-202D01*
G01Y1613250D01*
G03X665854Y1613147I200J-1D01*
G02Y1611185I-1640J-981D01*
G03X665826Y1611082I172J-102D01*
G01Y1608132D01*
G03X665854Y1608029I200J-1D01*
G02Y1606067I-1640J-981D01*
G03X665826Y1605964I172J-102D01*
G01Y1604838D01*
G02X665623Y1604636I-203J1D01*
G01X662803D01*
G02X662600Y1604838I-1J202D01*
G01Y1605964D01*
G03X662572Y1606067I-200J1D01*
G02Y1608029I1640J981D01*
G03X662600Y1608132I-172J102D01*
G01Y1611082D01*
G03X662572Y1611185I-200J1D01*
G02Y1613147I1640J981D01*
G03X662600Y1613250I-172J102D01*
G37*
G36*
G01X679922D02*
Y1614376D01*
G02X680125Y1614578I203J-1D01*
G01X682945D01*
G02X683148Y1614376I1J-202D01*
G01Y1613250D01*
G03X683176Y1613147I200J-1D01*
G02Y1611185I-1640J-981D01*
G03X683148Y1611082I172J-102D01*
G01Y1608132D01*
G03X683176Y1608029I200J-1D01*
G02Y1606067I-1640J-981D01*
G03X683148Y1605964I172J-102D01*
G01Y1604838D01*
G02X682945Y1604636I-203J1D01*
G01X680125D01*
G02X679922Y1604838I-1J202D01*
G01Y1605964D01*
G03X679894Y1606067I-200J1D01*
G02Y1608029I1640J981D01*
G03X679922Y1608132I-172J102D01*
G01Y1611082D01*
G03X679894Y1611185I-200J1D01*
G02Y1613147I1640J981D01*
G03X679922Y1613250I-172J102D01*
G37*
G36*
G01X1130238D02*
Y1614376D01*
G02X1130440Y1614578I202J0D01*
G01X1133260D01*
G02X1133462Y1614376I0J-202D01*
G01Y1613250D01*
G03X1133491Y1613147I200J1D01*
G02Y1611185I-1640J-981D01*
G03X1133462Y1611082I171J-104D01*
G01Y1608132D01*
G03X1133491Y1608029I200J1D01*
G02Y1606067I-1640J-981D01*
G03X1133462Y1605964I171J-104D01*
G01Y1604838D01*
G02X1133260Y1604636I-202J0D01*
G01X1130440D01*
G02X1130238Y1604838I0J202D01*
G01Y1605964D01*
G03X1130209Y1606067I-200J-1D01*
G02Y1608029I1640J981D01*
G03X1130238Y1608132I-171J104D01*
G01Y1611082D01*
G03X1130209Y1611185I-200J-1D01*
G02Y1613147I1640J981D01*
G03X1130238Y1613250I-171J104D01*
G37*
G36*
G01X1147560D02*
Y1614376D01*
G02X1147763Y1614578I203J-1D01*
G01X1150583D01*
G02X1150786Y1614376I1J-202D01*
G01Y1613250D01*
G03X1150814Y1613147I200J-1D01*
G02Y1611185I-1640J-981D01*
G03X1150786Y1611082I172J-102D01*
G01Y1608132D01*
G03X1150814Y1608029I200J-1D01*
G02Y1606067I-1640J-981D01*
G03X1150786Y1605964I172J-102D01*
G01Y1604838D01*
G02X1150583Y1604636I-203J1D01*
G01X1147763D01*
G02X1147560Y1604838I-1J202D01*
G01Y1605964D01*
G03X1147532Y1606067I-200J1D01*
G02Y1608029I1640J981D01*
G03X1147560Y1608132I-172J102D01*
G01Y1611082D01*
G03X1147532Y1611185I-200J1D01*
G02Y1613147I1640J981D01*
G03X1147560Y1613250I-172J102D01*
G37*
G36*
G01X1164884D02*
Y1614376D01*
G02X1165086Y1614578I202J0D01*
G01X1167906D01*
G02X1168108Y1614376I0J-202D01*
G01Y1613250D01*
G03X1168137Y1613147I200J1D01*
G02Y1611185I-1640J-981D01*
G03X1168108Y1611082I171J-104D01*
G01Y1608132D01*
G03X1168137Y1608029I200J1D01*
G02Y1606067I-1640J-981D01*
G03X1168108Y1605964I171J-104D01*
G01Y1604838D01*
G02X1167906Y1604636I-202J0D01*
G01X1165086D01*
G02X1164884Y1604838I0J202D01*
G01Y1605964D01*
G03X1164855Y1606067I-200J-1D01*
G02Y1608029I1640J981D01*
G03X1164884Y1608132I-171J104D01*
G01Y1611082D01*
G03X1164855Y1611185I-200J-1D01*
G02Y1613147I1640J981D01*
G03X1164884Y1613250I-171J104D01*
G37*
G36*
G01X1182206D02*
Y1614376D01*
G02X1182408Y1614578I202J0D01*
G01X1185228D01*
G02X1185430Y1614376I0J-202D01*
G01Y1613250D01*
G03X1185459Y1613147I200J1D01*
G02Y1611185I-1640J-981D01*
G03X1185430Y1611082I171J-104D01*
G01Y1608132D01*
G03X1185459Y1608029I200J1D01*
G02Y1606067I-1640J-981D01*
G03X1185430Y1605964I171J-104D01*
G01Y1604838D01*
G02X1185228Y1604636I-202J0D01*
G01X1182408D01*
G02X1182206Y1604838I0J202D01*
G01Y1605964D01*
G03X1182177Y1606067I-200J-1D01*
G02Y1608029I1640J981D01*
G03X1182206Y1608132I-171J104D01*
G01Y1611082D01*
G03X1182177Y1611185I-200J-1D01*
G02Y1613147I1640J981D01*
G03X1182206Y1613250I-171J104D01*
G37*
G36*
G01X636616Y1617580D02*
Y1618706D01*
G02X636818Y1618908I202J0D01*
G01X639638D01*
G02X639840Y1618706I0J-202D01*
G01Y1617580D01*
G03X639869Y1617477I200J1D01*
G02Y1615515I-1640J-981D01*
G03X639840Y1615412I171J-104D01*
G01Y1612462D01*
G03X639869Y1612359I200J1D01*
G02Y1610397I-1640J-981D01*
G03X639840Y1610294I171J-104D01*
G01Y1609168D01*
G02X639638Y1608966I-202J0D01*
G01X636818D01*
G02X636616Y1609168I0J202D01*
G01Y1610294D01*
G03X636587Y1610397I-200J-1D01*
G02Y1612359I1640J981D01*
G03X636616Y1612462I-171J104D01*
G01Y1615412D01*
G03X636587Y1615515I-200J-1D01*
G02Y1617477I1640J981D01*
G03X636616Y1617580I-171J104D01*
G37*
G36*
G01X653938D02*
Y1618706D01*
G02X654141Y1618908I203J-1D01*
G01X656961D01*
G02X657164Y1618706I1J-202D01*
G01Y1617580D01*
G03X657192Y1617477I200J-1D01*
G02Y1615515I-1640J-981D01*
G03X657164Y1615412I172J-102D01*
G01Y1612462D01*
G03X657192Y1612359I200J-1D01*
G02Y1610397I-1640J-981D01*
G03X657164Y1610294I172J-102D01*
G01Y1609168D01*
G02X656961Y1608966I-203J1D01*
G01X654141D01*
G02X653938Y1609168I-1J202D01*
G01Y1610294D01*
G03X653910Y1610397I-200J1D01*
G02Y1612359I1640J981D01*
G03X653938Y1612462I-172J102D01*
G01Y1615412D01*
G03X653910Y1615515I-200J1D01*
G02Y1617477I1640J981D01*
G03X653938Y1617580I-172J102D01*
G37*
G36*
G01X671262D02*
Y1618706D01*
G02X671464Y1618908I202J0D01*
G01X674284D01*
G02X674486Y1618706I0J-202D01*
G01Y1617580D01*
G03X674515Y1617477I200J1D01*
G02Y1615515I-1640J-981D01*
G03X674486Y1615412I171J-104D01*
G01Y1612462D01*
G03X674515Y1612359I200J1D01*
G02Y1610397I-1640J-981D01*
G03X674486Y1610294I171J-104D01*
G01Y1609168D01*
G02X674284Y1608966I-202J0D01*
G01X671464D01*
G02X671262Y1609168I0J202D01*
G01Y1610294D01*
G03X671233Y1610397I-200J-1D01*
G02Y1612359I1640J981D01*
G03X671262Y1612462I-171J104D01*
G01Y1615412D01*
G03X671233Y1615515I-200J-1D01*
G02Y1617477I1640J981D01*
G03X671262Y1617580I-171J104D01*
G37*
G36*
G01X688584D02*
Y1618706D01*
G02X688787Y1618908I203J-1D01*
G01X691607D01*
G02X691810Y1618706I1J-202D01*
G01Y1617580D01*
G03X691838Y1617477I200J-1D01*
G02Y1615515I-1640J-981D01*
G03X691810Y1615412I172J-102D01*
G01Y1612462D01*
G03X691838Y1612359I200J-1D01*
G02Y1610397I-1640J-981D01*
G03X691810Y1610294I172J-102D01*
G01Y1609168D01*
G02X691607Y1608966I-203J1D01*
G01X688787D01*
G02X688584Y1609168I-1J202D01*
G01Y1610294D01*
G03X688556Y1610397I-200J1D01*
G02Y1612359I1640J981D01*
G03X688584Y1612462I-172J102D01*
G01Y1615412D01*
G03X688556Y1615515I-200J1D01*
G02Y1617477I1640J981D01*
G03X688584Y1617580I-172J102D01*
G37*
G36*
G01X1138898D02*
Y1618706D01*
G02X1139101Y1618908I203J-1D01*
G01X1141921D01*
G02X1142124Y1618706I1J-202D01*
G01Y1617580D01*
G03X1142152Y1617477I200J-1D01*
G02Y1615515I-1640J-981D01*
G03X1142124Y1615412I172J-102D01*
G01Y1612462D01*
G03X1142152Y1612359I200J-1D01*
G02Y1610397I-1640J-981D01*
G03X1142124Y1610294I172J-102D01*
G01Y1609168D01*
G02X1141921Y1608966I-203J1D01*
G01X1139101D01*
G02X1138898Y1609168I-1J202D01*
G01Y1610294D01*
G03X1138870Y1610397I-200J1D01*
G02Y1612359I1640J981D01*
G03X1138898Y1612462I-172J102D01*
G01Y1615412D01*
G03X1138870Y1615515I-200J1D01*
G02Y1617477I1640J981D01*
G03X1138898Y1617580I-172J102D01*
G37*
G36*
G01X1156222D02*
Y1618706D01*
G02X1156424Y1618908I202J0D01*
G01X1159244D01*
G02X1159446Y1618706I0J-202D01*
G01Y1617580D01*
G03X1159475Y1617477I200J1D01*
G02Y1615515I-1640J-981D01*
G03X1159446Y1615412I171J-104D01*
G01Y1612462D01*
G03X1159475Y1612359I200J1D01*
G02Y1610397I-1640J-981D01*
G03X1159446Y1610294I171J-104D01*
G01Y1609168D01*
G02X1159244Y1608966I-202J0D01*
G01X1156424D01*
G02X1156222Y1609168I0J202D01*
G01Y1610294D01*
G03X1156193Y1610397I-200J-1D01*
G02Y1612359I1640J981D01*
G03X1156222Y1612462I-171J104D01*
G01Y1615412D01*
G03X1156193Y1615515I-200J-1D01*
G02Y1617477I1640J981D01*
G03X1156222Y1617580I-171J104D01*
G37*
G36*
G01X1173544D02*
Y1618706D01*
G02X1173747Y1618908I203J-1D01*
G01X1176567D01*
G02X1176770Y1618706I1J-202D01*
G01Y1617580D01*
G03X1176798Y1617477I200J-1D01*
G02Y1615515I-1640J-981D01*
G03X1176770Y1615412I172J-102D01*
G01Y1612462D01*
G03X1176798Y1612359I200J-1D01*
G02Y1610397I-1640J-981D01*
G03X1176770Y1610294I172J-102D01*
G01Y1609168D01*
G02X1176567Y1608966I-203J1D01*
G01X1173747D01*
G02X1173544Y1609168I-1J202D01*
G01Y1610294D01*
G03X1173516Y1610397I-200J1D01*
G02Y1612359I1640J981D01*
G03X1173544Y1612462I-172J102D01*
G01Y1615412D01*
G03X1173516Y1615515I-200J1D01*
G02Y1617477I1640J981D01*
G03X1173544Y1617580I-172J102D01*
G37*
G36*
G01X1190868D02*
Y1618706D01*
G02X1191070Y1618908I202J0D01*
G01X1193890D01*
G02X1194092Y1618706I0J-202D01*
G01Y1617580D01*
G03X1194121Y1617477I200J1D01*
G02Y1615515I-1640J-981D01*
G03X1194092Y1615412I171J-104D01*
G01Y1612462D01*
G03X1194121Y1612359I200J1D01*
G02Y1610397I-1640J-981D01*
G03X1194092Y1610294I171J-104D01*
G01Y1609168D01*
G02X1193890Y1608966I-202J0D01*
G01X1191070D01*
G02X1190868Y1609168I0J202D01*
G01Y1610294D01*
G03X1190839Y1610397I-200J-1D01*
G02Y1612359I1640J981D01*
G03X1190868Y1612462I-171J104D01*
G01Y1615412D01*
G03X1190839Y1615515I-200J-1D01*
G02Y1617477I1640J981D01*
G03X1190868Y1617580I-171J104D01*
G37*
G36*
G01X1049510Y1223444D02*
G02X1049103Y1224472I1095J1028D01*
G02X1052107I1502J0D01*
G02X1051167Y1223079I-1502J0D01*
G03X1051025Y1222435I150J-371D01*
G02X1051432Y1221407I-1095J-1028D01*
G02X1048428I-1502J0D01*
G02X1049368Y1222800I1502J0D01*
G03X1049510Y1223444I-150J371D01*
G37*
G36*
G01X1048775Y1349375D02*
G02X1047991Y1350694I718J1319D01*
G02X1050995I1502J0D01*
G02X1050351Y1349461I-1502J0D01*
G03X1050388Y1348781I228J-329D01*
G02X1051172Y1347462I-718J-1319D01*
G02X1048168I-1502J0D01*
G02X1048812Y1348695I1502J0D01*
G03X1048775Y1349375I-228J329D01*
G37*
G36*
G01X979288Y1388101D02*
G02X978590Y1389370I805J1269D01*
G02X981594I1502J0D01*
G02X980820Y1388056I-1502J0D01*
G03X980800Y1387369I194J-349D01*
G02X981498Y1386100I-805J-1269D01*
G02X978494I-1502J0D01*
G02X979268Y1387414I1502J0D01*
G03X979288Y1388101I-194J349D01*
G37*
G36*
G01X950339Y1408056D02*
G02X950239Y1408053I-95J1499D01*
G02X951741Y1409555I0J1502D01*
G02X951672Y1409105I-1502J0D01*
G03X952080Y1408586I381J-120D01*
G02X952180Y1408589I95J-1499D01*
G02X950678Y1407087I0J-1502D01*
G02X950747Y1407537I1502J0D01*
G03X950339Y1408056I-381J120D01*
G37*
G36*
G01X767069Y1436719D02*
G02X765713Y1435863I-1356J646D01*
G02Y1438867I0J1502D01*
G02X766882Y1438308I0J-1502D01*
G03X767554Y1438387I311J251D01*
G02X768910Y1439243I1356J-646D01*
G02Y1436239I0J-1502D01*
G02X767741Y1436798I0J1502D01*
G03X767069Y1436719I-311J-251D01*
G37*
G36*
G01X815013Y1621877D02*
X821583Y1628447D01*
G02X821725Y1628506I142J-141D01*
G01X928532D01*
G02X928674Y1628447I0J-200D01*
G01X934334Y1622787D01*
G02X934392Y1622645I-142J-141D01*
G01Y1586563D01*
G03X934451Y1586421I200J0D01*
G01X941326Y1579546D01*
G03X941468Y1579488I141J142D01*
G01X957195D01*
G02X957337Y1579429I0J-200D01*
G01X962092Y1574674D01*
G02X962150Y1574532I-142J-141D01*
G01Y1565954D01*
G03X962274Y1565770I200J1D01*
G01X962331Y1565746D01*
X962448Y1565770D01*
X964406Y1567727D01*
G02X964547Y1567786I142J-141D01*
G01X994238D01*
G02X994379Y1567727I-1J-200D01*
G01X996799Y1565307D01*
G02X996858Y1565166I-141J-142D01*
G01Y1546676D01*
G02X996799Y1546535I-200J1D01*
G01X994317Y1544053D01*
G02X994176Y1543994I-142J141D01*
G01X964878D01*
G02X964737Y1544053I1J200D01*
G01X962492Y1546298D01*
G03X962274Y1546341I-141J-142D01*
G01X962217Y1546318D01*
X962150Y1546218D01*
Y1546053D01*
G03X962209Y1545911I200J0D01*
G01X962224Y1545897D01*
Y1544019D01*
G03X962282Y1543877I200J-1D01*
G01X965514Y1540645D01*
G03X965656Y1540586I142J141D01*
G01X1020880D01*
G02X1021022Y1540528I1J-200D01*
G01X1033738Y1527812D01*
G02X1033796Y1527670I-142J-141D01*
G01Y1492032D01*
G03X1033855Y1491891I200J1D01*
G01X1037492Y1488254D01*
G03X1037633Y1488196I141J142D01*
G01X1039911D01*
G02X1040109Y1488019I-1J-200D01*
G01X1040193Y1487313D01*
G03X1050152Y1468206I30229J3607D01*
G01Y1443535D01*
G02X1050093Y1443393I-200J0D01*
G01X1049400Y1442700D01*
G03Y1442417I142J-141D01*
G01X1050621Y1441197D01*
G02X1050680Y1441055I-141J-142D01*
G01Y1425040D01*
G02X1050621Y1424898I-200J0D01*
G01X1046513Y1420790D01*
G02X1046371Y1420732I-141J142D01*
G01X1032396D01*
G03X1032254Y1420673I0J-200D01*
G01X1031585Y1420004D01*
G03X1031526Y1419862I141J-142D01*
G01Y1405291D01*
G02X1031468Y1405149I-200J-1D01*
G01X1029473Y1403154D01*
G02X1029331Y1403096I-141J142D01*
G01X996298D01*
G02X996156Y1403154I-1J200D01*
G01X993903Y1405407D01*
G02X993844Y1405549I141J142D01*
G01Y1410736D01*
G03X993786Y1410878I-200J1D01*
G01X990283Y1414381D01*
G03X990141Y1414440I-142J-141D01*
G01X970816D01*
G02X970674Y1414498I-1J200D01*
G01X966718Y1418455D01*
G03X966576Y1418514I-142J-141D01*
G01X934386D01*
X934377Y1418522D01*
X934344D01*
X932979Y1419888D01*
G03X932761Y1419931I-141J-142D01*
G01X932704Y1419908D01*
X932638Y1419808D01*
Y1412495D01*
G02X932373Y1411745I-1201J3D01*
G01Y1411744D01*
G02X932291Y1411651I-941J747D01*
G01X932160Y1411521D01*
X932159Y1411520D01*
X931440Y1410801D01*
X929764Y1409124D01*
G03X929761Y1409122I107J-164D01*
G01X929620Y1408975D01*
G02X929549Y1408928I-143J140D01*
G01X929354Y1408851D01*
X929353D01*
G02X928908Y1408764I-449J1114D01*
G01X796029D01*
G02X794844Y1409417I0J1402D01*
G03X794675Y1409511I-170J-106D01*
G01X794337D01*
G03X794168Y1409417I1J-200D01*
G02X792983Y1408764I-1185J749D01*
G01X785414D01*
G02X784464Y1409138I3J1401D01*
G02X784462Y1409139I85J172D01*
G02X784454Y1409147I845J853D01*
G03X784452Y1409149I-142J-140D01*
G02X784242Y1409401I964J1017D01*
G03X784241Y1409403I-179J-88D01*
G02X784194Y1409479I998J670D01*
G02X784158Y1409548I1224J682D01*
G02X783694Y1409475I-463J1429D01*
G02X783230Y1409548I-1J1502D01*
G02X783194Y1409479I-1260J613D01*
G02X783147Y1409403I-1045J594D01*
G03X783146Y1409401I178J-90D01*
G02X782936Y1409149I-1174J765D01*
G03X782934Y1409147I140J-142D01*
G02X782926Y1409139I-853J845D01*
G02X782924Y1409138I-87J171D01*
G02X781974Y1408764I-953J1027D01*
G01X776344D01*
G02X775594Y1409029I3J1201D01*
G01X775593D01*
G02X775500Y1409111I747J941D01*
G01X773600Y1411011D01*
G03X773598Y1411014I-164J-107D01*
G01X773451Y1411155D01*
G02X773404Y1411226I140J143D01*
G01X773327Y1411421D01*
Y1411422D01*
G02X773240Y1411867I1114J449D01*
G01Y1430787D01*
X773232Y1430815D01*
G02X773182Y1431159I1152J343D01*
G01Y1445363D01*
G03X773067Y1445545I-200J1D01*
G01X772685Y1445722D01*
X772570Y1445707D01*
X772525Y1445669D01*
G02X771557Y1445316I-967J1149D01*
G02Y1448320I0J1502D01*
G02X772525Y1447967I1J-1502D01*
G01X772570Y1447929D01*
X772685Y1447914D01*
X773067Y1448091D01*
G03X773182Y1448273I-85J181D01*
G01Y1458470D01*
G02X773200Y1458669I1201J-8D01*
G02X773530Y1459313I1184J-200D01*
G01X774846Y1460629D01*
X777440Y1463223D01*
X777442Y1463224D01*
G02X777613Y1463374I874J-824D01*
G02X777615Y1463375I89J-176D01*
G02X777752Y1463458I690J-984D01*
G01X777754Y1463459D01*
X777771Y1463468D01*
X777798Y1463482D01*
X794664Y1480346D01*
G02X794964Y1480551I820J-878D01*
G02X795447Y1480668I518J-1084D01*
G01X802707D01*
G02X803299Y1480511I-2J-1201D01*
G02X803549Y1480322I-593J-1045D01*
G01X804429Y1479441D01*
G03X804647Y1479398I141J142D01*
G01X804704Y1479421D01*
X804770Y1479521D01*
Y1487653D01*
X804681Y1487762D01*
X804611Y1487777D01*
G02Y1490717I308J1470D01*
G01X804681Y1490732D01*
X804770Y1490841D01*
Y1524691D01*
G02X804829Y1524833I200J0D01*
G01X814896Y1534899D01*
G03X814954Y1535041I-142J141D01*
G01Y1621735D01*
G02X815013Y1621877I200J0D01*
G37*
G36*
G01X603147Y599077D02*
X603450Y599351D01*
X603484Y599436D01*
X603481Y599482D01*
G02X603477Y599588I1498J110D01*
G02X604979Y598086I1502J0D01*
G02X604579Y598140I-1J1502D01*
G03X604391Y598096I-54J-193D01*
G01X604215Y597937D01*
G02X604227Y597882I-1461J-348D01*
G01X604235Y597842D01*
X604279Y597778D01*
X604580Y597577D01*
X604656Y597562D01*
X604695Y597569D01*
G02X604982Y597597I289J-1474D01*
G02Y594593I0J-1502D01*
G02X604640Y594632I-2J1502D01*
G01X604601Y594642D01*
X604523Y594629D01*
X604214Y594436D01*
X604168Y594371D01*
X604159Y594332D01*
G02X604155Y594315I-1464J336D01*
G01X604145Y594275D01*
X604159Y594195D01*
X604360Y593882D01*
X604426Y593836D01*
X604467Y593828D01*
G02X605682Y592354I-287J-1474D01*
G02X605221Y591271I-1503J0D01*
G01X605190Y591242D01*
X605159Y591166D01*
X605167Y590786D01*
X605202Y590711D01*
X605234Y590683D01*
G02X605743Y589556I-993J-1127D01*
G02X602739I-1502J0D01*
G02X603200Y590639I1503J0D01*
G01X603231Y590668D01*
X603262Y590744D01*
X603254Y591124D01*
X603219Y591199D01*
X603187Y591227D01*
G02X602678Y592354I993J1127D01*
G02X602720Y592707I1502J0D01*
G01X602730Y592747D01*
X602716Y592827D01*
X602515Y593140D01*
X602449Y593186D01*
X602408Y593194D01*
G02X601193Y594668I287J1474D01*
G02X601753Y595838I1502J0D01*
G01X601788Y595866D01*
X601827Y595944D01*
X601835Y596341D01*
X601800Y596421D01*
X601766Y596450D01*
G02X601254Y597580I991J1130D01*
G02X602756Y599082I1502J0D01*
G02X603013Y599060I1J-1502D01*
G01X603059Y599052D01*
X603147Y599077D01*
G37*
G36*
G01X642454Y560573D02*
G03X642083Y560944I-399J-28D01*
G02X640683Y562443I103J1499D01*
G02X642185Y563945I1502J0D01*
G02X643684Y562545I0J-1503D01*
G03X644055Y562174I399J28D01*
G02X645455Y560675I-103J-1499D01*
G02X643953Y559173I-1502J0D01*
G02X642454Y560573I0J1503D01*
G37*
G36*
G01X660678Y560000D02*
Y560337D01*
X660653Y560404D01*
X660629Y560432D01*
G02X660258Y561420I1130J988D01*
G02X663262I1502J0D01*
G02X662891Y560432I-1501J0D01*
G01X662867Y560404D01*
X662842Y560337D01*
Y560000D01*
X662867Y559933D01*
X662891Y559905D01*
G02X663262Y558917I-1130J-988D01*
G02X660258I-1502J0D01*
G02X660629Y559905I1501J0D01*
G01X660653Y559933D01*
X660678Y560000D01*
G37*
G36*
G01X660357Y552322D02*
X660167Y552664D01*
X660098Y552714D01*
X660055Y552724D01*
G02X658864Y554193I310J1469D01*
G02X661868I1502J0D01*
G02X661778Y553680I-1502J-1D01*
G01X661763Y553639D01*
X661769Y553554D01*
X661959Y553212D01*
X662028Y553162D01*
X662071Y553152D01*
G02X663262Y551683I-310J-1469D01*
G02X660258I-1502J0D01*
G02X660348Y552196I1502J1D01*
G01X660363Y552237D01*
X660357Y552322D01*
G37*
G36*
G01X790290Y1024796D02*
X789934Y1024892D01*
X789854Y1024880D01*
X789819Y1024860D01*
G02X789050Y1024648I-769J1289D01*
G02Y1027652I0J1502D01*
G02X790363Y1026880I0J-1503D01*
G01X790383Y1026844D01*
X790446Y1026794D01*
X790802Y1026698D01*
X790882Y1026710D01*
X790917Y1026730D01*
G02X791686Y1026942I769J-1289D01*
G02Y1023938I0J-1502D01*
G02X790373Y1024710I0J1503D01*
G01X790353Y1024746D01*
X790290Y1024796D01*
G37*
G36*
G01X871200Y1111217D02*
X871552D01*
X871621Y1111245D01*
X871649Y1111271D01*
G02X872676Y1111677I1027J-1096D01*
G02X873742Y1111233I0J-1502D01*
G01X873770Y1111204D01*
X873844Y1111174D01*
X874208D01*
X874282Y1111204D01*
X874310Y1111233D01*
G02X875376Y1111677I1066J-1058D01*
G02X876878Y1110175I0J-1502D01*
G02X876498Y1109176I-1503J0D01*
G01X876473Y1109149D01*
X876447Y1109081D01*
Y1108741D01*
X876473Y1108672D01*
X876498Y1108645D01*
G02X876877Y1107647I-1123J-998D01*
G02X875375Y1106145I-1502J0D01*
G02X874309Y1106589I0J1502D01*
G01X874281Y1106618D01*
X874207Y1106648D01*
X873843D01*
X873769Y1106618D01*
X873741Y1106589D01*
G02X872675Y1106145I-1066J1058D01*
G02X871648Y1106551I0J1502D01*
G01X871620Y1106577D01*
X871551Y1106605D01*
X871199D01*
X871130Y1106577D01*
X871102Y1106551D01*
G02X869048I-1027J1096D01*
G01X869020Y1106577D01*
X868951Y1106605D01*
X868599D01*
X868530Y1106577D01*
X868502Y1106551D01*
G02X867475Y1106145I-1027J1096D01*
G02X865973Y1107647I0J1502D01*
G02X866353Y1108646I1503J0D01*
G01X866378Y1108673D01*
X866404Y1108741D01*
Y1109081D01*
X866378Y1109150D01*
X866353Y1109177D01*
G02X865974Y1110175I1123J998D01*
G02X867476Y1111677I1502J0D01*
G02X868503Y1111271I0J-1502D01*
G01X868531Y1111245D01*
X868600Y1111217D01*
X868952D01*
X869021Y1111245D01*
X869049Y1111271D01*
G02X871103I1027J-1096D01*
G01X871131Y1111245D01*
X871200Y1111217D01*
G37*
G36*
G01X890073Y1115145D02*
X890425D01*
X890494Y1115173D01*
X890522Y1115199D01*
G02X891549Y1115605I1027J-1096D01*
G02X892615Y1115161I0J-1502D01*
G01X892643Y1115132D01*
X892717Y1115102D01*
X893081D01*
X893155Y1115132D01*
X893183Y1115161D01*
G02X894249Y1115605I1066J-1058D01*
G02Y1112601I0J-1502D01*
G02X893183Y1113045I0J1502D01*
G01X893155Y1113074D01*
X893081Y1113104D01*
X892717D01*
X892643Y1113074D01*
X892615Y1113045D01*
G02X891549Y1112601I-1066J1058D01*
G02X890522Y1113007I0J1502D01*
G01X890494Y1113033D01*
X890425Y1113061D01*
X890073D01*
X890004Y1113033D01*
X889976Y1113007D01*
G02X887922I-1027J1096D01*
G01X887894Y1113033D01*
X887825Y1113061D01*
X887473D01*
X887404Y1113033D01*
X887376Y1113007D01*
G02X886349Y1112601I-1027J1096D01*
G02Y1115605I0J1502D01*
G02X887376Y1115199I0J-1502D01*
G01X887404Y1115173D01*
X887473Y1115145D01*
X887825D01*
X887894Y1115173D01*
X887922Y1115199D01*
G02X889976I1027J-1096D01*
G01X890004Y1115173D01*
X890073Y1115145D01*
G37*
G36*
G01X829274Y1115168D02*
X828938D01*
X828871Y1115143D01*
X828843Y1115119D01*
G02X827856Y1114749I-987J1131D01*
G02Y1117753I0J1502D01*
G02X828843Y1117383I0J-1501D01*
G01X828871Y1117359D01*
X828938Y1117334D01*
X829274D01*
X829341Y1117359D01*
X829369Y1117383D01*
G02X830356Y1117753I987J-1131D01*
G02Y1114749I0J-1502D01*
G02X829369Y1115119I0J1501D01*
G01X829341Y1115143D01*
X829274Y1115168D01*
G37*
G36*
G01X859310Y1121635D02*
X859674D01*
X859748Y1121665D01*
X859776Y1121694D01*
G02X860842Y1122138I1066J-1058D01*
G02X861829Y1121768I0J-1501D01*
G01X861857Y1121744D01*
X861924Y1121719D01*
X862260D01*
X862327Y1121744D01*
X862355Y1121768D01*
G02X863342Y1122138I987J-1131D01*
G02Y1119134I0J-1502D01*
G02X862355Y1119504I0J1501D01*
G01X862327Y1119528D01*
X862260Y1119553D01*
X861924D01*
X861857Y1119528D01*
X861829Y1119504D01*
G02X860842Y1119134I-987J1131D01*
G02X859776Y1119578I0J1502D01*
G01X859748Y1119607D01*
X859674Y1119637D01*
X859310D01*
X859236Y1119607D01*
X859208Y1119578D01*
G02X858142Y1119134I-1066J1058D01*
G02X857115Y1119540I0J1502D01*
G01X857087Y1119566D01*
X857018Y1119594D01*
X856666D01*
X856597Y1119566D01*
X856569Y1119540D01*
G02X855542Y1119134I-1027J1096D01*
G02Y1122138I0J1502D01*
G02X856569Y1121732I0J-1502D01*
G01X856597Y1121706D01*
X856666Y1121678D01*
X857018D01*
X857087Y1121706D01*
X857115Y1121732D01*
G02X858142Y1122138I1027J-1096D01*
G02X859208Y1121694I0J-1502D01*
G01X859236Y1121665D01*
X859310Y1121635D01*
G37*
G36*
G01X875088Y1121678D02*
X875440D01*
X875509Y1121706D01*
X875537Y1121732D01*
G02X876564Y1122138I1027J-1096D01*
G02X877630Y1121694I0J-1502D01*
G01X877658Y1121665D01*
X877732Y1121635D01*
X878096D01*
X878170Y1121665D01*
X878198Y1121694D01*
G02X879264Y1122138I1066J-1058D01*
G02Y1119134I0J-1502D01*
G02X878198Y1119578I0J1502D01*
G01X878170Y1119607D01*
X878096Y1119637D01*
X877732D01*
X877658Y1119607D01*
X877630Y1119578D01*
G02X876564Y1119134I-1066J1058D01*
G02X875537Y1119540I0J1502D01*
G01X875509Y1119566D01*
X875440Y1119594D01*
X875088D01*
X875019Y1119566D01*
X874991Y1119540D01*
G02X872937I-1027J1096D01*
G01X872909Y1119566D01*
X872840Y1119594D01*
X872488D01*
X872419Y1119566D01*
X872391Y1119540D01*
G02X871364Y1119134I-1027J1096D01*
G02Y1122138I0J1502D01*
G02X872391Y1121732I0J-1502D01*
G01X872419Y1121706D01*
X872488Y1121678D01*
X872840D01*
X872909Y1121706D01*
X872937Y1121732D01*
G02X874991I1027J-1096D01*
G01X875019Y1121706D01*
X875088Y1121678D01*
G37*
G36*
G01X890073Y1124845D02*
X890425D01*
X890494Y1124873D01*
X890522Y1124899D01*
G02X891549Y1125305I1027J-1096D01*
G02X892615Y1124861I0J-1502D01*
G01X892643Y1124832D01*
X892717Y1124802D01*
X893081D01*
X893155Y1124832D01*
X893183Y1124861D01*
G02X894249Y1125305I1066J-1058D01*
G02Y1122301I0J-1502D01*
G02X893183Y1122745I0J1502D01*
G01X893155Y1122774D01*
X893081Y1122804D01*
X892717D01*
X892643Y1122774D01*
X892615Y1122745D01*
G02X891549Y1122301I-1066J1058D01*
G02X890522Y1122707I0J1502D01*
G01X890494Y1122733D01*
X890425Y1122761D01*
X890073D01*
X890004Y1122733D01*
X889976Y1122707D01*
G02X887922I-1027J1096D01*
G01X887894Y1122733D01*
X887825Y1122761D01*
X887473D01*
X887404Y1122733D01*
X887376Y1122707D01*
G02X886349Y1122301I-1027J1096D01*
G02Y1125305I0J1502D01*
G02X887376Y1124899I0J-1502D01*
G01X887404Y1124873D01*
X887473Y1124845D01*
X887825D01*
X887894Y1124873D01*
X887922Y1124899D01*
G02X889976I1027J-1096D01*
G01X890004Y1124873D01*
X890073Y1124845D01*
G37*
G36*
G01X859410Y1131335D02*
X859774D01*
X859848Y1131365D01*
X859876Y1131394D01*
G02X860942Y1131838I1066J-1058D01*
G02X861929Y1131468I0J-1501D01*
G01X861957Y1131444D01*
X862024Y1131419D01*
X862360D01*
X862427Y1131444D01*
X862455Y1131468D01*
G02X863442Y1131838I987J-1131D01*
G02Y1128834I0J-1502D01*
G02X862455Y1129204I0J1501D01*
G01X862427Y1129228D01*
X862360Y1129253D01*
X862024D01*
X861957Y1129228D01*
X861929Y1129204D01*
G02X860942Y1128834I-987J1131D01*
G02X859876Y1129278I0J1502D01*
G01X859848Y1129307D01*
X859774Y1129337D01*
X859410D01*
X859336Y1129307D01*
X859308Y1129278D01*
G02X858242Y1128834I-1066J1058D01*
G02X857215Y1129240I0J1502D01*
G01X857187Y1129266D01*
X857118Y1129294D01*
X856766D01*
X856697Y1129266D01*
X856669Y1129240D01*
G02X855642Y1128834I-1027J1096D01*
G02Y1131838I0J1502D01*
G02X856669Y1131432I0J-1502D01*
G01X856697Y1131406D01*
X856766Y1131378D01*
X857118D01*
X857187Y1131406D01*
X857215Y1131432D01*
G02X858242Y1131838I1027J-1096D01*
G02X859308Y1131394I0J-1502D01*
G01X859336Y1131365D01*
X859410Y1131335D01*
G37*
G36*
G01X875088Y1131378D02*
X875440D01*
X875509Y1131406D01*
X875537Y1131432D01*
G02X876564Y1131838I1027J-1096D01*
G02X877630Y1131394I0J-1502D01*
G01X877658Y1131365D01*
X877732Y1131335D01*
X878096D01*
X878170Y1131365D01*
X878198Y1131394D01*
G02X879264Y1131838I1066J-1058D01*
G02Y1128834I0J-1502D01*
G02X878198Y1129278I0J1502D01*
G01X878170Y1129307D01*
X878096Y1129337D01*
X877732D01*
X877658Y1129307D01*
X877630Y1129278D01*
G02X876564Y1128834I-1066J1058D01*
G02X875537Y1129240I0J1502D01*
G01X875509Y1129266D01*
X875440Y1129294D01*
X875088D01*
X875019Y1129266D01*
X874991Y1129240D01*
G02X872937I-1027J1096D01*
G01X872909Y1129266D01*
X872840Y1129294D01*
X872488D01*
X872419Y1129266D01*
X872391Y1129240D01*
G02X871364Y1128834I-1027J1096D01*
G02Y1131838I0J1502D01*
G02X872391Y1131432I0J-1502D01*
G01X872419Y1131406D01*
X872488Y1131378D01*
X872840D01*
X872909Y1131406D01*
X872937Y1131432D01*
G02X874991I1027J-1096D01*
G01X875019Y1131406D01*
X875088Y1131378D01*
G37*
G36*
G01X815393Y1132986D02*
X815111Y1133217D01*
X815034Y1133240D01*
X814994Y1133235D01*
G02X814835Y1133227I-155J1494D01*
G02Y1136231I0J1502D01*
G02X816323Y1134931I0J-1502D01*
G01X816329Y1134891D01*
X816369Y1134822D01*
X816661Y1134603D01*
X816738Y1134583D01*
X816778Y1134589D01*
G02X817006Y1134606I231J-1562D01*
G02X817469Y1134536I-2J-1579D01*
G01X817510Y1134524D01*
X817593Y1134534D01*
X817921Y1134728D01*
X817969Y1134796D01*
X817978Y1134838D01*
G02X819449Y1136036I1471J-304D01*
G02Y1133032I0J-1502D01*
G02X819060Y1133083I-1J1502D01*
G01X819019Y1133094D01*
X818936Y1133081D01*
X818616Y1132876D01*
X818569Y1132805D01*
X818562Y1132764D01*
G02X817006Y1131448I-1556J262D01*
G02X815435Y1132876I0J1578D01*
G01X815431Y1132916D01*
X815393Y1132986D01*
G37*
G36*
G01X862360Y1138253D02*
X862024D01*
X861957Y1138228D01*
X861929Y1138204D01*
G02X860942Y1137834I-987J1131D01*
G02Y1140838I0J1502D01*
G02X861929Y1140468I0J-1501D01*
G01X861957Y1140444D01*
X862024Y1140419D01*
X862360D01*
X862427Y1140444D01*
X862455Y1140468D01*
G02X863442Y1140838I987J-1131D01*
G02Y1137834I0J-1502D01*
G02X862455Y1138204I0J1501D01*
G01X862427Y1138228D01*
X862360Y1138253D01*
G37*
G36*
G01X870196Y1138337D02*
X869832D01*
X869758Y1138307D01*
X869730Y1138278D01*
G02X868664Y1137834I-1066J1058D01*
G02Y1140838I0J1502D01*
G02X869730Y1140394I0J-1502D01*
G01X869758Y1140365D01*
X869832Y1140335D01*
X870196D01*
X870270Y1140365D01*
X870298Y1140394D01*
G02X871364Y1140838I1066J-1058D01*
G02Y1137834I0J-1502D01*
G02X870298Y1138278I0J1502D01*
G01X870270Y1138307D01*
X870196Y1138337D01*
G37*
G36*
G01X862537Y1146997D02*
X862201D01*
X862134Y1146972D01*
X862106Y1146948D01*
G02X861119Y1146578I-987J1131D01*
G02Y1149582I0J1502D01*
G02X862106Y1149212I0J-1501D01*
G01X862134Y1149188D01*
X862201Y1149163D01*
X862537D01*
X862604Y1149188D01*
X862632Y1149212D01*
G02X863619Y1149582I987J-1131D01*
G02Y1146578I0J-1502D01*
G02X862632Y1146948I0J1501D01*
G01X862604Y1146972D01*
X862537Y1146997D01*
G37*
G36*
G01X869440D02*
X869104D01*
X869037Y1146972D01*
X869009Y1146948D01*
G02X868022Y1146578I-987J1131D01*
G02Y1149582I0J1502D01*
G02X869009Y1149212I0J-1501D01*
G01X869037Y1149188D01*
X869104Y1149163D01*
X869440D01*
X869507Y1149188D01*
X869535Y1149212D01*
G02X870522Y1149582I987J-1131D01*
G02Y1146578I0J-1502D01*
G02X869535Y1146948I0J1501D01*
G01X869507Y1146972D01*
X869440Y1146997D01*
G37*
G36*
G01X807227Y1219427D02*
X807499Y1219698D01*
X807529Y1219776D01*
X807527Y1219819D01*
G02X807525Y1219895I1500J77D01*
G02X809027Y1218393I1502J0D01*
G02X808942Y1218395I-7J1502D01*
G01X808899Y1218398D01*
X808820Y1218368D01*
X808548Y1218097D01*
X808518Y1218019D01*
X808520Y1217976D01*
G02X808522Y1217900I-1500J-77D01*
G02X807020Y1219402I-1502J0D01*
G02X807105Y1219400I7J-1502D01*
G01X807148Y1219397D01*
X807227Y1219427D01*
G37*
G36*
G01X877908Y1023492D02*
X877946Y1023525D01*
G02X878927Y1023889I980J-1138D01*
G02X879859Y1023565I0J-1502D01*
G01X879897Y1023535D01*
X879990Y1023516D01*
X880395Y1023628D01*
X880464Y1023692D01*
X880481Y1023738D01*
G02X881887Y1024710I1406J-531D01*
G02Y1021706I0J-1502D01*
G02X880955Y1022030I0J1502D01*
G01X880917Y1022060D01*
X880824Y1022079D01*
X880419Y1021967D01*
X880350Y1021903D01*
X880333Y1021857D01*
G02X878927Y1020885I-1406J531D01*
G02X877507Y1021898I0J1502D01*
G01X877491Y1021945D01*
X877418Y1022013D01*
X877002Y1022125D01*
X876906Y1022103D01*
X876868Y1022070D01*
G02X875887Y1021706I-980J1138D01*
G02Y1024710I0J1502D01*
G02X877307Y1023697I0J-1502D01*
G01X877323Y1023650D01*
X877396Y1023582D01*
X877812Y1023470D01*
X877908Y1023492D01*
G37*
G36*
G01X886386Y1023281D02*
X886390Y1023332D01*
G02X887887Y1024710I1497J-124D01*
G02X889389Y1023208I0J-1502D01*
G02X888887Y1022087I-1503J0D01*
G01X888844Y1022049D01*
X888812Y1021942D01*
X888930Y1021488D01*
X889012Y1021410D01*
X889067Y1021398D01*
G02X890245Y1019931I-324J-1467D01*
G02X887241I-1502J0D01*
G02X887743Y1021052I1503J0D01*
G01X887786Y1021090D01*
X887818Y1021197D01*
X887700Y1021651D01*
X887618Y1021729D01*
X887563Y1021741D01*
G02X887182Y1021882I326J1466D01*
G01X887137Y1021905D01*
X887037D01*
X886655Y1021696D01*
X886600Y1021612D01*
X886596Y1021561D01*
G02X885099Y1020183I-1497J124D01*
G02Y1023187I0J1502D01*
G02X885804Y1023011I0J-1502D01*
G01X885849Y1022988D01*
X885949D01*
X886331Y1023197D01*
X886386Y1023281D01*
G37*
G36*
G01X892846Y1022125D02*
G02X892385Y1023208I1042J1083D01*
G02X895389I1502J0D01*
G02X894344Y1021777I-1502J0D01*
G03X894188Y1021108I121J-381D01*
G02X894649Y1020025I-1042J-1083D01*
G02X891645I-1502J0D01*
G02X892690Y1021456I1502J0D01*
G03X892846Y1022125I-121J381D01*
G37*
G36*
G01X861648Y1025466D02*
X861600Y1025440D01*
G02X860887Y1025260I-713J1322D01*
G02X862389Y1026762I0J1502D01*
G02X862386Y1026672I-1502J5D01*
G01X862383Y1026617D01*
X862432Y1026520D01*
X862819Y1026274D01*
X862928Y1026270D01*
X862976Y1026296D01*
G02X863689Y1026476I713J-1322D01*
G02Y1023472I0J-1502D01*
G02X862976Y1023652I0J1502D01*
G01X862928Y1023678D01*
X862821Y1023674D01*
X862434Y1023430D01*
X862385Y1023335D01*
X862387Y1023280D01*
G02X862389Y1023208I-1500J-78D01*
G02X860887Y1024710I-1502J0D01*
G02X861600Y1024530I0J-1502D01*
G01X861648Y1024504D01*
X861755Y1024508D01*
X862142Y1024752D01*
X862191Y1024847D01*
X862189Y1024902D01*
G02X862187Y1024974I1500J78D01*
G02X862190Y1025064I1502J-5D01*
G01X862193Y1025119D01*
X862144Y1025216D01*
X861757Y1025462D01*
X861648Y1025466D01*
G37*
G36*
G01X868847Y1027103D02*
X868885Y1027129D01*
G02X869741Y1027397I856J-1233D01*
G02X870778Y1026981I-1J-1502D01*
G01X870817Y1026945D01*
X870918Y1026919D01*
X871352Y1027039D01*
X871425Y1027112D01*
X871440Y1027164D01*
G02X872887Y1028264I1447J-402D01*
G02Y1025260I0J-1502D01*
G02X871850Y1025676I1J1502D01*
G01X871811Y1025712D01*
X871710Y1025738D01*
X871276Y1025618D01*
X871203Y1025545D01*
X871188Y1025493D01*
G02X871060Y1025176I-1448J400D01*
G01X871037Y1025134D01*
X871034Y1025038D01*
X871215Y1024659D01*
X871292Y1024600D01*
X871339Y1024592D01*
G02X872571Y1023114I-271J-1478D01*
G02X869567I-1502J0D01*
G02X869750Y1023833I1502J0D01*
G01X869773Y1023875D01*
X869776Y1023971D01*
X869595Y1024350D01*
X869518Y1024409D01*
X869471Y1024417D01*
G02X868343Y1025345I270J1478D01*
G01X868326Y1025389D01*
X868260Y1025450D01*
X867870Y1025568D01*
X867781Y1025554D01*
X867743Y1025528D01*
G02X866887Y1025260I-856J1233D01*
G02Y1028264I0J1502D01*
G02X868285Y1027312I0J-1502D01*
G01X868302Y1027268D01*
X868368Y1027207D01*
X868758Y1027089D01*
X868847Y1027103D01*
G37*
G36*
G01X804814Y1134092D02*
X804788Y1134041D01*
G02X803453Y1133227I-1335J688D01*
G02Y1136231I0J1502D01*
G02X804788Y1135417I0J-1502D01*
G01X804814Y1135366D01*
X804909Y1135308D01*
X805379D01*
X805474Y1135366D01*
X805500Y1135417D01*
G02X806835Y1136231I1335J-688D01*
G02X808320Y1134951I0J-1501D01*
G01X808328Y1134902D01*
X808385Y1134823D01*
X808770Y1134635D01*
X808868Y1134637D01*
X808911Y1134662D01*
G02X809682Y1134862I769J-1379D01*
G02Y1131706I0J-1578D01*
G02X808115Y1133093I0J1579D01*
G01X808109Y1133142D01*
X808054Y1133223D01*
X807674Y1133422D01*
X807577D01*
X807532Y1133399D01*
G02X806835Y1133227I-698J1330D01*
G02X805500Y1134041I0J1502D01*
G01X805474Y1134092D01*
X805379Y1134150D01*
X804909D01*
X804814Y1134092D01*
G37*
G36*
G01X748730Y1140378D02*
X748721Y1140427D01*
G02X748700Y1140649I1181J224D01*
G02X749902Y1139447I1202J0D01*
G02X749679Y1139468I1J1202D01*
G01X749631Y1139477D01*
X749536Y1139448D01*
X749232Y1139144D01*
X749203Y1139050D01*
X749212Y1139001D01*
G02X749233Y1138779I-1181J-224D01*
G02X746829I-1202J0D01*
G02X746850Y1139001I1202J-2D01*
G01X746859Y1139050D01*
X746830Y1139143D01*
X746525Y1139448D01*
X746432Y1139477D01*
X746383Y1139468D01*
G02X746161Y1139447I-224J1181D01*
G02X747363Y1140649I0J1202D01*
G02X747342Y1140427I-1202J2D01*
G01X747333Y1140378D01*
X747362Y1140285D01*
X747667Y1139980D01*
X747760Y1139951D01*
X747809Y1139960D01*
G02X748031Y1139981I224J-1181D01*
G02X748254Y1139960I-1J-1202D01*
G01X748302Y1139951D01*
X748397Y1139980D01*
X748701Y1140284D01*
X748730Y1140378D01*
G37*
G36*
G01X771170D02*
X771161Y1140427D01*
G02X771140Y1140649I1181J224D01*
G02X772342Y1139447I1202J0D01*
G02X772120Y1139468I2J1202D01*
G01X772071Y1139477D01*
X771978Y1139448D01*
X771673Y1139143D01*
X771644Y1139050D01*
X771653Y1139001D01*
G02X771674Y1138779I-1181J-224D01*
G02X769270I-1202J0D01*
G02X769291Y1139001I1202J-2D01*
G01X769300Y1139050D01*
X769271Y1139143D01*
X768966Y1139448D01*
X768873Y1139477D01*
X768824Y1139468D01*
G02X768602Y1139447I-224J1181D01*
G02X769804Y1140649I0J1202D01*
G02X769783Y1140427I-1202J2D01*
G01X769774Y1140378D01*
X769803Y1140285D01*
X770108Y1139980D01*
X770201Y1139951D01*
X770250Y1139960D01*
G02X770472Y1139981I224J-1181D01*
G02X770694Y1139960I-2J-1202D01*
G01X770743Y1139951D01*
X770836Y1139980D01*
X771141Y1140285D01*
X771170Y1140378D01*
G37*
G36*
G01X824902Y1148843D02*
G02X824242Y1150087I842J1244D01*
G02X827246I1502J0D01*
G02X826586Y1148843I-1502J0D01*
G03Y1148181I224J-331D01*
G02X827246Y1146937I-842J-1244D01*
G02X824242I-1502J0D01*
G02X824902Y1148181I1502J0D01*
G03Y1148843I-224J331D01*
G37*
G36*
G01X809723Y1158669D02*
G02X809623Y1158666I-95J1499D01*
G02X811125Y1160168I0J1502D01*
G02X811011Y1159594I-1502J0D01*
G03X811407Y1159043I370J-152D01*
G02X811507Y1159046I95J-1499D01*
G02X810005Y1157544I0J-1502D01*
G02X810119Y1158118I1502J0D01*
G03X809723Y1158669I-370J152D01*
G37*
G36*
G01X753913Y1188099D02*
X753864Y1188090D01*
G02X753642Y1188069I-224J1181D01*
G02X754844Y1189271I0J1202D01*
G02X754823Y1189049I-1202J2D01*
G01X754814Y1189000D01*
X754843Y1188907D01*
X755148Y1188602D01*
X755241Y1188573D01*
X755290Y1188582D01*
G02X755512Y1188603I224J-1181D01*
G02X756714Y1187401I0J-1202D01*
G02X756693Y1187179I-1202J2D01*
G01X756684Y1187130D01*
X756713Y1187037D01*
X757018Y1186732D01*
X757111Y1186703D01*
X757160Y1186712D01*
G02X757382Y1186733I224J-1181D01*
G02X756180Y1185531I0J-1202D01*
G02X756201Y1185753I1202J-2D01*
G01X756210Y1185802D01*
X756181Y1185895D01*
X755876Y1186200D01*
X755783Y1186229D01*
X755734Y1186220D01*
G02X755512Y1186199I-224J1181D01*
G02X754310Y1187401I0J1202D01*
G02X754331Y1187623I1202J-2D01*
G01X754340Y1187672D01*
X754311Y1187765D01*
X754006Y1188070D01*
X753913Y1188099D01*
G37*
G36*
G01X746850Y1190919D02*
G02X746829Y1191141I1181J224D01*
G02X748031Y1189939I1202J0D01*
G02X747809Y1189960I2J1202D01*
G03X747342Y1189493I-74J-393D01*
G02X747363Y1189271I-1181J-224D01*
G02X746161Y1190473I-1202J0D01*
G02X746383Y1190452I-2J-1202D01*
G03X746850Y1190919I74J393D01*
G37*
G36*
G01X763214Y1189960D02*
G02X762992Y1189939I-224J1181D01*
G02X764194Y1191141I0J1202D01*
G02X764173Y1190919I-1202J2D01*
G03X764640Y1190452I393J-74D01*
G02X764862Y1190473I224J-1181D01*
G02X763660Y1189271I0J-1202D01*
G02X763681Y1189493I1202J-2D01*
G03X763214Y1189960I-393J74D01*
G37*
G36*
G01X805626Y1192168D02*
G02X804458Y1191610I-1168J943D01*
G02Y1194614I0J1502D01*
G02X805682Y1193983I0J-1503D01*
G03X806319Y1193963I326J232D01*
G02X807487Y1194521I1168J-943D01*
G02Y1191517I0J-1502D01*
G02X806263Y1192148I0J1503D01*
G03X805626Y1192168I-326J-232D01*
G37*
G36*
G01X766954Y1193700D02*
G02X766732Y1193679I-224J1181D01*
G02X767934Y1194881I0J1202D01*
G02X767913Y1194659I-1202J2D01*
G03X768380Y1194192I393J-74D01*
G02X768602Y1194213I224J-1181D01*
G02X767400Y1193011I0J-1202D01*
G02X767421Y1193233I1202J-2D01*
G03X766954Y1193700I-393J74D01*
G37*
G36*
G01X776691Y1198359D02*
X776684Y1198406D01*
G02X776666Y1198621I1269J214D01*
G02X777953Y1197334I1287J0D01*
G02X777738Y1197352I-1J1287D01*
G01X777691Y1197359D01*
X777601Y1197332D01*
X777300Y1197042D01*
X777269Y1196953D01*
X777275Y1196906D01*
G02X777285Y1196751I-1192J-155D01*
G02X774881I-1202J0D01*
G02X774902Y1196973I1202J-2D01*
G01X774911Y1197022D01*
X774882Y1197116D01*
X774578Y1197420D01*
X774483Y1197449D01*
X774435Y1197440D01*
G02X774212Y1197419I-224J1181D01*
G02X773990Y1197440I2J1202D01*
G01X773941Y1197449D01*
X773848Y1197420D01*
X773543Y1197115D01*
X773514Y1197022D01*
X773523Y1196973D01*
G02X773544Y1196751I-1181J-224D01*
G02X771140I-1202J0D01*
G02X771161Y1196973I1202J-2D01*
G01X771170Y1197022D01*
X771141Y1197115D01*
X770836Y1197420D01*
X770743Y1197449D01*
X770694Y1197440D01*
G02X770472Y1197419I-224J1181D01*
G02X771674Y1198621I0J1202D01*
G02X771653Y1198399I-1202J2D01*
G01X771644Y1198350D01*
X771673Y1198257D01*
X771978Y1197952D01*
X772071Y1197923D01*
X772120Y1197932D01*
G02X772342Y1197953I224J-1181D01*
G02X772564Y1197932I-2J-1202D01*
G01X772613Y1197923D01*
X772706Y1197952D01*
X773011Y1198257D01*
X773040Y1198350D01*
X773031Y1198399D01*
G02X773010Y1198621I1181J224D01*
G02X775414I1202J0D01*
G02X775393Y1198399I-1202J2D01*
G01X775384Y1198350D01*
X775413Y1198256D01*
X775717Y1197952D01*
X775812Y1197923D01*
X775860Y1197932D01*
G02X776083Y1197953I224J-1181D01*
G02X776238Y1197943I0J-1202D01*
G01X776285Y1197937D01*
X776374Y1197968D01*
X776664Y1198269D01*
X776691Y1198359D01*
G37*
G36*
G01X806004Y1201265D02*
G02X807489Y1202545I1485J-221D01*
G02Y1199541I0J-1502D01*
G02X806576Y1199850I0J1503D01*
G03X805937Y1199592I-243J-317D01*
G02X804452Y1198312I-1485J221D01*
G02Y1201316I0J1502D01*
G02X805365Y1201007I0J-1503D01*
G03X806004Y1201265I243J317D01*
G37*
G36*
G01X820368Y1214055D02*
X820356Y1214107D01*
G02X820314Y1214458I1460J353D01*
G02X821816Y1212956I1502J0D01*
G02X821465Y1212998I2J1502D01*
G01X821413Y1213010D01*
X821314Y1212982D01*
X820998Y1212666D01*
X820970Y1212567D01*
X820982Y1212515D01*
G02X821024Y1212164I-1460J-353D01*
G02X819522Y1210662I-1502J0D01*
G02X819378Y1210669I1J1502D01*
G01X819333Y1210673D01*
X819249Y1210643D01*
X818967Y1210361D01*
X818937Y1210278D01*
X818941Y1210233D01*
G02X818948Y1210089I-1495J-145D01*
G02X817446Y1211591I-1502J0D01*
G02X817590Y1211584I-1J-1502D01*
G01X817635Y1211580D01*
X817719Y1211610D01*
X818001Y1211892D01*
X818031Y1211975D01*
X818027Y1212020D01*
G02X818020Y1212164I1495J145D01*
G02X819522Y1213666I1502J0D01*
G02X819873Y1213624I-2J-1502D01*
G01X819925Y1213612D01*
X820024Y1213640D01*
X820340Y1213956D01*
X820368Y1214055D01*
G37*
G36*
G01X945510Y1083583D02*
X945174D01*
X945107Y1083558D01*
X945079Y1083534D01*
G02X944092Y1083164I-987J1131D01*
G02Y1086168I0J1502D01*
G02X945079Y1085798I0J-1501D01*
G01X945107Y1085774D01*
X945174Y1085749D01*
X945510D01*
X945577Y1085774D01*
X945605Y1085798D01*
G02X946592Y1086168I987J-1131D01*
G02Y1083164I0J-1502D01*
G02X945605Y1083534I0J1501D01*
G01X945577Y1083558D01*
X945510Y1083583D01*
G37*
G36*
G01X935352Y1092451D02*
X935704D01*
X935773Y1092479D01*
X935801Y1092505D01*
G02X937855I1027J-1096D01*
G01X937883Y1092479D01*
X937952Y1092451D01*
X938304D01*
X938373Y1092479D01*
X938401Y1092505D01*
G02X939428Y1092911I1027J-1096D01*
G02X940930Y1091409I0J-1502D01*
G02X940560Y1090422I-1501J0D01*
G01X940536Y1090394D01*
X940511Y1090327D01*
Y1089991D01*
X940536Y1089924D01*
X940560Y1089896D01*
G02X940930Y1088909I-1131J-987D01*
G02X939428Y1087407I-1502J0D01*
G02X938401Y1087813I0J1502D01*
G01X938373Y1087839D01*
X938304Y1087867D01*
X937952D01*
X937883Y1087839D01*
X937855Y1087813D01*
G02X935801I-1027J1096D01*
G01X935773Y1087839D01*
X935704Y1087867D01*
X935352D01*
X935283Y1087839D01*
X935255Y1087813D01*
G02X933201I-1027J1096D01*
G01X933173Y1087839D01*
X933104Y1087867D01*
X932752D01*
X932683Y1087839D01*
X932655Y1087813D01*
G02X931628Y1087407I-1027J1096D01*
G02X930126Y1088909I0J1502D01*
G02X930496Y1089896I1501J0D01*
G01X930520Y1089924D01*
X930545Y1089991D01*
Y1090327D01*
X930520Y1090394D01*
X930496Y1090422D01*
G02X930126Y1091409I1131J987D01*
G02X931628Y1092911I1502J0D01*
G02X932655Y1092505I0J-1502D01*
G01X932683Y1092479D01*
X932752Y1092451D01*
X933104D01*
X933173Y1092479D01*
X933201Y1092505D01*
G02X935255I1027J-1096D01*
G01X935283Y1092479D01*
X935352Y1092451D01*
G37*
G36*
G01X904490Y1308361D02*
X904101Y1308366D01*
X904023Y1308331D01*
X903993Y1308299D01*
G02X902875Y1307799I-1119J1002D01*
G02Y1310803I0J1502D01*
G02X904019Y1310274I0J-1501D01*
G01X904047Y1310241D01*
X904125Y1310204D01*
X904514Y1310199D01*
X904592Y1310234D01*
X904622Y1310266D01*
G02X905740Y1310766I1119J-1002D01*
G02Y1307762I0J-1502D01*
G02X904596Y1308291I0J1501D01*
G01X904568Y1308324D01*
X904490Y1308361D01*
G37*
G36*
G01X922848Y1324419D02*
Y1327819D01*
G02X924650Y1329622I1802J1D01*
G02X925542Y1329385I-1J-1803D01*
G03X925685Y1329364I99J174D01*
G01X925804Y1329391D01*
G03X925923Y1329470I-44J195D01*
G02X927146Y1330099I1222J-873D01*
G02Y1327095I0J-1502D01*
G02X926914Y1327113I0J1502D01*
G01X926871Y1327120D01*
X926787Y1327096D01*
X926522Y1326870D01*
G03X926452Y1326718I130J-152D01*
G01Y1325520D01*
G03X926522Y1325368I200J0D01*
G01X926787Y1325142D01*
X926871Y1325118D01*
X926914Y1325125D01*
G02X927146Y1325143I232J-1484D01*
G02Y1322139I0J-1502D01*
G02X925923Y1322768I-1J1502D01*
G03X925804Y1322847I-163J-116D01*
G01X925685Y1322874D01*
G03X925542Y1322853I-44J-195D01*
G02X924650Y1322616I-893J1566D01*
G02X922848Y1324419I1J1803D01*
G37*
G36*
G01X979886Y1103413D02*
X979852Y1103437D01*
G02X979224Y1104659I875J1222D01*
G02X982228I1502J0D01*
G02X981885Y1103703I-1502J-1D01*
G01X981858Y1103671D01*
X981835Y1103592D01*
X981884Y1103219D01*
X981927Y1103148D01*
X981961Y1103124D01*
G02X982589Y1101902I-875J-1222D01*
G02X981761Y1100560I-1502J0D01*
G01X981713Y1100536D01*
X981655Y1100449D01*
X981623Y1099999D01*
X981668Y1099905D01*
X981712Y1099875D01*
G02X982354Y1098643I-861J-1232D01*
G02X979350I-1502J0D01*
G02X980178Y1099985I1502J0D01*
G01X980226Y1100009D01*
X980284Y1100096D01*
X980316Y1100546D01*
X980271Y1100640D01*
X980227Y1100670D01*
G02X979585Y1101902I861J1232D01*
G02X979928Y1102858I1502J1D01*
G01X979955Y1102890D01*
X979978Y1102969D01*
X979929Y1103342D01*
X979886Y1103413D01*
G37*
G36*
G01X1022345Y1176396D02*
G02X1021604Y1177691I761J1295D01*
G02X1024608I1502J0D01*
G02X1023911Y1176423I-1502J0D01*
G03X1023923Y1175740I214J-338D01*
G02X1024664Y1174445I-761J-1295D01*
G02X1021660I-1502J0D01*
G02X1022357Y1175713I1502J0D01*
G03X1022345Y1176396I-214J338D01*
G37*
G36*
G01X1020549Y1204081D02*
G02X1020434Y1204077I-110J1498D01*
G02X1021936Y1205579I0J1502D01*
G02X1021888Y1205201I-1502J-1D01*
G03X1022305Y1204702I387J-100D01*
G02X1022420Y1204706I110J-1498D01*
G02X1020918Y1203204I0J-1502D01*
G02X1020966Y1203582I1502J1D01*
G03X1020549Y1204081I-387J100D01*
G37*
G36*
G01X902929Y1298325D02*
X902883Y1298326D01*
G02X901406Y1299828I25J1502D01*
G02X904410I1502J0D01*
G02X904351Y1299411I-1503J0D01*
G01X904338Y1299366D01*
X904354Y1299274D01*
X904599Y1298943D01*
X904682Y1298901D01*
X904728Y1298900D01*
G02X904794Y1298897I-35J-1502D01*
G01X904945Y1299047D01*
G03X905004Y1299189I-141J142D01*
G02X906506Y1300690I1502J-1D01*
G02X908008Y1299188I0J-1502D01*
G02X906582Y1297688I-1502J0D01*
G01X906544Y1297686D01*
X906478Y1297657D01*
X906235Y1297415D01*
X906205Y1297349D01*
X906203Y1297311D01*
G02X904703Y1295896I-1500J88D01*
G02X903201Y1297398I0J1502D01*
G02X903260Y1297815I1503J0D01*
G01X903273Y1297860D01*
X903257Y1297952D01*
X903012Y1298283D01*
X902929Y1298325D01*
G37*
G36*
G01X931281Y1309158D02*
G02X930754Y1309062I-528J1406D01*
G02X932256Y1310564I0J1502D01*
G02X932201Y1310161I-1502J0D01*
G03X932727Y1309679I385J-107D01*
G02X933254Y1309775I528J-1406D01*
G02X931752Y1308273I0J-1502D01*
G02X931807Y1308676I1502J0D01*
G03X931281Y1309158I-385J107D01*
G37*
G36*
G01X909132Y1314862D02*
G02X908700Y1314798I-434J1438D01*
G02X910202Y1316300I0J1502D01*
G02X910177Y1316025I-1502J-2D01*
G03X910685Y1315568I393J-74D01*
G02X911117Y1315632I434J-1438D01*
G02X909615Y1314130I0J-1502D01*
G02X909640Y1314405I1502J2D01*
G03X909132Y1314862I-393J74D01*
G37*
G36*
G01X981827Y854303D02*
G03X981497Y854812I-384J113D01*
G02X980198Y856300I203J1488D01*
G02X983202I1502J0D01*
G02X983142Y855880I-1502J0D01*
G03X983472Y855371I384J-113D01*
G02X984771Y853883I-203J-1488D01*
G02X981767I-1502J0D01*
G02X981827Y854303I1502J0D01*
G37*
G36*
G01X1031919Y730862D02*
X1031590Y730931D01*
X1031519Y730921D01*
X1031487Y730903D01*
G02X1030753Y730711I-735J1310D01*
G02Y733715I0J1502D01*
G02X1031951Y733118I-1J-1502D01*
G01X1031974Y733089D01*
X1032034Y733051D01*
X1032363Y732982D01*
X1032434Y732992D01*
X1032466Y733010D01*
G02X1033200Y733202I735J-1310D01*
G02Y730198I0J-1502D01*
G02X1032002Y730795I1J1502D01*
G01X1031979Y730824D01*
X1031919Y730862D01*
G37*
G36*
G01X1156625Y791782D02*
X1156650Y791831D01*
G02X1157985Y792644I1335J-690D01*
G02X1159179Y792053I0J-1502D01*
G01X1159213Y792009D01*
X1159315Y791968D01*
X1159772Y792040D01*
X1159856Y792110D01*
X1159875Y792162D01*
G02X1161291Y793164I1416J-500D01*
G02Y790160I0J-1502D01*
G02X1160097Y790751I0J1502D01*
G01X1160063Y790795D01*
X1159961Y790836D01*
X1159504Y790764D01*
X1159420Y790694D01*
X1159401Y790642D01*
G02X1157985Y789640I-1416J500D01*
G02X1156688Y790385I0J1501D01*
G01X1156660Y790433D01*
X1156565Y790486D01*
X1156104Y790474D01*
X1156012Y790416D01*
X1155987Y790367D01*
G02X1154652Y789554I-1335J690D01*
G02X1153332Y790340I0J1501D01*
G01X1153305Y790390D01*
X1153209Y790446D01*
X1152741Y790437D01*
X1152647Y790378D01*
X1152622Y790327D01*
G02X1151277Y789494I-1345J669D01*
G02Y792498I0J1502D01*
G02X1152597Y791712I0J-1501D01*
G01X1152624Y791662D01*
X1152720Y791606D01*
X1153188Y791615D01*
X1153282Y791674D01*
X1153307Y791725D01*
G02X1154652Y792558I1345J-669D01*
G02X1155949Y791813I0J-1501D01*
G01X1155977Y791765D01*
X1156072Y791712D01*
X1156533Y791724D01*
X1156625Y791782D01*
G37*
G36*
G01X1055877Y1171314D02*
X1056268Y1171325D01*
X1056345Y1171362D01*
X1056373Y1171396D01*
G02X1057380Y1171872I1007J-827D01*
G01X1061120D01*
G02Y1169268I0J-1302D01*
G01X1057380D01*
G02X1056373Y1169744I0J1303D01*
G01X1056345Y1169778D01*
X1056268Y1169815D01*
X1055877Y1169826D01*
X1055799Y1169792D01*
X1055769Y1169760D01*
G02X1054881Y1169368I-888J810D01*
G02Y1171772I0J1202D01*
G02X1055769Y1171380I0J-1202D01*
G01X1055799Y1171348D01*
X1055877Y1171314D01*
G37*
G36*
G01X1072342Y1179354D02*
G02Y1176748I0J-1303D01*
G01X1068602D01*
G02Y1179354I0J1303D01*
G01X1072342D01*
G37*
G36*
G01X1055877Y1178795D02*
X1056268Y1178805D01*
X1056345Y1178843D01*
X1056373Y1178877D01*
G02X1057380Y1179354I1008J-826D01*
G01X1061120D01*
G02Y1176748I0J-1303D01*
G01X1057380D01*
G02X1056374Y1177224I1J1303D01*
G01X1056345Y1177259D01*
X1056269Y1177296D01*
X1055878Y1177306D01*
X1055799Y1177273D01*
X1055769Y1177240D01*
G02X1054881Y1176848I-888J810D01*
G02Y1179252I0J1202D01*
G02X1055768Y1178861I0J-1202D01*
G01X1055798Y1178828D01*
X1055877Y1178795D01*
G37*
G36*
G01X1117444Y552322D02*
X1117254Y552664D01*
X1117185Y552714D01*
X1117142Y552724D01*
G02X1115951Y554193I310J1469D01*
G02X1118955I1502J0D01*
G02X1118865Y553680I-1502J-1D01*
G01X1118850Y553639D01*
X1118856Y553554D01*
X1119046Y553212D01*
X1119115Y553162D01*
X1119158Y553152D01*
G02X1120349Y551683I-310J-1469D01*
G02X1117345I-1502J0D01*
G02X1117435Y552196I1502J1D01*
G01X1117450Y552237D01*
X1117444Y552322D01*
G37*
G36*
G01X1117765Y560000D02*
Y560337D01*
X1117740Y560404D01*
X1117716Y560432D01*
G02X1117345Y561420I1130J988D01*
G02X1120349I1502J0D01*
G02X1119978Y560432I-1501J0D01*
G01X1119954Y560404D01*
X1119929Y560337D01*
Y560000D01*
X1119954Y559933D01*
X1119978Y559905D01*
G02X1120349Y558917I-1130J-988D01*
G02X1117345I-1502J0D01*
G02X1117716Y559905I1501J0D01*
G01X1117740Y559933D01*
X1117765Y560000D01*
G37*
G36*
G01X1099541Y560573D02*
G03X1099170Y560944I-399J-28D01*
G02X1097770Y562443I103J1499D01*
G02X1099272Y563945I1502J0D01*
G02X1100771Y562545I0J-1503D01*
G03X1101142Y562174I399J28D01*
G02X1102542Y560675I-103J-1499D01*
G02X1101040Y559173I-1502J0D01*
G02X1099541Y560573I0J1503D01*
G37*
G36*
G01X1060234Y599077D02*
X1060537Y599351D01*
X1060571Y599436D01*
X1060568Y599482D01*
G02X1060564Y599588I1498J110D01*
G02X1062066Y598086I1502J0D01*
G02X1061666Y598140I-1J1502D01*
G03X1061478Y598096I-54J-193D01*
G01X1061302Y597937D01*
G02X1061314Y597882I-1461J-348D01*
G01X1061322Y597842D01*
X1061366Y597778D01*
X1061667Y597577D01*
X1061743Y597562D01*
X1061782Y597569D01*
G02X1062069Y597597I289J-1474D01*
G02Y594593I0J-1502D01*
G02X1061727Y594632I-2J1502D01*
G01X1061688Y594642D01*
X1061610Y594629D01*
X1061301Y594436D01*
X1061255Y594371D01*
X1061246Y594332D01*
G02X1061242Y594315I-1464J336D01*
G01X1061232Y594275D01*
X1061246Y594195D01*
X1061447Y593882D01*
X1061513Y593836D01*
X1061554Y593828D01*
G02X1062769Y592354I-287J-1474D01*
G02X1062308Y591271I-1503J0D01*
G01X1062277Y591242D01*
X1062246Y591166D01*
X1062254Y590786D01*
X1062289Y590711D01*
X1062321Y590683D01*
G02X1062830Y589556I-993J-1127D01*
G02X1059826I-1502J0D01*
G02X1060287Y590639I1503J0D01*
G01X1060318Y590668D01*
X1060349Y590744D01*
X1060341Y591124D01*
X1060306Y591199D01*
X1060274Y591227D01*
G02X1059765Y592354I993J1127D01*
G02X1059807Y592707I1502J0D01*
G01X1059817Y592747D01*
X1059803Y592827D01*
X1059602Y593140D01*
X1059536Y593186D01*
X1059495Y593194D01*
G02X1058280Y594668I287J1474D01*
G02X1058840Y595838I1502J0D01*
G01X1058875Y595866D01*
X1058914Y595944D01*
X1058922Y596341D01*
X1058887Y596421D01*
X1058853Y596450D01*
G02X1058341Y597580I991J1130D01*
G02X1059843Y599082I1502J0D01*
G02X1060100Y599060I1J-1502D01*
G01X1060146Y599052D01*
X1060234Y599077D01*
G37*
G36*
G01X1060863Y614193D02*
X1060945Y614575D01*
X1060927Y614659D01*
X1060900Y614694D01*
G02X1060596Y615600I1198J906D01*
G02X1063600I1502J0D01*
G02X1062821Y614283I-1503J0D01*
G01X1062782Y614262D01*
X1062731Y614193D01*
X1062649Y613811D01*
X1062667Y613727D01*
X1062694Y613692D01*
G02X1062998Y612786I-1198J-906D01*
G02X1062558Y611723I-1502J-1D01*
G01X1062532Y611697D01*
X1062502Y611631D01*
X1062481Y611293D01*
X1062503Y611223D01*
X1062525Y611194D01*
G02X1062844Y610269I-1182J-925D01*
G02X1062619Y609478I-1503J0D01*
G01X1062597Y609443D01*
X1062585Y609361D01*
X1062683Y608998D01*
X1062734Y608934D01*
X1062771Y608914D01*
G02X1063568Y607588I-705J-1326D01*
G02X1060564I-1502J0D01*
G02X1060789Y608379I1503J0D01*
G01X1060811Y608414D01*
X1060823Y608496D01*
X1060725Y608859D01*
X1060674Y608923D01*
X1060637Y608943D01*
G02X1059840Y610269I705J1326D01*
G02X1060280Y611332I1502J1D01*
G01X1060306Y611358D01*
X1060336Y611424D01*
X1060357Y611762D01*
X1060335Y611832D01*
X1060313Y611861D01*
G02X1059994Y612786I1182J925D01*
G02X1060773Y614103I1503J0D01*
G01X1060812Y614124D01*
X1060863Y614193D01*
G37*
G36*
G01X1100909Y1530229D02*
X1100801Y1530176D01*
G03X1100707Y1530079I88J-179D01*
G02X1099339Y1529198I-1368J622D01*
G02Y1532202I0J1502D01*
G02X1099697Y1532159I1J-1502D01*
G03X1099832Y1532173I48J194D01*
G01X1099940Y1532226D01*
G03X1100034Y1532323I-88J179D01*
G02X1101402Y1533204I1368J-622D01*
G02Y1530200I0J-1502D01*
G02X1101044Y1530243I-1J1502D01*
G03X1100909Y1530229I-48J-194D01*
G37*
G36*
G01X1098093Y1534671D02*
G02X1096780Y1533898I-1313J729D01*
G02Y1536902I0J1502D01*
G02X1097930Y1536366I0J-1502D01*
G03X1098587Y1536429I307J257D01*
G02X1099900Y1537202I1313J-729D01*
G02Y1534198I0J-1502D01*
G02X1098750Y1534734I0J1502D01*
G03X1098093Y1534671I-307J-257D01*
G37*
G36*
G01X1097237Y1561140D02*
G02X1096264Y1560783I-972J1145D01*
G02Y1563787I0J1502D01*
G02X1097745Y1562536I0J-1502D01*
G03X1098398Y1562298I394J67D01*
G02X1099371Y1562655I972J-1145D01*
G02Y1559651I0J-1502D01*
G02X1097890Y1560902I0J1502D01*
G03X1097237Y1561140I-394J-67D01*
G37*
G36*
G01X1294889Y1123348D02*
X1294879Y1123722D01*
X1294845Y1123796D01*
X1294813Y1123824D01*
G02X1294313Y1124943I1002J1119D01*
G02X1297317I1502J0D01*
G02X1296878Y1123882I-1502J0D01*
G01X1296848Y1123852D01*
X1296819Y1123777D01*
X1296829Y1123403D01*
X1296863Y1123329D01*
X1296895Y1123301D01*
G02X1297395Y1122182I-1002J-1119D01*
G02X1294391I-1502J0D01*
G02X1294830Y1123243I1502J0D01*
G01X1294860Y1123273D01*
X1294889Y1123348D01*
G37*
G36*
G01X1254816Y1194603D02*
X1254513Y1194449D01*
X1254465Y1194396D01*
X1254452Y1194362D01*
G02X1253056Y1193415I-1396J555D01*
G02Y1196419I0J1502D01*
G02X1253429Y1196372I0J-1502D01*
G01X1253466Y1196363D01*
X1253536Y1196370D01*
X1253839Y1196524D01*
X1253887Y1196577D01*
X1253900Y1196611D01*
G02X1255296Y1197558I1396J-555D01*
G02Y1194554I0J-1502D01*
G02X1254923Y1194601I0J1502D01*
G01X1254886Y1194610D01*
X1254816Y1194603D01*
G37*
G36*
G01X1317095Y1199403D02*
Y1199739D01*
X1317070Y1199806D01*
X1317046Y1199834D01*
G02X1316676Y1200821I1131J987D01*
G02X1319680I1502J0D01*
G02X1319310Y1199834I-1501J0D01*
G01X1319286Y1199806D01*
X1319261Y1199739D01*
Y1199403D01*
X1319286Y1199336D01*
X1319310Y1199308D01*
G02X1319680Y1198321I-1131J-987D01*
G02X1316676I-1502J0D01*
G02X1317046Y1199308I1501J0D01*
G01X1317070Y1199336D01*
X1317095Y1199403D01*
G37*
G36*
G01X1330560D02*
Y1199739D01*
X1330535Y1199806D01*
X1330511Y1199834D01*
G02X1330141Y1200821I1131J987D01*
G02X1333145I1502J0D01*
G02X1332775Y1199834I-1501J0D01*
G01X1332751Y1199806D01*
X1332726Y1199739D01*
Y1199403D01*
X1332751Y1199336D01*
X1332775Y1199308D01*
G02X1333145Y1198321I-1131J-987D01*
G02X1330141I-1502J0D01*
G02X1330511Y1199308I1501J0D01*
G01X1330535Y1199336D01*
X1330560Y1199403D01*
G37*
G36*
G01X1336025D02*
Y1199739D01*
X1336000Y1199806D01*
X1335976Y1199834D01*
G02X1335606Y1200821I1131J987D01*
G02X1338610I1502J0D01*
G02X1338240Y1199834I-1501J0D01*
G01X1338216Y1199806D01*
X1338191Y1199739D01*
Y1199403D01*
X1338216Y1199336D01*
X1338240Y1199308D01*
G02X1338610Y1198321I-1131J-987D01*
G02X1335606I-1502J0D01*
G02X1335976Y1199308I1501J0D01*
G01X1336000Y1199336D01*
X1336025Y1199403D01*
G37*
G36*
G01X1344025D02*
Y1199739D01*
X1344000Y1199806D01*
X1343976Y1199834D01*
G02X1343606Y1200821I1131J987D01*
G02X1346610I1502J0D01*
G02X1346240Y1199834I-1501J0D01*
G01X1346216Y1199806D01*
X1346191Y1199739D01*
Y1199403D01*
X1346216Y1199336D01*
X1346240Y1199308D01*
G02X1346610Y1198321I-1131J-987D01*
G02X1343606I-1502J0D01*
G02X1343976Y1199308I1501J0D01*
G01X1344000Y1199336D01*
X1344025Y1199403D01*
G37*
G36*
G01X1362955D02*
Y1199739D01*
X1362930Y1199806D01*
X1362906Y1199834D01*
G02X1362536Y1200821I1131J987D01*
G02X1365540I1502J0D01*
G02X1365170Y1199834I-1501J0D01*
G01X1365146Y1199806D01*
X1365121Y1199739D01*
Y1199403D01*
X1365146Y1199336D01*
X1365170Y1199308D01*
G02X1365540Y1198321I-1131J-987D01*
G02X1362536I-1502J0D01*
G02X1362906Y1199308I1501J0D01*
G01X1362930Y1199336D01*
X1362955Y1199403D01*
G37*
G36*
G01X1319410Y1210487D02*
Y1210823D01*
X1319385Y1210890D01*
X1319361Y1210918D01*
G02X1318991Y1211905I1131J987D01*
G02X1321995I1502J0D01*
G02X1321625Y1210918I-1501J0D01*
G01X1321601Y1210890D01*
X1321576Y1210823D01*
Y1210487D01*
X1321601Y1210420D01*
X1321625Y1210392D01*
G02Y1208418I-1131J-987D01*
G01X1321601Y1208390D01*
X1321576Y1208323D01*
Y1207987D01*
X1321601Y1207920D01*
X1321625Y1207892D01*
G02Y1205918I-1131J-987D01*
G01X1321601Y1205890D01*
X1321576Y1205823D01*
Y1205487D01*
X1321601Y1205420D01*
X1321625Y1205392D01*
G02X1321995Y1204405I-1131J-987D01*
G02X1318991I-1502J0D01*
G02X1319361Y1205392I1501J0D01*
G01X1319385Y1205420D01*
X1319410Y1205487D01*
Y1205823D01*
X1319385Y1205890D01*
X1319361Y1205918D01*
G02Y1207892I1131J987D01*
G01X1319385Y1207920D01*
X1319410Y1207987D01*
Y1208323D01*
X1319385Y1208390D01*
X1319361Y1208418D01*
G02Y1210392I1131J987D01*
G01X1319385Y1210420D01*
X1319410Y1210487D01*
G37*
G36*
G01X1346340D02*
Y1210823D01*
X1346315Y1210890D01*
X1346291Y1210918D01*
G02X1345921Y1211905I1131J987D01*
G02X1348925I1502J0D01*
G02X1348555Y1210918I-1501J0D01*
G01X1348531Y1210890D01*
X1348506Y1210823D01*
Y1210487D01*
X1348531Y1210420D01*
X1348555Y1210392D01*
G02Y1208418I-1131J-987D01*
G01X1348531Y1208390D01*
X1348506Y1208323D01*
Y1207987D01*
X1348531Y1207920D01*
X1348555Y1207892D01*
G02Y1205918I-1131J-987D01*
G01X1348531Y1205890D01*
X1348506Y1205823D01*
Y1205487D01*
X1348531Y1205420D01*
X1348555Y1205392D01*
G02X1348925Y1204405I-1131J-987D01*
G02X1345921I-1502J0D01*
G02X1346291Y1205392I1501J0D01*
G01X1346315Y1205420D01*
X1346340Y1205487D01*
Y1205823D01*
X1346315Y1205890D01*
X1346291Y1205918D01*
G02Y1207892I1131J987D01*
G01X1346315Y1207920D01*
X1346340Y1207987D01*
Y1208323D01*
X1346315Y1208390D01*
X1346291Y1208418D01*
G02Y1210392I1131J987D01*
G01X1346315Y1210420D01*
X1346340Y1210487D01*
G37*
G36*
G01X1333710Y1210699D02*
Y1211035D01*
X1333685Y1211102D01*
X1333661Y1211130D01*
G02X1333291Y1212117I1131J987D01*
G02X1336295I1502J0D01*
G02X1335925Y1211130I-1501J0D01*
G01X1335901Y1211102D01*
X1335876Y1211035D01*
Y1210699D01*
X1335901Y1210632D01*
X1335925Y1210604D01*
G02Y1208630I-1131J-987D01*
G01X1335901Y1208602D01*
X1335876Y1208535D01*
Y1208199D01*
X1335901Y1208132D01*
X1335925Y1208104D01*
G02Y1206130I-1131J-987D01*
G01X1335901Y1206102D01*
X1335876Y1206035D01*
Y1205699D01*
X1335901Y1205632D01*
X1335925Y1205604D01*
G02X1336295Y1204617I-1131J-987D01*
G02X1333291I-1502J0D01*
G02X1333661Y1205604I1501J0D01*
G01X1333685Y1205632D01*
X1333710Y1205699D01*
Y1206035D01*
X1333685Y1206102D01*
X1333661Y1206130D01*
G02Y1208104I1131J987D01*
G01X1333685Y1208132D01*
X1333710Y1208199D01*
Y1208535D01*
X1333685Y1208602D01*
X1333661Y1208630D01*
G02Y1210604I1131J987D01*
G01X1333685Y1210632D01*
X1333710Y1210699D01*
G37*
G36*
G01X1360640D02*
Y1211035D01*
X1360615Y1211102D01*
X1360591Y1211130D01*
G02X1360221Y1212117I1131J987D01*
G02X1363225I1502J0D01*
G02X1362855Y1211130I-1501J0D01*
G01X1362831Y1211102D01*
X1362806Y1211035D01*
Y1210699D01*
X1362831Y1210632D01*
X1362855Y1210604D01*
G02Y1208630I-1131J-987D01*
G01X1362831Y1208602D01*
X1362806Y1208535D01*
Y1208199D01*
X1362831Y1208132D01*
X1362855Y1208104D01*
G02Y1206130I-1131J-987D01*
G01X1362831Y1206102D01*
X1362806Y1206035D01*
Y1205699D01*
X1362831Y1205632D01*
X1362855Y1205604D01*
G02X1363225Y1204617I-1131J-987D01*
G02X1360221I-1502J0D01*
G02X1360591Y1205604I1501J0D01*
G01X1360615Y1205632D01*
X1360640Y1205699D01*
Y1206035D01*
X1360615Y1206102D01*
X1360591Y1206130D01*
G02Y1208104I1131J987D01*
G01X1360615Y1208132D01*
X1360640Y1208199D01*
Y1208535D01*
X1360615Y1208602D01*
X1360591Y1208630D01*
G02Y1210604I1131J987D01*
G01X1360615Y1210632D01*
X1360640Y1210699D01*
G37*
G36*
G01X1362218Y1261006D02*
X1362534D01*
G03X1362691Y1261083I-1J200D01*
G02X1365061I1185J-923D01*
G03X1365218Y1261006I158J123D01*
G01X1365534D01*
G03X1365691Y1261083I-1J200D01*
G02X1366876Y1261662I1185J-923D01*
G02X1368378Y1260160I0J-1502D01*
G02X1367799Y1258975I-1502J0D01*
G03X1367722Y1258818I123J-158D01*
G01Y1258502D01*
G03X1367799Y1258345I200J1D01*
G02X1368378Y1257160I-923J-1185D01*
G02X1366876Y1255658I-1502J0D01*
G02X1365691Y1256237I0J1502D01*
G03X1365534Y1256314I-158J-123D01*
G01X1365218D01*
G03X1365061Y1256237I1J-200D01*
G02X1362691I-1185J923D01*
G03X1362534Y1256314I-158J-123D01*
G01X1362218D01*
G03X1362061Y1256237I1J-200D01*
G02X1359691I-1185J923D01*
G03X1359534Y1256314I-158J-123D01*
G01X1359218D01*
G03X1359061Y1256237I1J-200D01*
G02X1356691I-1185J923D01*
G03X1356534Y1256314I-158J-123D01*
G01X1356218D01*
G03X1356061Y1256237I1J-200D01*
G02X1353691I-1185J923D01*
G03X1353534Y1256314I-158J-123D01*
G01X1353218D01*
G03X1353061Y1256237I1J-200D01*
G02X1350691I-1185J923D01*
G03X1350534Y1256314I-158J-123D01*
G01X1350218D01*
G03X1350061Y1256237I1J-200D01*
G02X1347691I-1185J923D01*
G03X1347534Y1256314I-158J-123D01*
G01X1347218D01*
G03X1347061Y1256237I1J-200D01*
G02X1344691I-1185J923D01*
G03X1344534Y1256314I-158J-123D01*
G01X1344218D01*
G03X1344061Y1256237I1J-200D01*
G02X1341691I-1185J923D01*
G03X1341534Y1256314I-158J-123D01*
G01X1341218D01*
G03X1341061Y1256237I1J-200D01*
G02X1338691I-1185J923D01*
G03X1338534Y1256314I-158J-123D01*
G01X1338218D01*
G03X1338061Y1256237I1J-200D01*
G02X1335691I-1185J923D01*
G03X1335534Y1256314I-158J-123D01*
G01X1335218D01*
G03X1335061Y1256237I1J-200D01*
G02X1333876Y1255658I-1185J923D01*
G02X1332374Y1257160I0J1502D01*
G02X1332953Y1258345I1502J0D01*
G03X1333030Y1258502I-123J158D01*
G01Y1258818D01*
G03X1332953Y1258975I-200J-1D01*
G02X1332374Y1260160I923J1185D01*
G02X1333876Y1261662I1502J0D01*
G02X1335061Y1261083I0J-1502D01*
G03X1335218Y1261006I158J123D01*
G01X1335534D01*
G03X1335691Y1261083I-1J200D01*
G02X1338061I1185J-923D01*
G03X1338218Y1261006I158J123D01*
G01X1338534D01*
G03X1338691Y1261083I-1J200D01*
G02X1341061I1185J-923D01*
G03X1341218Y1261006I158J123D01*
G01X1341534D01*
G03X1341691Y1261083I-1J200D01*
G02X1344061I1185J-923D01*
G03X1344218Y1261006I158J123D01*
G01X1344534D01*
G03X1344691Y1261083I-1J200D01*
G02X1347061I1185J-923D01*
G03X1347218Y1261006I158J123D01*
G01X1347534D01*
G03X1347691Y1261083I-1J200D01*
G02X1350061I1185J-923D01*
G03X1350218Y1261006I158J123D01*
G01X1350534D01*
G03X1350691Y1261083I-1J200D01*
G02X1353061I1185J-923D01*
G03X1353218Y1261006I158J123D01*
G01X1353534D01*
G03X1353691Y1261083I-1J200D01*
G02X1356061I1185J-923D01*
G03X1356218Y1261006I158J123D01*
G01X1356534D01*
G03X1356691Y1261083I-1J200D01*
G02X1359061I1185J-923D01*
G03X1359218Y1261006I158J123D01*
G01X1359534D01*
G03X1359691Y1261083I-1J200D01*
G02X1362061I1185J-923D01*
G03X1362218Y1261006I158J123D01*
G37*
G36*
G01X1309299Y1281962D02*
X1308936Y1282096D01*
X1308853Y1282090D01*
X1308814Y1282070D01*
G02X1308107Y1281893I-707J1325D01*
G02Y1284897I0J1502D01*
G02X1309505Y1283943I0J-1501D01*
G01X1309521Y1283902D01*
X1309581Y1283844D01*
X1309944Y1283710D01*
X1310027Y1283716D01*
X1310066Y1283736D01*
G02X1310773Y1283913I707J-1325D01*
G02Y1280909I0J-1502D01*
G02X1309375Y1281863I0J1501D01*
G01X1309359Y1281904D01*
X1309299Y1281962D01*
G37*
G36*
G01X1131012Y1114197D02*
X1131003Y1114246D01*
G02X1130982Y1114468I1181J224D01*
G02X1132184Y1113266I1202J0D01*
G02X1131962Y1113287I2J1202D01*
G01X1131913Y1113296D01*
X1131820Y1113267D01*
X1131515Y1112962D01*
X1131486Y1112869D01*
X1131495Y1112820D01*
G02X1131516Y1112598I-1181J-224D01*
G02X1129112I-1202J0D01*
G02X1129133Y1112820I1202J-2D01*
G01X1129142Y1112869D01*
X1129113Y1112962D01*
X1128808Y1113267D01*
X1128715Y1113296D01*
X1128666Y1113287D01*
G02X1128444Y1113266I-224J1181D01*
G02X1129646Y1114468I0J1202D01*
G02X1129625Y1114246I-1202J2D01*
G01X1129616Y1114197D01*
X1129645Y1114104D01*
X1129950Y1113799D01*
X1130043Y1113770D01*
X1130092Y1113779D01*
G02X1130314Y1113800I224J-1181D01*
G02X1130536Y1113779I-2J-1202D01*
G01X1130585Y1113770D01*
X1130678Y1113799D01*
X1130983Y1114104D01*
X1131012Y1114197D01*
G37*
G36*
G01X1261874Y1134041D02*
G02X1260539Y1133227I-1335J688D01*
G02Y1136231I0J1502D01*
G02X1261874Y1135417I0J-1502D01*
G03X1262586I356J183D01*
G02X1263921Y1136231I1335J-688D01*
G02Y1133227I0J-1502D01*
G02X1262586Y1134041I0J1502D01*
G03X1261874I-356J-183D01*
G37*
G36*
G01X1274323Y1134422D02*
X1274315Y1134468D01*
G02X1274292Y1134729I1479J262D01*
G02X1275794Y1133227I1502J0D01*
G02X1275750Y1133228I12J1502D01*
G01X1275704Y1133229D01*
X1275623Y1133193D01*
X1275360Y1132889D01*
X1275336Y1132804D01*
X1275344Y1132758D01*
G02X1275367Y1132497I-1479J-262D01*
G02X1272363I-1502J0D01*
G02X1272386Y1132759I1502J0D01*
G01X1272394Y1132804D01*
X1272370Y1132890D01*
X1272106Y1133194D01*
X1272023Y1133230D01*
X1271977Y1133228D01*
G02X1271921Y1133227I-55J1501D01*
G02X1271751Y1133237I3J1502D01*
G01X1271700Y1133242D01*
X1271608Y1133206D01*
X1271328Y1132875D01*
X1271307Y1132779D01*
X1271321Y1132730D01*
G02X1271378Y1132319I-1445J-410D01*
G02X1268374I-1502J0D01*
G02X1268429Y1132723I1502J1D01*
G01X1268443Y1132771D01*
X1268423Y1132865D01*
X1268155Y1133195D01*
X1268068Y1133233D01*
X1268018Y1133230D01*
G02X1267921Y1133227I-95J1499D01*
G02X1269423Y1134729I0J1502D01*
G02X1269368Y1134325I-1502J-1D01*
G01X1269354Y1134277D01*
X1269374Y1134183D01*
X1269642Y1133853D01*
X1269729Y1133815D01*
X1269779Y1133818D01*
G02X1269876Y1133821I95J-1499D01*
G02X1270046Y1133811I-3J-1502D01*
G01X1270097Y1133806D01*
X1270189Y1133842D01*
X1270469Y1134173D01*
X1270490Y1134269D01*
X1270476Y1134318D01*
G02X1270419Y1134729I1445J410D01*
G02X1273423I1502J0D01*
G02X1273400Y1134467I-1502J0D01*
G01X1273392Y1134422D01*
X1273416Y1134336D01*
X1273680Y1134032D01*
X1273763Y1133996D01*
X1273809Y1133998D01*
G02X1273865Y1133999I55J-1501D01*
G02X1273909Y1133998I-12J-1502D01*
G01X1273955Y1133997D01*
X1274036Y1134033D01*
X1274299Y1134337D01*
X1274323Y1134422D01*
G37*
G36*
G01X1205815Y1136638D02*
X1205806Y1136687D01*
G02X1205785Y1136909I1181J224D01*
G02X1208189I1202J0D01*
G02X1208168Y1136687I-1202J2D01*
G01X1208159Y1136638D01*
X1208188Y1136544D01*
X1208492Y1136240D01*
X1208587Y1136211D01*
X1208635Y1136220D01*
G02X1208858Y1136241I224J-1181D01*
G02X1207656Y1135039I0J-1202D01*
G02X1207677Y1135261I1202J-2D01*
G01X1207686Y1135310D01*
X1207657Y1135404D01*
X1207353Y1135708D01*
X1207258Y1135737D01*
X1207210Y1135728D01*
G02X1206987Y1135707I-224J1181D01*
G02X1206765Y1135728I2J1202D01*
G01X1206716Y1135737D01*
X1206623Y1135708D01*
X1206318Y1135403D01*
X1206289Y1135310D01*
X1206298Y1135261D01*
G02X1206319Y1135039I-1181J-224D01*
G02X1205117Y1136241I-1202J0D01*
G02X1205339Y1136220I-2J-1202D01*
G01X1205388Y1136211D01*
X1205481Y1136240D01*
X1205786Y1136545D01*
X1205815Y1136638D01*
G37*
G36*
G01X1239477D02*
X1239468Y1136687D01*
G02X1239447Y1136909I1181J224D01*
G02X1240649Y1138111I1202J0D01*
G02X1241587Y1137661I0J-1203D01*
G03X1241743Y1137586I156J125D01*
G01X1242055D01*
G03X1242211Y1137661I0J200D01*
G02X1243149Y1138111I938J-753D01*
G02Y1135707I0J-1202D01*
G02X1242211Y1136157I0J1203D01*
G03X1242055Y1136232I-156J-125D01*
G01X1241743D01*
G03X1241587Y1136157I0J-200D01*
G02X1240649Y1135707I-938J753D01*
G02X1240427Y1135728I2J1202D01*
G01X1240378Y1135737D01*
X1240285Y1135708D01*
X1239980Y1135403D01*
X1239951Y1135310D01*
X1239960Y1135261D01*
G02X1239981Y1135039I-1181J-224D01*
G02X1237577I-1202J0D01*
G02X1237598Y1135261I1202J-2D01*
G01X1237607Y1135310D01*
X1237578Y1135403D01*
X1237273Y1135708D01*
X1237180Y1135737D01*
X1237131Y1135728D01*
G02X1236909Y1135707I-224J1181D01*
G02X1236687Y1135728I2J1202D01*
G01X1236638Y1135737D01*
X1236545Y1135708D01*
X1236240Y1135403D01*
X1236211Y1135310D01*
X1236220Y1135261D01*
G02X1236241Y1135039I-1181J-224D01*
G02X1233837I-1202J0D01*
G02X1233858Y1135261I1202J-2D01*
G01X1233867Y1135310D01*
X1233838Y1135403D01*
X1233533Y1135708D01*
X1233440Y1135737D01*
X1233391Y1135728D01*
G02X1233169Y1135707I-224J1181D01*
G02X1233014Y1135717I0J1202D01*
G01X1232966Y1135723D01*
X1232877Y1135692D01*
X1232587Y1135391D01*
X1232559Y1135301D01*
X1232567Y1135254D01*
G02X1232586Y1135039I-1269J-220D01*
G02X1230010I-1288J0D01*
G02X1230029Y1135254I1288J-5D01*
G01X1230036Y1135301D01*
X1230009Y1135391D01*
X1229719Y1135692D01*
X1229630Y1135723D01*
X1229583Y1135717D01*
G02X1229428Y1135707I-155J1192D01*
G02X1229273Y1135717I0J1202D01*
G01X1229226Y1135723D01*
X1229137Y1135692D01*
X1228847Y1135391D01*
X1228820Y1135301D01*
X1228827Y1135254D01*
G02X1228846Y1135039I-1269J-220D01*
G02X1227558Y1136326I-1288J-1D01*
G02X1227773Y1136308I1J-1287D01*
G01X1227820Y1136301D01*
X1227910Y1136328D01*
X1228211Y1136618D01*
X1228242Y1136707D01*
X1228236Y1136754D01*
G02X1228226Y1136909I1192J155D01*
G02X1230630I1202J0D01*
G02X1230620Y1136754I-1202J0D01*
G01X1230614Y1136707D01*
X1230645Y1136618D01*
X1230946Y1136328D01*
X1231036Y1136301D01*
X1231083Y1136308D01*
G02X1231298Y1136326I214J-1269D01*
G02X1231513Y1136308I1J-1287D01*
G01X1231561Y1136300D01*
X1231651Y1136328D01*
X1231952Y1136617D01*
X1231983Y1136707D01*
X1231977Y1136754D01*
G02X1231967Y1136909I1192J155D01*
G02X1234371I1202J0D01*
G02X1234350Y1136687I-1202J2D01*
G01X1234341Y1136638D01*
X1234370Y1136545D01*
X1234675Y1136240D01*
X1234768Y1136211D01*
X1234817Y1136220D01*
G02X1235039Y1136241I224J-1181D01*
G02X1235261Y1136220I-2J-1202D01*
G01X1235310Y1136211D01*
X1235403Y1136240D01*
X1235708Y1136545D01*
X1235737Y1136638D01*
X1235728Y1136687D01*
G02X1235707Y1136909I1181J224D01*
G02X1238111I1202J0D01*
G02X1238090Y1136687I-1202J2D01*
G01X1238081Y1136638D01*
X1238110Y1136545D01*
X1238415Y1136240D01*
X1238508Y1136211D01*
X1238557Y1136220D01*
G02X1238779Y1136241I224J-1181D01*
G02X1239001Y1136220I-2J-1202D01*
G01X1239050Y1136211D01*
X1239143Y1136240D01*
X1239448Y1136545D01*
X1239477Y1136638D01*
G37*
G36*
G01X1281988Y1148843D02*
G02X1281328Y1150087I842J1244D01*
G02X1284332I1502J0D01*
G02X1283672Y1148843I-1502J0D01*
G03Y1148181I224J-331D01*
G02X1284332Y1146937I-842J-1244D01*
G02X1281328I-1502J0D01*
G02X1281988Y1148181I1502J0D01*
G03Y1148843I-224J331D01*
G37*
G36*
G01X1266809Y1158669D02*
G02X1266709Y1158666I-95J1499D01*
G02X1268211Y1160168I0J1502D01*
G02X1268097Y1159594I-1502J0D01*
G03X1268493Y1159043I370J-152D01*
G02X1268593Y1159046I95J-1499D01*
G02X1267091Y1157544I0J-1502D01*
G02X1267205Y1158118I1502J0D01*
G03X1266809Y1158669I-370J152D01*
G37*
G36*
G01X1256821Y1187433D02*
G02X1255628Y1186843I-1193J911D01*
G02Y1189847I0J1502D01*
G02X1256889Y1189161I0J-1502D01*
G03X1257543Y1189135I336J217D01*
G02X1258736Y1189725I1193J-911D01*
G02Y1186721I0J-1502D01*
G02X1257475Y1187407I0J1502D01*
G03X1256821Y1187433I-336J-217D01*
G37*
G36*
G01X1212820Y1193700D02*
G02X1212598Y1193679I-224J1181D01*
G02X1213800Y1194881I0J1202D01*
G02X1213779Y1194659I-1202J2D01*
G03X1214246Y1194192I393J-74D01*
G02X1214468Y1194213I224J-1181D01*
G02X1213266Y1193011I0J-1202D01*
G02X1213287Y1193233I1202J-2D01*
G03X1212820Y1193700I-393J74D01*
G37*
G36*
G01X1222646Y1194610D02*
X1222637Y1194659D01*
G02X1222616Y1194881I1181J224D01*
G02X1225020I1202J0D01*
G02X1224999Y1194659I-1202J2D01*
G01X1224990Y1194610D01*
X1225019Y1194517D01*
X1225324Y1194212D01*
X1225417Y1194183D01*
X1225466Y1194192D01*
G02X1225688Y1194213I224J-1181D01*
G02X1224486Y1193011I0J-1202D01*
G02X1224507Y1193233I1202J-2D01*
G01X1224516Y1193282D01*
X1224487Y1193375D01*
X1224182Y1193680D01*
X1224089Y1193709D01*
X1224040Y1193700D01*
G02X1223818Y1193679I-224J1181D01*
G02X1223596Y1193700I2J1202D01*
G01X1223547Y1193709D01*
X1223454Y1193680D01*
X1223149Y1193375D01*
X1223120Y1193282D01*
X1223129Y1193233D01*
G02X1223150Y1193011I-1181J-224D01*
G02X1221948Y1194213I-1202J0D01*
G02X1222170Y1194192I-2J-1202D01*
G01X1222219Y1194183D01*
X1222312Y1194212D01*
X1222617Y1194517D01*
X1222646Y1194610D01*
G37*
G36*
G01X1233867Y1198350D02*
X1233858Y1198399D01*
G02X1233837Y1198621I1181J224D01*
G02X1235039Y1197419I1202J0D01*
G02X1234817Y1197440I2J1202D01*
G01X1234768Y1197449D01*
X1234675Y1197420D01*
X1234370Y1197115D01*
X1234341Y1197022D01*
X1234350Y1196973D01*
G02X1234371Y1196751I-1181J-224D01*
G02X1231967I-1202J0D01*
G02X1231988Y1196973I1202J-2D01*
G01X1231997Y1197022D01*
X1231968Y1197116D01*
X1231664Y1197420D01*
X1231569Y1197449D01*
X1231521Y1197440D01*
G02X1231298Y1197419I-224J1181D01*
G02X1231076Y1197440I2J1202D01*
G01X1231027Y1197449D01*
X1230934Y1197420D01*
X1230629Y1197115D01*
X1230600Y1197022D01*
X1230609Y1196973D01*
G02X1230630Y1196751I-1181J-224D01*
G02X1228226I-1202J0D01*
G02X1228247Y1196973I1202J-2D01*
G01X1228256Y1197022D01*
X1228227Y1197115D01*
X1227922Y1197420D01*
X1227829Y1197449D01*
X1227780Y1197440D01*
G02X1227558Y1197419I-224J1181D01*
G02X1228760Y1198621I0J1202D01*
G02X1228739Y1198399I-1202J2D01*
G01X1228730Y1198350D01*
X1228759Y1198257D01*
X1229064Y1197952D01*
X1229157Y1197923D01*
X1229206Y1197932D01*
G02X1229428Y1197953I224J-1181D01*
G02X1229650Y1197932I-2J-1202D01*
G01X1229699Y1197923D01*
X1229792Y1197952D01*
X1230097Y1198257D01*
X1230126Y1198350D01*
X1230117Y1198399D01*
G02X1230096Y1198621I1181J224D01*
G02X1232500I1202J0D01*
G02X1232479Y1198399I-1202J2D01*
G01X1232470Y1198350D01*
X1232499Y1198256D01*
X1232803Y1197952D01*
X1232898Y1197923D01*
X1232946Y1197932D01*
G02X1233169Y1197953I224J-1181D01*
G02X1233391Y1197932I-2J-1202D01*
G01X1233440Y1197923D01*
X1233533Y1197952D01*
X1233838Y1198257D01*
X1233867Y1198350D01*
G37*
G36*
G01X1263090Y1201265D02*
G02X1264575Y1202545I1485J-221D01*
G02Y1199541I0J-1502D01*
G02X1263662Y1199850I0J1503D01*
G03X1263023Y1199592I-243J-317D01*
G02X1261538Y1198312I-1485J221D01*
G02Y1201316I0J1502D01*
G02X1262451Y1201007I0J-1503D01*
G03X1263090Y1201265I243J317D01*
G37*
G36*
G01X1277954Y1213555D02*
X1277942Y1213607D01*
G02X1277900Y1213958I1460J353D01*
G02X1279402Y1212456I1502J0D01*
G02X1279051Y1212498I2J1502D01*
G01X1278999Y1212510D01*
X1278900Y1212482D01*
X1278584Y1212166D01*
X1278556Y1212067D01*
X1278568Y1212015D01*
G02X1278610Y1211664I-1460J-353D01*
G02X1277108Y1210162I-1502J0D01*
G02X1276964Y1210169I1J1502D01*
G01X1276919Y1210173D01*
X1276835Y1210143D01*
X1276553Y1209861D01*
X1276523Y1209778D01*
X1276527Y1209733D01*
G02X1276534Y1209589I-1495J-145D01*
G02X1275032Y1211091I-1502J0D01*
G02X1275176Y1211084I-1J-1502D01*
G01X1275221Y1211080D01*
X1275305Y1211110D01*
X1275587Y1211392D01*
X1275617Y1211475D01*
X1275613Y1211520D01*
G02X1275606Y1211664I1495J145D01*
G02X1277108Y1213166I1502J0D01*
G02X1277459Y1213124I-2J-1502D01*
G01X1277511Y1213112D01*
X1277610Y1213140D01*
X1277926Y1213456D01*
X1277954Y1213555D01*
G37*
G36*
G01X1155323Y1217051D02*
X1155314Y1217100D01*
G02X1155293Y1217322I1181J224D01*
G02X1157697I1202J0D01*
G02X1157676Y1217100I-1202J2D01*
G01X1157667Y1217051D01*
X1157696Y1216958D01*
X1158001Y1216653D01*
X1158094Y1216624D01*
X1158143Y1216633D01*
G02X1158365Y1216654I224J-1181D01*
G02X1157163Y1215452I0J-1202D01*
G02X1157184Y1215674I1202J-2D01*
G01X1157193Y1215723D01*
X1157164Y1215816D01*
X1156859Y1216121D01*
X1156766Y1216150D01*
X1156717Y1216141D01*
G02X1156495Y1216120I-224J1181D01*
G02X1156273Y1216141I2J1202D01*
G01X1156224Y1216150D01*
X1156131Y1216121D01*
X1155826Y1215816D01*
X1155797Y1215723D01*
X1155806Y1215674D01*
G02X1155827Y1215452I-1181J-224D01*
G02X1153423I-1202J0D01*
G02X1153444Y1215674I1202J-2D01*
G01X1153453Y1215723D01*
X1153424Y1215816D01*
X1153119Y1216121D01*
X1153026Y1216150D01*
X1152977Y1216141D01*
G02X1152755Y1216120I-224J1181D01*
G02X1152533Y1216141I2J1202D01*
G01X1152484Y1216150D01*
X1152391Y1216121D01*
X1152086Y1215816D01*
X1152057Y1215723D01*
X1152066Y1215674D01*
G02X1152087Y1215452I-1181J-224D01*
G02X1150885Y1216654I-1202J0D01*
G02X1151107Y1216633I-2J-1202D01*
G01X1151156Y1216624D01*
X1151249Y1216653D01*
X1151554Y1216958D01*
X1151583Y1217051D01*
X1151574Y1217100D01*
G02X1151553Y1217322I1181J224D01*
G02X1153957I1202J0D01*
G02X1153936Y1217100I-1202J2D01*
G01X1153927Y1217051D01*
X1153956Y1216958D01*
X1154261Y1216653D01*
X1154354Y1216624D01*
X1154403Y1216633D01*
G02X1154625Y1216654I224J-1181D01*
G02X1154847Y1216633I-2J-1202D01*
G01X1154896Y1216624D01*
X1154989Y1216653D01*
X1155294Y1216958D01*
X1155323Y1217051D01*
G37*
G36*
G01X1226297Y1224540D02*
X1226289Y1224588D01*
G02X1226270Y1224803I1269J220D01*
G02X1227558Y1223516I1288J1D01*
G02X1227343Y1223534I-1J1287D01*
G01X1227296Y1223542D01*
X1227206Y1223514D01*
X1226905Y1223224D01*
X1226874Y1223135D01*
X1226880Y1223087D01*
G02X1226890Y1222932I-1192J-155D01*
G02X1226869Y1222710I-1202J2D01*
G01X1226860Y1222661D01*
X1226889Y1222568D01*
X1227194Y1222263D01*
X1227287Y1222234D01*
X1227336Y1222243D01*
G02X1227558Y1222264I224J-1181D01*
G02X1226356Y1221062I0J-1202D01*
G02X1226377Y1221284I1202J-2D01*
G01X1226386Y1221333D01*
X1226357Y1221426D01*
X1226052Y1221731D01*
X1225959Y1221760D01*
X1225910Y1221751D01*
G02X1225688Y1221730I-224J1181D01*
G02X1225466Y1221751I2J1202D01*
G01X1225417Y1221760D01*
X1225324Y1221731D01*
X1225019Y1221426D01*
X1224990Y1221333D01*
X1224999Y1221284D01*
G02X1225020Y1221062I-1181J-224D01*
G02X1223818Y1222264I-1202J0D01*
G02X1224040Y1222243I-2J-1202D01*
G01X1224089Y1222234D01*
X1224182Y1222263D01*
X1224487Y1222568D01*
X1224516Y1222661D01*
X1224507Y1222710D01*
G02X1224486Y1222932I1181J224D01*
G02X1224507Y1223155I1202J-1D01*
G01X1224516Y1223203D01*
X1224487Y1223298D01*
X1224183Y1223602D01*
X1224089Y1223631D01*
X1224040Y1223622D01*
G02X1223818Y1223601I-224J1181D01*
G02X1225020Y1224803I0J1202D01*
G02X1224999Y1224580I-1202J1D01*
G01X1224990Y1224532D01*
X1225019Y1224437D01*
X1225323Y1224133D01*
X1225417Y1224104D01*
X1225466Y1224113D01*
G02X1225688Y1224134I224J-1181D01*
G02X1225843Y1224124I0J-1202D01*
G01X1225890Y1224118D01*
X1225980Y1224149D01*
X1226269Y1224450D01*
X1226297Y1224540D01*
G37*
G36*
G01X1272968Y1227959D02*
G02X1272944Y1228226I1478J267D01*
G02X1274446Y1226724I1502J0D01*
G02X1274178Y1226748I-1J1502D01*
G03X1273713Y1226283I-71J-394D01*
G02X1273737Y1226016I-1478J-267D01*
G02X1272235Y1227518I-1502J0D01*
G02X1272503Y1227494I1J-1502D01*
G03X1272968Y1227959I71J394D01*
G37*
G36*
G01X1189883Y425256D02*
X1197183D01*
G02Y417854I0J-3701D01*
G01X1189883D01*
G02Y425256I0J3701D01*
G37*
G36*
G01X1252203Y420612D02*
Y420964D01*
X1252175Y421033D01*
X1252149Y421061D01*
G02X1251743Y422088I1096J1027D01*
G02X1254747I1502J0D01*
G02X1254341Y421061I-1502J0D01*
G01X1254315Y421033D01*
X1254287Y420964D01*
Y420612D01*
X1254315Y420543D01*
X1254341Y420515D01*
G02Y418461I-1096J-1027D01*
G01X1254315Y418433D01*
X1254287Y418364D01*
Y418012D01*
X1254315Y417943D01*
X1254341Y417915D01*
G02X1254747Y416888I-1096J-1027D01*
G02X1251743I-1502J0D01*
G02X1252149Y417915I1502J0D01*
G01X1252175Y417943D01*
X1252203Y418012D01*
Y418364D01*
X1252175Y418433D01*
X1252149Y418461D01*
G02Y420515I1096J1027D01*
G01X1252175Y420543D01*
X1252203Y420612D01*
G37*
G36*
G01X1197530Y431982D02*
X1197533Y432362D01*
X1197499Y432439D01*
X1197468Y432468D01*
G02X1196987Y433570I1022J1102D01*
G02X1199991I1502J0D01*
G02X1199493Y432453I-1502J0D01*
G01X1199462Y432425D01*
X1199427Y432348D01*
X1199424Y431968D01*
X1199458Y431891D01*
X1199489Y431862D01*
G02X1199970Y430760I-1022J-1102D01*
G02X1196966I-1502J0D01*
G02X1197464Y431877I1502J0D01*
G01X1197495Y431905D01*
X1197530Y431982D01*
G37*
G36*
G01X1179035Y438680D02*
Y439016D01*
X1179010Y439083D01*
X1178986Y439111D01*
G02X1178616Y440098I1131J987D01*
G02X1181620I1502J0D01*
G02X1181250Y439111I-1501J0D01*
G01X1181226Y439083D01*
X1181201Y439016D01*
Y438680D01*
X1181226Y438613D01*
X1181250Y438585D01*
G02Y436611I-1131J-987D01*
G01X1181226Y436583D01*
X1181201Y436516D01*
Y436180D01*
X1181226Y436113D01*
X1181250Y436085D01*
G02Y434111I-1131J-987D01*
G01X1181226Y434083D01*
X1181201Y434016D01*
Y433680D01*
X1181226Y433613D01*
X1181250Y433585D01*
G02Y431611I-1131J-987D01*
G01X1181226Y431583D01*
X1181201Y431516D01*
Y431180D01*
X1181226Y431113D01*
X1181250Y431085D01*
G02X1181620Y430098I-1131J-987D01*
G02X1178616I-1502J0D01*
G02X1178986Y431085I1501J0D01*
G01X1179010Y431113D01*
X1179035Y431180D01*
Y431516D01*
X1179010Y431583D01*
X1178986Y431611D01*
G02Y433585I1131J987D01*
G01X1179010Y433613D01*
X1179035Y433680D01*
Y434016D01*
X1179010Y434083D01*
X1178986Y434111D01*
G02Y436085I1131J987D01*
G01X1179010Y436113D01*
X1179035Y436180D01*
Y436516D01*
X1179010Y436583D01*
X1178986Y436611D01*
G02Y438585I1131J987D01*
G01X1179010Y438613D01*
X1179035Y438680D01*
G37*
G36*
G01X1205584Y439393D02*
Y439745D01*
X1205556Y439814D01*
X1205530Y439842D01*
G02X1205124Y440869I1096J1027D01*
G02X1206626Y442371I1502J0D01*
G02X1207732Y441886I1J-1502D01*
G03X1207879Y441821I148J135D01*
G01X1208173D01*
G03X1208320Y441886I-1J200D01*
G02X1209426Y442371I1105J-1017D01*
G02X1210928Y440869I0J-1502D01*
G02X1210522Y439842I-1502J0D01*
G01X1210496Y439814D01*
X1210468Y439745D01*
Y439393D01*
X1210496Y439324D01*
X1210522Y439296D01*
G02Y437242I-1096J-1027D01*
G01X1210496Y437214D01*
X1210468Y437145D01*
Y436793D01*
X1210496Y436724D01*
X1210522Y436696D01*
G02Y434642I-1096J-1027D01*
G01X1210496Y434614D01*
X1210468Y434545D01*
Y434193D01*
X1210496Y434124D01*
X1210522Y434096D01*
G02Y432042I-1096J-1027D01*
G01X1210496Y432014D01*
X1210468Y431945D01*
Y431593D01*
X1210496Y431524D01*
X1210522Y431496D01*
G02X1210928Y430469I-1096J-1027D01*
G02X1209426Y428967I-1502J0D01*
G02X1208320Y429452I-1J1502D01*
G03X1208173Y429517I-148J-135D01*
G01X1207879D01*
G03X1207732Y429452I1J-200D01*
G02X1206626Y428967I-1105J1017D01*
G02X1205124Y430469I0J1502D01*
G02X1205530Y431496I1502J0D01*
G01X1205556Y431524D01*
X1205584Y431593D01*
Y431945D01*
X1205556Y432014D01*
X1205530Y432042D01*
G02Y434096I1096J1027D01*
G01X1205556Y434124D01*
X1205584Y434193D01*
Y434545D01*
X1205556Y434614D01*
X1205530Y434642D01*
G02Y436696I1096J1027D01*
G01X1205556Y436724D01*
X1205584Y436793D01*
Y437145D01*
X1205556Y437214D01*
X1205530Y437242D01*
G02Y439296I1096J1027D01*
G01X1205556Y439324D01*
X1205584Y439393D01*
G37*
G36*
G01X1197590Y453217D02*
X1197598Y453587D01*
X1197569Y453660D01*
X1197540Y453690D01*
G02X1197108Y454744I1070J1054D01*
G02X1200112I1502J0D01*
G02X1199634Y453645I-1502J0D01*
G01X1199604Y453617D01*
X1199572Y453545D01*
X1199564Y453175D01*
X1199593Y453102D01*
X1199622Y453072D01*
G02X1200054Y452018I-1070J-1054D01*
G02X1197050I-1502J0D01*
G02X1197528Y453117I1502J0D01*
G01X1197558Y453145D01*
X1197590Y453217D01*
G37*
G36*
G01X1196687Y460047D02*
G03X1197160Y460400I75J393D01*
G02X1198655Y461752I1495J-151D01*
G02Y458748I0J-1502D01*
G02X1198371Y458775I0J1502D01*
G03X1197898Y458422I-75J-393D01*
G02X1196403Y457070I-1495J151D01*
G02Y460074I0J1502D01*
G02X1196687Y460047I0J-1502D01*
G37*
G36*
G01X1207343Y463780D02*
X1207016Y464035D01*
X1206924Y464054D01*
X1206878Y464041D01*
G02X1206489Y463990I-388J1451D01*
G02Y466994I0J1502D01*
G02X1207985Y465631I0J-1502D01*
G01X1207989Y465584D01*
X1208038Y465505D01*
X1208391Y465287D01*
X1208484Y465279D01*
X1208528Y465296D01*
G02X1209184Y465420I657J-1679D01*
G02X1210986Y463617I-1J-1803D01*
G01Y460217D01*
G02X1209184Y458414I-1802J-1D01*
G02X1208523Y458540I1J1803D01*
G01X1208479Y458557D01*
X1208388Y458550D01*
X1208035Y458341D01*
X1207985Y458265D01*
X1207979Y458218D01*
G02X1206489Y456904I-1490J188D01*
G02Y459908I0J1502D01*
G02X1207017Y459812I0J-1502D01*
G03X1207207Y459838I71J187D01*
G01X1207306Y459911D01*
G03X1207386Y460087I-120J161D01*
G02X1207382Y460217I1798J120D01*
G01Y463617D01*
Y463648D01*
X1207383Y463696D01*
X1207343Y463780D01*
G37*
G36*
G01X1282503Y466541D02*
Y466835D01*
G03X1282438Y466982I-200J-1D01*
G02X1281953Y468088I1017J1105D01*
G02X1284957I1502J0D01*
G02X1284472Y466982I-1502J-1D01*
G03X1284407Y466835I135J-148D01*
G01Y466541D01*
G03X1284472Y466394I200J1D01*
G02X1284957Y465288I-1017J-1105D01*
G02X1281953I-1502J0D01*
G02X1282438Y466394I1502J1D01*
G03X1282503Y466541I-135J148D01*
G37*
G36*
G01X1289137Y468918D02*
X1288801D01*
X1288734Y468893D01*
X1288706Y468869D01*
G02X1287719Y468499I-987J1131D01*
G02Y471503I0J1502D01*
G02X1288706Y471133I0J-1501D01*
G01X1288734Y471109D01*
X1288801Y471084D01*
X1289137D01*
X1289204Y471109D01*
X1289232Y471133D01*
G02X1290219Y471503I987J-1131D01*
G02Y468499I0J-1502D01*
G02X1289232Y468869I0J1501D01*
G01X1289204Y468893D01*
X1289137Y468918D01*
G37*
G36*
G01X1234075Y472316D02*
X1234192Y472287D01*
G03X1234333Y472304I48J194D01*
G02X1235999I833J-1599D01*
G03X1236140Y472287I93J177D01*
G01X1236257Y472316D01*
G03X1236373Y472395I-47J194D01*
G02X1237662Y473062I1289J-912D01*
G02Y469906I0J-1578D01*
G02X1237428Y469923I-3J1578D01*
G01X1237385Y469929D01*
X1237301Y469905D01*
X1237038Y469679D01*
G03X1236968Y469527I130J-152D01*
G01Y468485D01*
G03X1237038Y468333I200J0D01*
G01X1237301Y468107D01*
X1237385Y468083D01*
X1237428Y468089D01*
G02X1237662Y468106I231J-1561D01*
G02Y464950I0J-1578D01*
G02X1236373Y465617I0J1579D01*
G03X1236257Y465696I-163J-115D01*
G01X1236140Y465725D01*
G03X1235999Y465708I-48J-194D01*
G02X1234333I-833J1599D01*
G03X1234192Y465725I-93J-177D01*
G01X1234075Y465696D01*
G03X1233959Y465617I47J-194D01*
G02X1232670Y464950I-1289J912D01*
G02Y468106I0J1578D01*
G02X1232904Y468089I3J-1578D01*
G01X1232947Y468083D01*
X1233031Y468107D01*
X1233294Y468333D01*
G03X1233364Y468485I-130J152D01*
G01Y469527D01*
G03X1233294Y469679I-200J0D01*
G01X1233031Y469905D01*
X1232947Y469929D01*
X1232904Y469923D01*
G02X1232670Y469906I-231J1561D01*
G02Y473062I0J1578D01*
G02X1233959Y472395I0J-1579D01*
G03X1234075Y472316I163J115D01*
G37*
G36*
G01X1244477Y479428D02*
X1244594Y479399D01*
G03X1244735Y479416I48J194D01*
G02X1246401I833J-1599D01*
G03X1246542Y479399I93J177D01*
G01X1246659Y479428D01*
G03X1246775Y479507I-47J194D01*
G02X1248064Y480174I1289J-912D01*
G02Y477018I0J-1578D01*
G02X1247830Y477035I-3J1578D01*
G01X1247787Y477041D01*
X1247703Y477017D01*
X1247440Y476791D01*
G03X1247370Y476639I130J-152D01*
G01Y475597D01*
G03X1247440Y475445I200J0D01*
G01X1247703Y475219D01*
X1247787Y475195D01*
X1247830Y475201D01*
G02X1248064Y475218I231J-1561D01*
G02Y472062I0J-1578D01*
G02X1246775Y472729I0J1579D01*
G03X1246659Y472808I-163J-115D01*
G01X1246542Y472837D01*
G03X1246401Y472820I-48J-194D01*
G02X1244735I-833J1599D01*
G03X1244594Y472837I-93J-177D01*
G01X1244477Y472808D01*
G03X1244361Y472729I47J-194D01*
G02X1243072Y472062I-1289J912D01*
G02Y475218I0J1578D01*
G02X1243306Y475201I3J-1578D01*
G01X1243349Y475195D01*
X1243433Y475219D01*
X1243696Y475445D01*
G03X1243766Y475597I-130J152D01*
G01Y476639D01*
G03X1243696Y476791I-200J0D01*
G01X1243433Y477017D01*
X1243349Y477041D01*
X1243306Y477035D01*
G02X1243072Y477018I-231J1561D01*
G02Y480174I0J1578D01*
G02X1244361Y479507I0J-1579D01*
G03X1244477Y479428I163J115D01*
G37*
G36*
G01X1287087Y486663D02*
X1287423D01*
X1287490Y486688D01*
X1287518Y486712D01*
G02X1289492I987J-1131D01*
G01X1289520Y486688D01*
X1289587Y486663D01*
X1289923D01*
X1289990Y486688D01*
X1290018Y486712D01*
G02X1291005Y487082I987J-1131D01*
G02Y484078I0J-1502D01*
G02X1290018Y484448I0J1501D01*
G01X1289990Y484472D01*
X1289923Y484497D01*
X1289587D01*
X1289520Y484472D01*
X1289492Y484448D01*
G02X1287518I-987J1131D01*
G01X1287490Y484472D01*
X1287423Y484497D01*
X1287087D01*
X1287020Y484472D01*
X1286992Y484448D01*
G02X1286005Y484078I-987J1131D01*
G02Y487082I0J1502D01*
G02X1286992Y486712I0J-1501D01*
G01X1287020Y486688D01*
X1287087Y486663D01*
G37*
G36*
G01X1234075Y486489D02*
X1234192Y486460D01*
G03X1234333Y486477I48J194D01*
G02X1235166Y486682I835J-1598D01*
G02X1235999Y486477I-2J-1803D01*
G03X1236140Y486460I93J177D01*
G01X1236257Y486489D01*
G03X1236373Y486568I-47J194D01*
G02X1237662Y487236I1289J-910D01*
G02Y484078I0J-1579D01*
G02X1237428Y484096I4J1579D01*
G01X1237385Y484102D01*
X1237301Y484078D01*
X1237038Y483852D01*
G03X1236968Y483700I130J-152D01*
G01Y482658D01*
G03X1237038Y482506I200J0D01*
G01X1237301Y482280D01*
X1237385Y482256D01*
X1237428Y482262D01*
G02X1237662Y482280I238J-1561D01*
G02Y479122I0J-1579D01*
G02X1236373Y479790I0J1578D01*
G03X1236257Y479869I-163J-115D01*
G01X1236140Y479898D01*
G03X1235999Y479881I-48J-194D01*
G02X1235166Y479676I-835J1598D01*
G02X1234333Y479881I2J1803D01*
G03X1234192Y479898I-93J-177D01*
G01X1234075Y479869D01*
G03X1233959Y479790I47J-194D01*
G02X1232670Y479122I-1289J910D01*
G02Y482280I0J1579D01*
G02X1232904Y482262I-4J-1579D01*
G01X1232947Y482256D01*
X1233031Y482280D01*
X1233294Y482506D01*
G03X1233364Y482658I-130J152D01*
G01Y483700D01*
G03X1233294Y483852I-200J0D01*
G01X1233031Y484078D01*
X1232947Y484102D01*
X1232904Y484096D01*
G02X1232670Y484078I-238J1561D01*
G02Y487236I0J1579D01*
G02X1233959Y486568I0J-1578D01*
G03X1234075Y486489I163J115D01*
G37*
G36*
G01X1278422Y488652D02*
Y488988D01*
X1278397Y489055D01*
X1278373Y489083D01*
G02X1278003Y490070I1131J987D01*
G02X1281007I1502J0D01*
G02X1280637Y489083I-1501J0D01*
G01X1280613Y489055D01*
X1280588Y488988D01*
Y488652D01*
X1280613Y488585D01*
X1280637Y488557D01*
G02X1281007Y487570I-1131J-987D01*
G02X1278003I-1502J0D01*
G02X1278373Y488557I1501J0D01*
G01X1278397Y488585D01*
X1278422Y488652D01*
G37*
G36*
G01X1244477Y493601D02*
X1244594Y493572D01*
G03X1244735Y493589I48J194D01*
G02X1245568Y493794I835J-1598D01*
G02X1246401Y493589I-2J-1803D01*
G03X1246542Y493572I93J177D01*
G01X1246659Y493601D01*
G03X1246775Y493680I-47J194D01*
G02X1248064Y494348I1289J-910D01*
G02Y491190I0J-1579D01*
G02X1247830Y491208I4J1579D01*
G01X1247787Y491214D01*
X1247703Y491190D01*
X1247440Y490964D01*
G03X1247370Y490812I130J-152D01*
G01Y489770D01*
G03X1247440Y489618I200J0D01*
G01X1247703Y489392D01*
X1247787Y489368D01*
X1247830Y489374D01*
G02X1248064Y489392I238J-1561D01*
G02Y486234I0J-1579D01*
G02X1246775Y486902I0J1578D01*
G03X1246659Y486981I-163J-115D01*
G01X1246542Y487010D01*
G03X1246401Y486993I-48J-194D01*
G02X1245568Y486788I-835J1598D01*
G02X1244735Y486993I2J1803D01*
G03X1244594Y487010I-93J-177D01*
G01X1244477Y486981D01*
G03X1244361Y486902I47J-194D01*
G02X1243072Y486234I-1289J910D01*
G02Y489392I0J1579D01*
G02X1243306Y489374I-4J-1579D01*
G01X1243349Y489368D01*
X1243433Y489392D01*
X1243696Y489618D01*
G03X1243766Y489770I-130J152D01*
G01Y490812D01*
G03X1243696Y490964I-200J0D01*
G01X1243433Y491190D01*
X1243349Y491214D01*
X1243306Y491208D01*
G02X1243072Y491190I-238J1561D01*
G02Y494348I0J1579D01*
G02X1244361Y493680I0J-1578D01*
G03X1244477Y493601I163J115D01*
G37*
G36*
G01X1167715Y437176D02*
G02X1167183Y438323I970J1147D01*
G02X1170187I1502J0D01*
G02X1169060Y436868I-1503J0D01*
G03X1168901Y436176I100J-387D01*
G02X1169433Y435029I-970J-1147D01*
G02X1166429I-1502J0D01*
G02X1167556Y436484I1503J0D01*
G03X1167715Y437176I-100J387D01*
G37*
G36*
G01X1197742Y441939D02*
X1197700Y441970D01*
G02X1197088Y443180I890J1210D01*
G02X1200092I1502J0D01*
G02X1199287Y441850I-1501J0D01*
G01X1199241Y441825D01*
X1199184Y441739D01*
X1199151Y441298D01*
X1199194Y441204D01*
X1199236Y441173D01*
G02X1199848Y439963I-890J-1210D01*
G02X1199306Y438808I-1502J0D01*
G01X1199272Y438779D01*
X1199234Y438701D01*
X1199229Y438309D01*
X1199264Y438229D01*
X1199297Y438200D01*
G02X1199807Y437072I-992J-1128D01*
G02X1196803I-1502J0D01*
G02X1197345Y438227I1502J0D01*
G01X1197379Y438256D01*
X1197417Y438334D01*
X1197422Y438726D01*
X1197387Y438806D01*
X1197354Y438835D01*
G02X1196844Y439963I992J1128D01*
G02X1197649Y441293I1501J0D01*
G01X1197695Y441318D01*
X1197752Y441404D01*
X1197785Y441845D01*
X1197742Y441939D01*
G37*
G36*
G01X1197263Y472106D02*
G02X1197187Y472579I1426J472D01*
G02X1198689Y471077I1502J0D01*
G02X1198323Y471122I-1J1502D01*
G03X1197846Y470609I-97J-388D01*
G02X1197922Y470136I-1426J-472D01*
G02X1196420Y471638I-1502J0D01*
G02X1196786Y471593I1J-1502D01*
G03X1197263Y472106I97J388D01*
G37*
G36*
G01X1299469Y485889D02*
G02X1299304Y485880I-164J1493D01*
G02X1300806Y487382I0J1502D01*
G02X1300727Y486901I-1502J0D01*
G03X1301149Y486375I379J-128D01*
G02X1301314Y486384I164J-1493D01*
G02X1299812Y484882I0J-1502D01*
G02X1299891Y485363I1502J0D01*
G03X1299469Y485889I-379J128D01*
G37*
G36*
G01X1372557Y1018860D02*
G02X1375561I1502J0D01*
G02X1375554Y1018721I-1502J6D01*
G01Y1018719D01*
X1375550Y1018672D01*
X1375585Y1018584D01*
X1375864Y1018338D01*
G03X1376037Y1018292I132J150D01*
G01X1376038D01*
G02X1376359Y1018327I322J-1467D01*
G02Y1015323I0J-1502D01*
G01X1376358D01*
G02X1375884Y1015400I1J1502D01*
G01X1375849Y1015412D01*
X1375776Y1015409D01*
X1375463Y1015274D01*
X1375411Y1015224D01*
X1375395Y1015190D01*
G02X1374034Y1014323I-1361J635D01*
G02X1372532Y1015825I0J1502D01*
G02X1373138Y1017031I1503J0D01*
G01X1373176Y1017059D01*
X1373219Y1017142D01*
X1373222Y1017509D01*
G03X1373144Y1017669I-200J2D01*
G02X1372557Y1018860I915J1191D01*
G37*
G36*
G01X1343465Y1030425D02*
G02X1344967Y1028923I0J-1502D01*
G02X1344482Y1027817I-1504J0D01*
G03X1344417Y1027670I135J-148D01*
G01Y1027376D01*
G03X1344482Y1027229I200J1D01*
G02X1344967Y1026123I-1019J-1106D01*
G02X1343465Y1024621I-1502J0D01*
G02X1342359Y1025106I0J1504D01*
G03X1342212Y1025171I-148J-135D01*
G01X1341918D01*
G03X1341771Y1025106I1J-200D01*
G02X1340665Y1024621I-1106J1019D01*
G02X1339163Y1026123I0J1502D01*
G02X1339648Y1027229I1504J0D01*
G03X1339713Y1027376I-135J148D01*
G01Y1027670D01*
G03X1339648Y1027817I-200J-1D01*
G02X1339163Y1028923I1019J1106D01*
G02X1340665Y1030425I1502J0D01*
G02X1341771Y1029940I0J-1504D01*
G03X1341918Y1029875I148J135D01*
G01X1342212D01*
G03X1342359Y1029940I-1J200D01*
G02X1343465Y1030425I1106J-1019D01*
G37*
G36*
G01X1387813Y1032454D02*
G02Y1029450I0J-1502D01*
G02X1387635Y1029461I3J1502D01*
G01X1387634D01*
G03X1387495Y1029426I-24J-199D01*
G01X1387276Y1029270D01*
G03X1387197Y1029151I116J-163D01*
G02X1385732Y1027980I-1465J331D01*
G02Y1030984I0J1502D01*
G02X1385910Y1030973I-3J-1502D01*
G01X1385911D01*
G03X1386050Y1031008I24J199D01*
G01X1386269Y1031164D01*
G03X1386348Y1031283I-116J163D01*
G02X1387813Y1032454I1465J-331D01*
G37*
G36*
G01X1329221Y1062199D02*
G02X1330723Y1060697I0J-1502D01*
G02X1330317Y1059670I-1502J0D01*
G01X1330291Y1059643D01*
X1330263Y1059572D01*
Y1059222D01*
X1330291Y1059151D01*
X1330317Y1059124D01*
G02X1330723Y1058097I-1096J-1027D01*
G02X1329221Y1056595I-1502J0D01*
G02X1328234Y1056965I0J1501D01*
G01X1328233D01*
Y1056966D01*
G03X1328103Y1057014I-130J-152D01*
G01X1327839D01*
G03X1327709Y1056966I0J-200D01*
G01X1327708Y1056965D01*
G02X1325734I-987J1131D01*
G01X1325733D01*
Y1056966D01*
G03X1325603Y1057014I-130J-152D01*
G01X1325339D01*
G03X1325209Y1056966I0J-200D01*
G01X1325208Y1056965D01*
G02X1323234I-987J1131D01*
G01X1323233D01*
Y1056966D01*
G03X1323103Y1057014I-130J-152D01*
G01X1322839D01*
G03X1322709Y1056966I0J-200D01*
G01X1322708Y1056965D01*
G02X1320734I-987J1131D01*
G01X1320733D01*
Y1056966D01*
G03X1320603Y1057014I-130J-152D01*
G01X1320339D01*
G03X1320209Y1056966I0J-200D01*
G01X1320208Y1056965D01*
G02X1319221Y1056595I-987J1131D01*
G02X1317719Y1058097I0J1502D01*
G02X1318125Y1059124I1502J0D01*
G01X1318151Y1059151D01*
X1318179Y1059222D01*
Y1059572D01*
X1318151Y1059643D01*
X1318125Y1059670D01*
G02X1317719Y1060697I1096J1027D01*
G02X1319221Y1062199I1502J0D01*
G02X1320208Y1061829I0J-1501D01*
G01X1320209D01*
Y1061828D01*
G03X1320339Y1061780I130J152D01*
G01X1320603D01*
G03X1320733Y1061828I0J200D01*
G01X1320734Y1061829D01*
G02X1322708I987J-1131D01*
G01X1322709D01*
Y1061828D01*
G03X1322839Y1061780I130J152D01*
G01X1323103D01*
G03X1323233Y1061828I0J200D01*
G01X1323234Y1061829D01*
G02X1325208I987J-1131D01*
G01X1325209D01*
Y1061828D01*
G03X1325339Y1061780I130J152D01*
G01X1325603D01*
G03X1325733Y1061828I0J200D01*
G01X1325734Y1061829D01*
G02X1327708I987J-1131D01*
G01X1327709D01*
Y1061828D01*
G03X1327839Y1061780I130J152D01*
G01X1328103D01*
G03X1328233Y1061828I0J200D01*
G01X1328234Y1061829D01*
G02X1329221Y1062199I987J-1131D01*
G37*
G36*
G01X1417351D02*
G02X1418853Y1060697I0J-1502D01*
G02X1418447Y1059670I-1502J0D01*
G01X1418421Y1059643D01*
X1418393Y1059572D01*
Y1059222D01*
X1418421Y1059151D01*
X1418447Y1059124D01*
G02X1418853Y1058097I-1096J-1027D01*
G02X1417351Y1056595I-1502J0D01*
G02X1416364Y1056965I0J1501D01*
G01X1416363D01*
Y1056966D01*
G03X1416233Y1057014I-130J-152D01*
G01X1415969D01*
G03X1415839Y1056966I0J-200D01*
G01X1415838Y1056965D01*
G02X1413864I-987J1131D01*
G01X1413863D01*
Y1056966D01*
G03X1413733Y1057014I-130J-152D01*
G01X1413469D01*
G03X1413339Y1056966I0J-200D01*
G01X1413338Y1056965D01*
G02X1411364I-987J1131D01*
G01X1411363D01*
Y1056966D01*
G03X1411233Y1057014I-130J-152D01*
G01X1410969D01*
G03X1410839Y1056966I0J-200D01*
G01X1410838Y1056965D01*
G02X1408864I-987J1131D01*
G01X1408863D01*
Y1056966D01*
G03X1408733Y1057014I-130J-152D01*
G01X1408469D01*
G03X1408339Y1056966I0J-200D01*
G01X1408338Y1056965D01*
G02X1407351Y1056595I-987J1131D01*
G02X1405849Y1058097I0J1502D01*
G02X1406255Y1059124I1502J0D01*
G01X1406281Y1059151D01*
X1406309Y1059222D01*
Y1059572D01*
X1406281Y1059643D01*
X1406255Y1059670D01*
G02X1405849Y1060697I1096J1027D01*
G02X1407351Y1062199I1502J0D01*
G02X1408338Y1061829I0J-1501D01*
G01X1408339D01*
Y1061828D01*
G03X1408469Y1061780I130J152D01*
G01X1408733D01*
G03X1408863Y1061828I0J200D01*
G01X1408864Y1061829D01*
G02X1410838I987J-1131D01*
G01X1410839D01*
Y1061828D01*
G03X1410969Y1061780I130J152D01*
G01X1411233D01*
G03X1411363Y1061828I0J200D01*
G01X1411364Y1061829D01*
G02X1413338I987J-1131D01*
G01X1413339D01*
Y1061828D01*
G03X1413469Y1061780I130J152D01*
G01X1413733D01*
G03X1413863Y1061828I0J200D01*
G01X1413864Y1061829D01*
G02X1415838I987J-1131D01*
G01X1415839D01*
Y1061828D01*
G03X1415969Y1061780I130J152D01*
G01X1416233D01*
G03X1416363Y1061828I0J200D01*
G01X1416364Y1061829D01*
G02X1417351Y1062199I987J-1131D01*
G37*
G36*
G01X1415677Y1088298D02*
G02X1417179Y1086796I0J-1502D01*
G02X1416809Y1085809I-1501J0D01*
G01Y1085808D01*
X1416808D01*
G03X1416760Y1085678I152J-130D01*
G01Y1085414D01*
G03X1416808Y1085284I200J0D01*
G01X1416809Y1085283D01*
G02X1417179Y1084296I-1131J-987D01*
G02X1415677Y1082794I-1502J0D01*
G02X1414690Y1083164I0J1501D01*
G01X1414689D01*
Y1083165D01*
G03X1414559Y1083213I-130J-152D01*
G01X1414295D01*
G03X1414165Y1083165I0J-200D01*
G01X1414164Y1083164D01*
G02X1412190I-987J1131D01*
G01X1412189D01*
Y1083165D01*
G03X1412059Y1083213I-130J-152D01*
G01X1411795D01*
G03X1411665Y1083165I0J-200D01*
G01X1411664Y1083164D01*
G02X1409690I-987J1131D01*
G01X1409689D01*
Y1083165D01*
G03X1409559Y1083213I-130J-152D01*
G01X1409295D01*
G03X1409165Y1083165I0J-200D01*
G01X1409164Y1083164D01*
G02X1407190I-987J1131D01*
G01X1407189D01*
Y1083165D01*
G03X1407059Y1083213I-130J-152D01*
G01X1406795D01*
G03X1406665Y1083165I0J-200D01*
G01X1406664Y1083164D01*
G02X1405677Y1082794I-987J1131D01*
G02X1404175Y1084296I0J1502D01*
G02X1404545Y1085283I1501J0D01*
G01Y1085284D01*
X1404546D01*
G03X1404594Y1085414I-152J130D01*
G01Y1085678D01*
G03X1404546Y1085808I-200J0D01*
G01X1404545Y1085809D01*
G02X1404175Y1086796I1131J987D01*
G02X1405677Y1088298I1502J0D01*
G02X1406664Y1087928I0J-1501D01*
G01X1406665D01*
Y1087927D01*
G03X1406795Y1087879I130J152D01*
G01X1407059D01*
G03X1407189Y1087927I0J200D01*
G01X1407190Y1087928D01*
G02X1409164I987J-1131D01*
G01X1409165D01*
Y1087927D01*
G03X1409295Y1087879I130J152D01*
G01X1409559D01*
G03X1409689Y1087927I0J200D01*
G01X1409690Y1087928D01*
G02X1411664I987J-1131D01*
G01X1411665D01*
Y1087927D01*
G03X1411795Y1087879I130J152D01*
G01X1412059D01*
G03X1412189Y1087927I0J200D01*
G01X1412190Y1087928D01*
G02X1414164I987J-1131D01*
G01X1414165D01*
Y1087927D01*
G03X1414295Y1087879I130J152D01*
G01X1414559D01*
G03X1414689Y1087927I0J200D01*
G01X1414690Y1087928D01*
G02X1415677Y1088298I987J-1131D01*
G37*
G36*
G01X1391189Y1089224D02*
G02X1394193I1502J0D01*
G02X1393823Y1088237I-1501J0D01*
G01Y1088236D01*
X1393822D01*
G03X1393774Y1088106I152J-130D01*
G01Y1087842D01*
G03X1393822Y1087712I200J0D01*
G01X1393823Y1087711D01*
G02Y1085737I-1131J-987D01*
G01Y1085736D01*
X1393822D01*
G03X1393774Y1085606I152J-130D01*
G01Y1085342D01*
G03X1393822Y1085212I200J0D01*
G01X1393823Y1085211D01*
G02Y1083237I-1131J-987D01*
G01Y1083236D01*
X1393822D01*
G03X1393774Y1083106I152J-130D01*
G01Y1082842D01*
G03X1393822Y1082712I200J0D01*
G01X1393823Y1082711D01*
G02X1394193Y1081724I-1131J-987D01*
G02X1392691Y1080222I-1502J0D01*
G02X1391704Y1080592I0J1501D01*
G01X1391703D01*
Y1080593D01*
G03X1391573Y1080641I-130J-152D01*
G01X1391309D01*
G03X1391179Y1080593I0J-200D01*
G01X1391178Y1080592D01*
G02X1390191Y1080222I-987J1131D01*
G02X1388689Y1081724I0J1502D01*
G02X1389059Y1082711I1501J0D01*
G01Y1082712D01*
X1389060D01*
G03X1389108Y1082842I-152J130D01*
G01Y1083106D01*
G03X1389060Y1083236I-200J0D01*
G01X1389059Y1083237D01*
G02Y1085211I1131J987D01*
G01Y1085212D01*
X1389060D01*
G03X1389108Y1085342I-152J130D01*
G01Y1085606D01*
G03X1389060Y1085736I-200J0D01*
G01X1389059Y1085737D01*
G02X1388689Y1086724I1131J987D01*
G02X1390191Y1088226I1502J0D01*
G02X1391239Y1087800I0J-1502D01*
G03X1391378Y1087743I140J143D01*
G01X1391504D01*
G03X1391643Y1087800I-1J200D01*
G02X1391672Y1087827I1038J-1086D01*
G01Y1088037D01*
G03X1391615Y1088176I-200J-1D01*
G02X1391189Y1089224I1076J1048D01*
G37*
G36*
G01X1386949Y1093048D02*
G02X1389953I1502J0D01*
G02X1389423Y1091903I-1502J0D01*
G03X1389352Y1091746I129J-153D01*
G01X1389361Y1091389D01*
X1389402Y1091309D01*
X1389438Y1091281D01*
G02X1390025Y1090090I-915J-1191D01*
G02X1387021I-1502J0D01*
G02X1387551Y1091235I1502J0D01*
G03X1387622Y1091392I-129J153D01*
G01X1387613Y1091749D01*
X1387572Y1091829D01*
X1387536Y1091857D01*
G02X1386949Y1093048I915J1191D01*
G37*
G36*
G01X1350418Y1094590D02*
G02X1351920Y1093088I0J-1502D01*
G02X1351435Y1091982I-1504J0D01*
G03X1351370Y1091835I135J-148D01*
G01Y1091541D01*
G03X1351435Y1091394I200J1D01*
G02X1351920Y1090288I-1019J-1106D01*
G02X1350418Y1088786I-1502J0D01*
G02X1349579Y1089042I0J1503D01*
G01X1349578Y1089043D01*
G03X1349402Y1089066I-111J-166D01*
G01X1349056Y1088949D01*
X1348991Y1088883D01*
X1348976Y1088838D01*
G02X1348684Y1088330I-1423J480D01*
G01Y1088328D01*
X1348683D01*
G03X1348635Y1088198I152J-130D01*
G01Y1087934D01*
G03X1348683Y1087804I200J0D01*
G01X1348684Y1087803D01*
G02Y1085829I-1131J-987D01*
G01Y1085828D01*
X1348683D01*
G03X1348635Y1085698I152J-130D01*
G01Y1085434D01*
G03X1348683Y1085304I200J0D01*
G01X1348684Y1085303D01*
G02Y1083329I-1131J-987D01*
G01Y1083328D01*
X1348683D01*
G03X1348635Y1083198I152J-130D01*
G01Y1082934D01*
G03X1348683Y1082804I200J0D01*
G01X1348684Y1082803D01*
G02X1349054Y1081816I-1131J-987D01*
G02X1347552Y1080314I-1502J0D01*
G02X1346565Y1080684I0J1501D01*
G01X1346564D01*
Y1080685D01*
G03X1346434Y1080733I-130J-152D01*
G01X1346170D01*
G03X1346040Y1080685I0J-200D01*
G01X1346039Y1080684D01*
G02X1345052Y1080314I-987J1131D01*
G02X1343550Y1081816I0J1502D01*
G02X1343920Y1082803I1501J0D01*
G01Y1082804D01*
X1343921D01*
G03X1343969Y1082934I-152J130D01*
G01Y1083198D01*
G03X1343921Y1083328I-200J0D01*
G01X1343920Y1083329D01*
G02Y1085303I1131J987D01*
G01Y1085304D01*
X1343921D01*
G03X1343969Y1085434I-152J130D01*
G01Y1085698D01*
G03X1343921Y1085828I-200J0D01*
G01X1343920Y1085829D01*
G02X1343550Y1086816I1131J987D01*
G02X1345052Y1088318I1502J0D01*
G02X1346100Y1087892I0J-1502D01*
G03X1346239Y1087835I140J143D01*
G01X1346365D01*
G03X1346504Y1087892I-1J200D01*
G02X1346533Y1087919I1038J-1086D01*
G01Y1088129D01*
G03X1346476Y1088268I-200J-1D01*
G02X1346050Y1089316I1076J1048D01*
G02X1346420Y1090303I1501J0D01*
G01Y1090304D01*
X1346421D01*
G03X1346469Y1090434I-152J130D01*
G01Y1090698D01*
G03X1346421Y1090828I-200J0D01*
G01X1346420Y1090829D01*
G02X1346050Y1091816I1131J987D01*
G02X1347552Y1093318I1502J0D01*
G01X1347554D01*
G02X1348339Y1093096I-1J-1502D01*
G01X1348381Y1093070D01*
X1348479Y1093063D01*
X1348872Y1093238D01*
X1348932Y1093314D01*
X1348941Y1093363D01*
G02X1350418Y1094590I1477J-275D01*
G37*
G36*
G01X1414503Y1093088D02*
G02X1417507I1502J0D01*
G02X1417022Y1091982I-1504J0D01*
G03X1416957Y1091835I135J-148D01*
G01Y1091541D01*
G03X1417022Y1091394I200J1D01*
G02X1417507Y1090288I-1019J-1106D01*
G02X1414503I-1502J0D01*
G02X1414988Y1091394I1504J0D01*
G03X1415053Y1091541I-135J148D01*
G01Y1091835D01*
G03X1414988Y1091982I-200J-1D01*
G02X1414503Y1093088I1019J1106D01*
G37*
G36*
G01X1321519Y1093956D02*
G02X1324523I1502J0D01*
G02X1323944Y1092771I-1502J0D01*
G03X1323867Y1092613I123J-158D01*
G01Y1092299D01*
G03X1323944Y1092141I200J0D01*
G02X1324523Y1090956I-923J-1185D01*
G02X1323863Y1089712I-1502J0D01*
G01X1323820Y1089683D01*
X1323773Y1089589D01*
X1323796Y1089142D01*
X1323852Y1089054D01*
X1323899Y1089029D01*
G02X1324225Y1088792I-712J-1322D01*
G01X1324226Y1088791D01*
G03X1324396Y1088739I137J146D01*
G01X1324759Y1088800D01*
X1324834Y1088855D01*
X1324856Y1088897D01*
G02X1325399Y1089482I1333J-692D01*
G01X1325400Y1089483D01*
G03X1325493Y1089634I-106J169D01*
G01X1325527Y1089999D01*
X1325493Y1090086D01*
X1325458Y1090118D01*
G02X1324969Y1091227I1013J1109D01*
G02X1327973I1502J0D01*
G02X1327261Y1089950I-1501J0D01*
G01X1327260Y1089949D01*
G03X1327167Y1089798I106J-169D01*
G01X1327133Y1089433D01*
X1327167Y1089346D01*
X1327202Y1089314D01*
G02X1327374Y1089128I-1013J-1109D01*
G03X1327532Y1089051I158J123D01*
G01X1327846D01*
G03X1328004Y1089128I0J200D01*
G02X1329189Y1089707I1185J-923D01*
G02X1330691Y1088205I0J-1502D01*
G02X1330112Y1087020I-1502J0D01*
G03X1330035Y1086862I123J-158D01*
G01Y1086548D01*
G03X1330112Y1086390I200J0D01*
G02X1330691Y1085205I-923J-1185D01*
G02X1330235Y1084127I-1502J0D01*
G01X1330206Y1084099D01*
X1330175Y1084026D01*
X1330171Y1083661D01*
X1330201Y1083588D01*
X1330230Y1083559D01*
G02X1330665Y1082502I-1067J-1057D01*
G01Y1082501D01*
G02X1329163Y1080999I-1502J0D01*
G02X1327978Y1081578I0J1502D01*
G03X1327820Y1081655I-158J-123D01*
G01X1327506D01*
G03X1327348Y1081578I0J-200D01*
G02X1324978I-1185J923D01*
G03X1324820Y1081655I-158J-123D01*
G01X1324506D01*
G03X1324348Y1081578I0J-200D01*
G02X1323163Y1080999I-1185J923D01*
G02X1321661Y1082501I0J1502D01*
G02X1322117Y1083579I1502J0D01*
G01X1322146Y1083607D01*
X1322177Y1083680D01*
X1322181Y1084045D01*
X1322151Y1084118D01*
X1322122Y1084147D01*
G02X1321687Y1085204I1067J1057D01*
G01Y1085205D01*
G02X1322057Y1086192I1501J0D01*
G01Y1086193D01*
X1322058D01*
G03X1322106Y1086323I-152J130D01*
G01Y1086587D01*
G03X1322058Y1086717I-200J0D01*
G01X1322057Y1086718D01*
G02X1321687Y1087705I1131J987D01*
G02X1322347Y1088949I1502J0D01*
G01X1322390Y1088978D01*
X1322437Y1089072D01*
X1322414Y1089519D01*
X1322358Y1089607D01*
X1322311Y1089632D01*
G02X1321519Y1090956I711J1324D01*
G02X1322098Y1092141I1502J0D01*
G03X1322175Y1092299I-123J158D01*
G01Y1092613D01*
G03X1322098Y1092771I-200J0D01*
G02X1321519Y1093956I923J1185D01*
G37*
G36*
G01X1337667Y1106897D02*
G02X1340671I1502J0D01*
G02X1339269Y1105398I-1502J0D01*
G01X1339222Y1105395D01*
X1339140Y1105347D01*
X1338914Y1104998D01*
X1338904Y1104905D01*
X1338921Y1104860D01*
G02X1339016Y1104335I-1407J-526D01*
G02X1338959Y1103925I-1503J0D01*
G01X1338947Y1103881D01*
X1338962Y1103792D01*
X1339170Y1103500D01*
G03X1339320Y1103416I163J115D01*
G01X1339321D01*
G02X1340736Y1101917I-86J-1499D01*
G02X1337732I-1502J0D01*
G02X1337789Y1102327I1503J0D01*
G01X1337801Y1102371D01*
X1337786Y1102460D01*
X1337578Y1102752D01*
G03X1337428Y1102836I-163J-115D01*
G01X1337427D01*
G02X1336073Y1103910I86J1499D01*
G01X1336061Y1103952D01*
X1336006Y1104016D01*
X1335699Y1104162D01*
G03X1335535Y1104166I-86J-180D01*
G02X1334956Y1104050I-579J1387D01*
G02X1333514Y1105133I0J1502D01*
G01Y1105134D01*
G03X1333421Y1105251I-192J-57D01*
G01X1333180Y1105389D01*
G03X1333033Y1105410I-100J-173D01*
G02X1332972Y1105396I-366J1457D01*
G01X1332971D01*
G03X1332851Y1105318I42J-196D01*
G01X1332670Y1105068D01*
X1332651Y1104996D01*
X1332655Y1104959D01*
G02X1332664Y1104792I-1493J-164D01*
G02X1329660I-1502J0D01*
G02X1330859Y1106263I1502J0D01*
G01X1330860D01*
G03X1330980Y1106341I-42J196D01*
G01X1331161Y1106591D01*
X1331180Y1106663D01*
X1331176Y1106700D01*
G02X1331167Y1106867I1493J164D01*
G02X1332669Y1108369I1502J0D01*
G02X1334111Y1107286I0J-1502D01*
G01Y1107285D01*
G03X1334204Y1107168I192J57D01*
G01X1334445Y1107030D01*
G03X1334592Y1107009I100J173D01*
G02X1334956Y1107054I365J-1457D01*
G02X1336397Y1105977I0J-1503D01*
G01X1336409Y1105935D01*
X1336464Y1105871D01*
X1336771Y1105725D01*
G03X1336935Y1105721I86J180D01*
G02X1337414Y1105834I580J-1386D01*
G01X1337461Y1105837D01*
X1337543Y1105885D01*
X1337769Y1106234D01*
X1337779Y1106327D01*
X1337762Y1106372D01*
G02X1337667Y1106897I1407J526D01*
G37*
G36*
G01X1369795D02*
G02X1372799I1502J0D01*
G02X1371397Y1105398I-1502J0D01*
G01X1371350Y1105395D01*
X1371268Y1105347D01*
X1371042Y1104998D01*
X1371032Y1104905D01*
X1371049Y1104860D01*
G02X1371144Y1104335I-1407J-526D01*
G02X1371087Y1103925I-1503J0D01*
G01X1371075Y1103881D01*
X1371090Y1103792D01*
X1371298Y1103500D01*
G03X1371448Y1103416I163J115D01*
G01X1371449D01*
G02X1372864Y1101917I-86J-1499D01*
G02X1369860I-1502J0D01*
G02X1369917Y1102327I1503J0D01*
G01X1369929Y1102371D01*
X1369914Y1102460D01*
X1369706Y1102752D01*
G03X1369556Y1102836I-163J-115D01*
G01X1369555D01*
G02X1368201Y1103910I86J1499D01*
G01X1368189Y1103952D01*
X1368134Y1104016D01*
X1367827Y1104162D01*
G03X1367663Y1104166I-86J-180D01*
G02X1367084Y1104050I-579J1387D01*
G02X1365642Y1105133I0J1502D01*
G01Y1105134D01*
G03X1365549Y1105251I-192J-57D01*
G01X1365308Y1105389D01*
G03X1365161Y1105410I-100J-173D01*
G02X1365100Y1105396I-366J1457D01*
G01X1365099D01*
G03X1364979Y1105318I42J-196D01*
G01X1364798Y1105068D01*
X1364779Y1104996D01*
X1364783Y1104959D01*
G02X1364792Y1104792I-1493J-164D01*
G02X1361788I-1502J0D01*
G02X1362987Y1106263I1502J0D01*
G01X1362988D01*
G03X1363108Y1106341I-42J196D01*
G01X1363289Y1106591D01*
X1363308Y1106663D01*
X1363304Y1106700D01*
G02X1363295Y1106867I1493J164D01*
G02X1364797Y1108369I1502J0D01*
G02X1366239Y1107286I0J-1502D01*
G01Y1107285D01*
G03X1366332Y1107168I192J57D01*
G01X1366573Y1107030D01*
G03X1366720Y1107009I100J173D01*
G02X1367084Y1107054I365J-1457D01*
G02X1368525Y1105977I0J-1503D01*
G01X1368537Y1105935D01*
X1368592Y1105871D01*
X1368899Y1105725D01*
G03X1369063Y1105721I86J180D01*
G02X1369542Y1105834I580J-1386D01*
G01X1369589Y1105837D01*
X1369671Y1105885D01*
X1369897Y1106234D01*
X1369907Y1106327D01*
X1369890Y1106372D01*
G02X1369795Y1106897I1407J526D01*
G37*
G36*
G01X1403254D02*
G02X1406258I1502J0D01*
G02X1404856Y1105398I-1502J0D01*
G01X1404809Y1105395D01*
X1404727Y1105347D01*
X1404501Y1104998D01*
X1404491Y1104905D01*
X1404508Y1104860D01*
G02X1404603Y1104335I-1407J-526D01*
G02X1404546Y1103925I-1503J0D01*
G01X1404534Y1103881D01*
X1404549Y1103792D01*
X1404757Y1103500D01*
G03X1404907Y1103416I163J115D01*
G01X1404908D01*
G02X1406323Y1101917I-86J-1499D01*
G02X1403319I-1502J0D01*
G02X1403376Y1102327I1503J0D01*
G01X1403388Y1102371D01*
X1403373Y1102460D01*
X1403165Y1102752D01*
G03X1403015Y1102836I-163J-115D01*
G01X1403014D01*
G02X1401660Y1103910I86J1499D01*
G01X1401648Y1103952D01*
X1401593Y1104016D01*
X1401286Y1104162D01*
G03X1401122Y1104166I-86J-180D01*
G02X1400543Y1104050I-579J1387D01*
G02X1399101Y1105133I0J1502D01*
G01Y1105134D01*
G03X1399008Y1105251I-192J-57D01*
G01X1398767Y1105389D01*
G03X1398620Y1105410I-100J-173D01*
G02X1398559Y1105396I-366J1457D01*
G01X1398558D01*
G03X1398438Y1105318I42J-196D01*
G01X1398257Y1105068D01*
X1398238Y1104996D01*
X1398242Y1104959D01*
G02X1398251Y1104792I-1493J-164D01*
G02X1395247I-1502J0D01*
G02X1396446Y1106263I1502J0D01*
G01X1396447D01*
G03X1396567Y1106341I-42J196D01*
G01X1396748Y1106591D01*
X1396767Y1106663D01*
X1396763Y1106700D01*
G02X1396754Y1106867I1493J164D01*
G02X1398256Y1108369I1502J0D01*
G02X1399698Y1107286I0J-1502D01*
G01Y1107285D01*
G03X1399791Y1107168I192J57D01*
G01X1400032Y1107030D01*
G03X1400179Y1107009I100J173D01*
G02X1400543Y1107054I365J-1457D01*
G02X1401984Y1105977I0J-1503D01*
G01X1401996Y1105935D01*
X1402051Y1105871D01*
X1402358Y1105725D01*
G03X1402522Y1105721I86J180D01*
G02X1403001Y1105834I580J-1386D01*
G01X1403048Y1105837D01*
X1403130Y1105885D01*
X1403356Y1106234D01*
X1403366Y1106327D01*
X1403349Y1106372D01*
G02X1403254Y1106897I1407J526D01*
G37*
G36*
G01X1435382D02*
G02X1438386I1502J0D01*
G02X1436984Y1105398I-1502J0D01*
G01X1436937Y1105395D01*
X1436855Y1105347D01*
X1436629Y1104998D01*
X1436619Y1104905D01*
X1436636Y1104860D01*
G02X1436731Y1104335I-1407J-526D01*
G02X1436674Y1103925I-1503J0D01*
G01X1436662Y1103881D01*
X1436677Y1103792D01*
X1436885Y1103500D01*
G03X1437035Y1103416I163J115D01*
G01X1437036D01*
G02X1438451Y1101917I-86J-1499D01*
G02X1435447I-1502J0D01*
G02X1435504Y1102327I1503J0D01*
G01X1435516Y1102371D01*
X1435501Y1102460D01*
X1435293Y1102752D01*
G03X1435143Y1102836I-163J-115D01*
G01X1435142D01*
G02X1433788Y1103910I86J1499D01*
G01X1433776Y1103952D01*
X1433721Y1104016D01*
X1433414Y1104162D01*
G03X1433250Y1104166I-86J-180D01*
G02X1432671Y1104050I-579J1387D01*
G02X1431229Y1105133I0J1502D01*
G01Y1105134D01*
G03X1431136Y1105251I-192J-57D01*
G01X1430895Y1105389D01*
G03X1430748Y1105410I-100J-173D01*
G02X1430687Y1105396I-366J1457D01*
G01X1430686D01*
G03X1430566Y1105318I42J-196D01*
G01X1430385Y1105068D01*
X1430366Y1104996D01*
X1430370Y1104959D01*
G02X1430379Y1104792I-1493J-164D01*
G02X1427375I-1502J0D01*
G02X1428574Y1106263I1502J0D01*
G01X1428575D01*
G03X1428695Y1106341I-42J196D01*
G01X1428876Y1106591D01*
X1428895Y1106663D01*
X1428891Y1106700D01*
G02X1428882Y1106867I1493J164D01*
G02X1430384Y1108369I1502J0D01*
G02X1431826Y1107286I0J-1502D01*
G01Y1107285D01*
G03X1431919Y1107168I192J57D01*
G01X1432160Y1107030D01*
G03X1432307Y1107009I100J173D01*
G02X1432671Y1107054I365J-1457D01*
G02X1434112Y1105977I0J-1503D01*
G01X1434124Y1105935D01*
X1434179Y1105871D01*
X1434486Y1105725D01*
G03X1434650Y1105721I86J180D01*
G02X1435129Y1105834I580J-1386D01*
G01X1435176Y1105837D01*
X1435258Y1105885D01*
X1435484Y1106234D01*
X1435494Y1106327D01*
X1435477Y1106372D01*
G02X1435382Y1106897I1407J526D01*
G37*
G36*
G01X1328754Y1115150D02*
G02Y1112146I0J-1502D01*
G02X1327767Y1112516I0J1501D01*
G01X1327766D01*
Y1112517D01*
G03X1327636Y1112565I-130J-152D01*
G01X1327372D01*
G03X1327242Y1112517I0J-200D01*
G01X1327241Y1112516D01*
G02X1326254Y1112146I-987J1131D01*
G02Y1115150I0J1502D01*
G02X1327241Y1114780I0J-1501D01*
G01X1327242D01*
Y1114779D01*
G03X1327372Y1114731I130J152D01*
G01X1327636D01*
G03X1327766Y1114779I0J200D01*
G01X1327767Y1114780D01*
G02X1328754Y1115150I987J-1131D01*
G37*
G36*
G01X1360882D02*
G02Y1112146I0J-1502D01*
G02X1359895Y1112516I0J1501D01*
G01X1359894D01*
Y1112517D01*
G03X1359764Y1112565I-130J-152D01*
G01X1359500D01*
G03X1359370Y1112517I0J-200D01*
G01X1359369Y1112516D01*
G02X1358382Y1112146I-987J1131D01*
G02Y1115150I0J1502D01*
G02X1359369Y1114780I0J-1501D01*
G01X1359370D01*
Y1114779D01*
G03X1359500Y1114731I130J152D01*
G01X1359764D01*
G03X1359894Y1114779I0J200D01*
G01X1359895Y1114780D01*
G02X1360882Y1115150I987J-1131D01*
G37*
G36*
G01X1394341D02*
G02Y1112146I0J-1502D01*
G02X1393354Y1112516I0J1501D01*
G01X1393353D01*
Y1112517D01*
G03X1393223Y1112565I-130J-152D01*
G01X1392959D01*
G03X1392829Y1112517I0J-200D01*
G01X1392828Y1112516D01*
G02X1391841Y1112146I-987J1131D01*
G02Y1115150I0J1502D01*
G02X1392828Y1114780I0J-1501D01*
G01X1392829D01*
Y1114779D01*
G03X1392959Y1114731I130J152D01*
G01X1393223D01*
G03X1393353Y1114779I0J200D01*
G01X1393354Y1114780D01*
G02X1394341Y1115150I987J-1131D01*
G37*
G36*
G01X1426469D02*
G02Y1112146I0J-1502D01*
G02X1425482Y1112516I0J1501D01*
G01X1425481D01*
Y1112517D01*
G03X1425351Y1112565I-130J-152D01*
G01X1425087D01*
G03X1424957Y1112517I0J-200D01*
G01X1424956Y1112516D01*
G02X1423969Y1112146I-987J1131D01*
G02Y1115150I0J1502D01*
G02X1424956Y1114780I0J-1501D01*
G01X1424957D01*
Y1114779D01*
G03X1425087Y1114731I130J152D01*
G01X1425351D01*
G03X1425481Y1114779I0J200D01*
G01X1425482Y1114780D01*
G02X1426469Y1115150I987J-1131D01*
G37*
G36*
G01X1344148Y1118396D02*
G02X1347152I1502J0D01*
G02X1346782Y1117409I-1501J0D01*
G01Y1117408D01*
X1346781D01*
G03X1346733Y1117278I152J-130D01*
G01Y1117014D01*
G03X1346781Y1116884I200J0D01*
G01X1346782Y1116883D01*
G02X1347152Y1115896I-1131J-987D01*
G02X1344148I-1502J0D01*
G02X1344518Y1116883I1501J0D01*
G01Y1116884D01*
X1344519D01*
G03X1344567Y1117014I-152J130D01*
G01Y1117278D01*
G03X1344519Y1117408I-200J0D01*
G01X1344518Y1117409D01*
G02X1344148Y1118396I1131J987D01*
G37*
G36*
G01X1376276D02*
G02X1379280I1502J0D01*
G02X1378910Y1117409I-1501J0D01*
G01Y1117408D01*
X1378909D01*
G03X1378861Y1117278I152J-130D01*
G01Y1117014D01*
G03X1378909Y1116884I200J0D01*
G01X1378910Y1116883D01*
G02X1379280Y1115896I-1131J-987D01*
G02X1376276I-1502J0D01*
G02X1376646Y1116883I1501J0D01*
G01Y1116884D01*
X1376647D01*
G03X1376695Y1117014I-152J130D01*
G01Y1117278D01*
G03X1376647Y1117408I-200J0D01*
G01X1376646Y1117409D01*
G02X1376276Y1118396I1131J987D01*
G37*
G36*
G01X1409735D02*
G02X1412739I1502J0D01*
G02X1412369Y1117409I-1501J0D01*
G01Y1117408D01*
X1412368D01*
G03X1412320Y1117278I152J-130D01*
G01Y1117014D01*
G03X1412368Y1116884I200J0D01*
G01X1412369Y1116883D01*
G02X1412739Y1115896I-1131J-987D01*
G02X1409735I-1502J0D01*
G02X1410105Y1116883I1501J0D01*
G01Y1116884D01*
X1410106D01*
G03X1410154Y1117014I-152J130D01*
G01Y1117278D01*
G03X1410106Y1117408I-200J0D01*
G01X1410105Y1117409D01*
G02X1409735Y1118396I1131J987D01*
G37*
G36*
G01X1441863D02*
G02X1444867I1502J0D01*
G02X1444497Y1117409I-1501J0D01*
G01Y1117408D01*
X1444496D01*
G03X1444448Y1117278I152J-130D01*
G01Y1117014D01*
G03X1444496Y1116884I200J0D01*
G01X1444497Y1116883D01*
G02X1444867Y1115896I-1131J-987D01*
G02X1441863I-1502J0D01*
G02X1442233Y1116883I1501J0D01*
G01Y1116884D01*
X1442234D01*
G03X1442282Y1117014I-152J130D01*
G01Y1117278D01*
G03X1442234Y1117408I-200J0D01*
G01X1442233Y1117409D01*
G02X1441863Y1118396I1131J987D01*
G37*
G36*
G01X1318969Y1107895D02*
G02X1318763Y1107909I-1J1502D01*
G01X1318727Y1107914D01*
X1318656Y1107898D01*
X1318373Y1107710D01*
X1318331Y1107650D01*
X1318322Y1107615D01*
G02X1316869Y1106495I-1453J383D01*
G02X1315367Y1107997I0J1502D01*
G02X1315897Y1109142I1502J0D01*
G03X1315968Y1109294I-129J153D01*
G01Y1109600D01*
G03X1315897Y1109752I-200J-1D01*
G02X1315367Y1110897I972J1145D01*
G02X1315897Y1112042I1502J0D01*
G03X1315968Y1112194I-129J153D01*
G01Y1112500D01*
G03X1315897Y1112652I-200J-1D01*
G02X1315367Y1113797I972J1145D01*
G02X1316869Y1115299I1502J0D01*
G02X1318325Y1114167I0J-1502D01*
G01X1318334Y1114130D01*
X1318379Y1114068D01*
X1318674Y1113879D01*
X1318749Y1113865D01*
X1318787Y1113872D01*
G02X1319069Y1113899I284J-1475D01*
G02X1319872Y1113666I0J-1502D01*
G01X1319914Y1113639D01*
X1320011Y1113632D01*
X1320409Y1113804D01*
X1320469Y1113880D01*
X1320479Y1113929D01*
G02X1321671Y1115123I1475J-281D01*
G01X1321714Y1115131D01*
X1321782Y1115180D01*
X1321980Y1115513D01*
X1321989Y1115598D01*
X1321976Y1115639D01*
G02X1321903Y1116101I1429J463D01*
G02X1322347Y1117167I1502J0D01*
G03X1322406Y1117309I-141J142D01*
G01Y1117593D01*
G03X1322347Y1117735I-200J0D01*
G02X1321903Y1118801I1058J1066D01*
G02X1324907I1502J0D01*
G02X1324463Y1117735I-1502J0D01*
G03X1324404Y1117593I141J-142D01*
G01Y1117309D01*
G03X1324463Y1117167I200J0D01*
G02X1324907Y1116101I-1058J-1066D01*
G02X1323688Y1114626I-1502J0D01*
G01X1323645Y1114618D01*
X1323577Y1114569D01*
X1323379Y1114236D01*
X1323370Y1114151D01*
X1323383Y1114110D01*
G02X1323456Y1113648I-1429J-463D01*
G02X1322459Y1112234I-1501J0D01*
G03X1322333Y1112095I68J-188D01*
G01X1322238Y1111725D01*
X1322261Y1111629D01*
X1322294Y1111592D01*
G02X1322671Y1110597I-1125J-995D01*
G02X1322224Y1109528I-1502J0D01*
G01X1322197Y1109502D01*
X1322166Y1109432D01*
X1322153Y1109081D01*
X1322178Y1109011D01*
X1322203Y1108982D01*
G02X1322571Y1107997I-1134J-985D01*
G02X1321069Y1106495I-1502J0D01*
G02X1319616Y1107615I0J1503D01*
G01X1319607Y1107650D01*
X1319565Y1107710D01*
X1319282Y1107898D01*
X1319211Y1107914D01*
X1319175Y1107909D01*
G02X1318969Y1107895I-205J1488D01*
G37*
G36*
G01X1351097D02*
G02X1350891Y1107909I-1J1502D01*
G01X1350855Y1107914D01*
X1350784Y1107898D01*
X1350501Y1107710D01*
X1350459Y1107650D01*
X1350450Y1107615D01*
G02X1348997Y1106495I-1453J383D01*
G02X1347495Y1107997I0J1502D01*
G02X1348025Y1109142I1502J0D01*
G03X1348096Y1109294I-129J153D01*
G01Y1109600D01*
G03X1348025Y1109752I-200J-1D01*
G02X1347495Y1110897I972J1145D01*
G02X1348025Y1112042I1502J0D01*
G03X1348096Y1112194I-129J153D01*
G01Y1112500D01*
G03X1348025Y1112652I-200J-1D01*
G02X1347495Y1113797I972J1145D01*
G02X1348997Y1115299I1502J0D01*
G02X1350453Y1114167I0J-1502D01*
G01X1350462Y1114130D01*
X1350507Y1114068D01*
X1350802Y1113879D01*
X1350877Y1113865D01*
X1350915Y1113872D01*
G02X1351197Y1113899I284J-1475D01*
G02X1352000Y1113666I0J-1502D01*
G01X1352042Y1113639D01*
X1352139Y1113632D01*
X1352537Y1113804D01*
X1352597Y1113880D01*
X1352607Y1113929D01*
G02X1353799Y1115123I1475J-281D01*
G01X1353842Y1115131D01*
X1353910Y1115180D01*
X1354108Y1115513D01*
X1354117Y1115598D01*
X1354104Y1115639D01*
G02X1354031Y1116101I1429J463D01*
G02X1354475Y1117167I1502J0D01*
G03X1354534Y1117309I-141J142D01*
G01Y1117593D01*
G03X1354475Y1117735I-200J0D01*
G02X1354031Y1118801I1058J1066D01*
G02X1357035I1502J0D01*
G02X1356591Y1117735I-1502J0D01*
G03X1356532Y1117593I141J-142D01*
G01Y1117309D01*
G03X1356591Y1117167I200J0D01*
G02X1357035Y1116101I-1058J-1066D01*
G02X1355816Y1114626I-1502J0D01*
G01X1355773Y1114618D01*
X1355705Y1114569D01*
X1355507Y1114236D01*
X1355498Y1114151D01*
X1355511Y1114110D01*
G02X1355584Y1113648I-1429J-463D01*
G02X1354587Y1112234I-1501J0D01*
G03X1354461Y1112095I68J-188D01*
G01X1354366Y1111725D01*
X1354389Y1111629D01*
X1354422Y1111592D01*
G02X1354799Y1110597I-1125J-995D01*
G02X1354352Y1109528I-1502J0D01*
G01X1354325Y1109502D01*
X1354294Y1109432D01*
X1354281Y1109081D01*
X1354306Y1109011D01*
X1354331Y1108982D01*
G02X1354699Y1107997I-1134J-985D01*
G02X1353197Y1106495I-1502J0D01*
G02X1351744Y1107615I0J1503D01*
G01X1351735Y1107650D01*
X1351693Y1107710D01*
X1351410Y1107898D01*
X1351339Y1107914D01*
X1351303Y1107909D01*
G02X1351097Y1107895I-205J1488D01*
G37*
G36*
G01X1384556D02*
G02X1384350Y1107909I-1J1502D01*
G01X1384314Y1107914D01*
X1384243Y1107898D01*
X1383960Y1107710D01*
X1383918Y1107650D01*
X1383909Y1107615D01*
G02X1382456Y1106495I-1453J383D01*
G02X1380954Y1107997I0J1502D01*
G02X1381484Y1109142I1502J0D01*
G03X1381555Y1109294I-129J153D01*
G01Y1109600D01*
G03X1381484Y1109752I-200J-1D01*
G02X1380954Y1110897I972J1145D01*
G02X1381484Y1112042I1502J0D01*
G03X1381555Y1112194I-129J153D01*
G01Y1112500D01*
G03X1381484Y1112652I-200J-1D01*
G02X1380954Y1113797I972J1145D01*
G02X1382456Y1115299I1502J0D01*
G02X1383912Y1114167I0J-1502D01*
G01X1383921Y1114130D01*
X1383966Y1114068D01*
X1384261Y1113879D01*
X1384336Y1113865D01*
X1384374Y1113872D01*
G02X1384656Y1113899I284J-1475D01*
G02X1385459Y1113666I0J-1502D01*
G01X1385501Y1113639D01*
X1385598Y1113632D01*
X1385996Y1113804D01*
X1386056Y1113880D01*
X1386066Y1113929D01*
G02X1387258Y1115123I1475J-281D01*
G01X1387301Y1115131D01*
X1387369Y1115180D01*
X1387567Y1115513D01*
X1387576Y1115598D01*
X1387563Y1115639D01*
G02X1387490Y1116101I1429J463D01*
G02X1387934Y1117167I1502J0D01*
G03X1387993Y1117309I-141J142D01*
G01Y1117593D01*
G03X1387934Y1117735I-200J0D01*
G02X1387490Y1118801I1058J1066D01*
G02X1390494I1502J0D01*
G02X1390050Y1117735I-1502J0D01*
G03X1389991Y1117593I141J-142D01*
G01Y1117309D01*
G03X1390050Y1117167I200J0D01*
G02X1390494Y1116101I-1058J-1066D01*
G02X1389275Y1114626I-1502J0D01*
G01X1389232Y1114618D01*
X1389164Y1114569D01*
X1388966Y1114236D01*
X1388957Y1114151D01*
X1388970Y1114110D01*
G02X1389043Y1113648I-1429J-463D01*
G02X1388046Y1112234I-1501J0D01*
G03X1387920Y1112095I68J-188D01*
G01X1387825Y1111725D01*
X1387848Y1111629D01*
X1387881Y1111592D01*
G02X1388258Y1110597I-1125J-995D01*
G02X1387811Y1109528I-1502J0D01*
G01X1387784Y1109502D01*
X1387753Y1109432D01*
X1387740Y1109081D01*
X1387765Y1109011D01*
X1387790Y1108982D01*
G02X1388158Y1107997I-1134J-985D01*
G02X1386656Y1106495I-1502J0D01*
G02X1385203Y1107615I0J1503D01*
G01X1385194Y1107650D01*
X1385152Y1107710D01*
X1384869Y1107898D01*
X1384798Y1107914D01*
X1384762Y1107909D01*
G02X1384556Y1107895I-205J1488D01*
G37*
G36*
G01X1416684D02*
G02X1416478Y1107909I-1J1502D01*
G01X1416442Y1107914D01*
X1416371Y1107898D01*
X1416088Y1107710D01*
X1416046Y1107650D01*
X1416037Y1107615D01*
G02X1414584Y1106495I-1453J383D01*
G02X1413082Y1107997I0J1502D01*
G02X1413612Y1109142I1502J0D01*
G03X1413683Y1109294I-129J153D01*
G01Y1109600D01*
G03X1413612Y1109752I-200J-1D01*
G02X1413082Y1110897I972J1145D01*
G02X1413612Y1112042I1502J0D01*
G03X1413683Y1112194I-129J153D01*
G01Y1112500D01*
G03X1413612Y1112652I-200J-1D01*
G02X1413082Y1113797I972J1145D01*
G02X1414584Y1115299I1502J0D01*
G02X1416040Y1114167I0J-1502D01*
G01X1416049Y1114130D01*
X1416094Y1114068D01*
X1416389Y1113879D01*
X1416464Y1113865D01*
X1416502Y1113872D01*
G02X1416784Y1113899I284J-1475D01*
G02X1417587Y1113666I0J-1502D01*
G01X1417629Y1113639D01*
X1417726Y1113632D01*
X1418124Y1113804D01*
X1418184Y1113880D01*
X1418194Y1113929D01*
G02X1419386Y1115123I1475J-281D01*
G01X1419429Y1115131D01*
X1419497Y1115180D01*
X1419695Y1115513D01*
X1419704Y1115598D01*
X1419691Y1115639D01*
G02X1419618Y1116101I1429J463D01*
G02X1420062Y1117167I1502J0D01*
G03X1420121Y1117309I-141J142D01*
G01Y1117593D01*
G03X1420062Y1117735I-200J0D01*
G02X1419618Y1118801I1058J1066D01*
G02X1422622I1502J0D01*
G02X1422178Y1117735I-1502J0D01*
G03X1422119Y1117593I141J-142D01*
G01Y1117309D01*
G03X1422178Y1117167I200J0D01*
G02X1422622Y1116101I-1058J-1066D01*
G02X1421403Y1114626I-1502J0D01*
G01X1421360Y1114618D01*
X1421292Y1114569D01*
X1421094Y1114236D01*
X1421085Y1114151D01*
X1421098Y1114110D01*
G02X1421171Y1113648I-1429J-463D01*
G02X1420174Y1112234I-1501J0D01*
G03X1420048Y1112095I68J-188D01*
G01X1419953Y1111725D01*
X1419976Y1111629D01*
X1420009Y1111592D01*
G02X1420386Y1110597I-1125J-995D01*
G02X1419939Y1109528I-1502J0D01*
G01X1419912Y1109502D01*
X1419881Y1109432D01*
X1419868Y1109081D01*
X1419893Y1109011D01*
X1419918Y1108982D01*
G02X1420286Y1107997I-1134J-985D01*
G02X1418784Y1106495I-1502J0D01*
G02X1417331Y1107615I0J1503D01*
G01X1417322Y1107650D01*
X1417280Y1107710D01*
X1416997Y1107898D01*
X1416926Y1107914D01*
X1416890Y1107909D01*
G02X1416684Y1107895I-205J1488D01*
G37*
G36*
G01X1495319Y1141174D02*
X1495313Y1141583D01*
X1495272Y1141664D01*
X1495235Y1141693D01*
G02X1494638Y1142891I905J1199D01*
G02X1497642I1502J0D01*
G02X1497081Y1141720I-1503J0D01*
G01X1497045Y1141691D01*
X1497006Y1141608D01*
X1497012Y1141199D01*
X1497053Y1141118D01*
X1497090Y1141089D01*
G02X1497687Y1139891I-905J-1199D01*
G02X1494683I-1502J0D01*
G02X1495244Y1141062I1503J0D01*
G01X1495280Y1141091D01*
X1495319Y1141174D01*
G37*
G36*
G01Y1153774D02*
X1495313Y1154183D01*
X1495272Y1154264D01*
X1495235Y1154293D01*
G02X1494638Y1155491I905J1199D01*
G02X1497642I1502J0D01*
G02X1497081Y1154320I-1503J0D01*
G01X1497045Y1154291D01*
X1497006Y1154208D01*
X1497012Y1153799D01*
X1497053Y1153718D01*
X1497090Y1153689D01*
G02X1497687Y1152491I-905J-1199D01*
G02X1494683I-1502J0D01*
G02X1495244Y1153662I1503J0D01*
G01X1495280Y1153691D01*
X1495319Y1153774D01*
G37*
G36*
G01Y1166374D02*
X1495313Y1166783D01*
X1495272Y1166864D01*
X1495235Y1166893D01*
G02X1494638Y1168091I905J1199D01*
G02X1497642I1502J0D01*
G02X1497081Y1166920I-1503J0D01*
G01X1497045Y1166891D01*
X1497006Y1166808D01*
X1497012Y1166399D01*
X1497053Y1166318D01*
X1497090Y1166289D01*
G02X1497687Y1165091I-905J-1199D01*
G02X1494683I-1502J0D01*
G02X1495244Y1166262I1503J0D01*
G01X1495280Y1166291D01*
X1495319Y1166374D01*
G37*
G36*
G01X1512964Y1171314D02*
X1513355Y1171325D01*
X1513432Y1171362D01*
X1513460Y1171396D01*
G02X1514467Y1171872I1007J-827D01*
G01X1518207D01*
G02Y1169268I0J-1302D01*
G01X1514467D01*
G02X1513460Y1169744I0J1303D01*
G01X1513432Y1169778D01*
X1513355Y1169815D01*
X1512964Y1169826D01*
X1512886Y1169792D01*
X1512856Y1169760D01*
G02X1511968Y1169368I-888J810D01*
G02Y1171772I0J1202D01*
G02X1512856Y1171380I0J-1202D01*
G01X1512886Y1171348D01*
X1512964Y1171314D01*
G37*
G36*
G01Y1178795D02*
X1513355Y1178805D01*
X1513432Y1178843D01*
X1513460Y1178877D01*
G02X1514467Y1179354I1008J-826D01*
G01X1518207D01*
G02Y1176748I0J-1303D01*
G01X1514467D01*
G02X1513461Y1177224I1J1303D01*
G01X1513432Y1177259D01*
X1513356Y1177296D01*
X1512965Y1177306D01*
X1512886Y1177273D01*
X1512856Y1177240D01*
G02X1511968Y1176848I-888J810D01*
G02Y1179252I0J1202D01*
G02X1512855Y1178861I0J-1202D01*
G01X1512885Y1178828D01*
X1512964Y1178795D01*
G37*
G36*
G01X1495319Y1178974D02*
X1495313Y1179383D01*
X1495272Y1179464D01*
X1495235Y1179493D01*
G02X1494638Y1180691I905J1199D01*
G02X1497642I1502J0D01*
G02X1497081Y1179520I-1503J0D01*
G01X1497045Y1179491D01*
X1497006Y1179408D01*
X1497012Y1178999D01*
X1497053Y1178918D01*
X1497090Y1178889D01*
G02X1497687Y1177691I-905J-1199D01*
G02X1494683I-1502J0D01*
G02X1495244Y1178862I1503J0D01*
G01X1495280Y1178891D01*
X1495319Y1178974D01*
G37*
G36*
G01X1390297Y1199403D02*
Y1199739D01*
X1390272Y1199806D01*
X1390248Y1199834D01*
G02X1389878Y1200821I1131J987D01*
G02X1392882I1502J0D01*
G02X1392512Y1199834I-1501J0D01*
G01X1392488Y1199806D01*
X1392463Y1199739D01*
Y1199403D01*
X1392488Y1199336D01*
X1392512Y1199308D01*
G02X1392882Y1198321I-1131J-987D01*
G02X1389878I-1502J0D01*
G02X1390248Y1199308I1501J0D01*
G01X1390272Y1199336D01*
X1390297Y1199403D01*
G37*
G36*
G01X1403762D02*
Y1199739D01*
X1403737Y1199806D01*
X1403713Y1199834D01*
G02X1403343Y1200821I1131J987D01*
G02X1406347I1502J0D01*
G02X1405977Y1199834I-1501J0D01*
G01X1405953Y1199806D01*
X1405928Y1199739D01*
Y1199403D01*
X1405953Y1199336D01*
X1405977Y1199308D01*
G02X1406347Y1198321I-1131J-987D01*
G02X1403343I-1502J0D01*
G02X1403713Y1199308I1501J0D01*
G01X1403737Y1199336D01*
X1403762Y1199403D01*
G37*
G36*
G01X1409227D02*
Y1199739D01*
X1409202Y1199806D01*
X1409178Y1199834D01*
G02X1408808Y1200821I1131J987D01*
G02X1411812I1502J0D01*
G02X1411442Y1199834I-1501J0D01*
G01X1411418Y1199806D01*
X1411393Y1199739D01*
Y1199403D01*
X1411418Y1199336D01*
X1411442Y1199308D01*
G02X1411812Y1198321I-1131J-987D01*
G02X1408808I-1502J0D01*
G02X1409178Y1199308I1501J0D01*
G01X1409202Y1199336D01*
X1409227Y1199403D01*
G37*
G36*
G01X1417227D02*
Y1199739D01*
X1417202Y1199806D01*
X1417178Y1199834D01*
G02X1416808Y1200821I1131J987D01*
G02X1419812I1502J0D01*
G02X1419442Y1199834I-1501J0D01*
G01X1419418Y1199806D01*
X1419393Y1199739D01*
Y1199403D01*
X1419418Y1199336D01*
X1419442Y1199308D01*
G02X1419812Y1198321I-1131J-987D01*
G02X1416808I-1502J0D01*
G02X1417178Y1199308I1501J0D01*
G01X1417202Y1199336D01*
X1417227Y1199403D01*
G37*
G36*
G01X1436157D02*
Y1199739D01*
X1436132Y1199806D01*
X1436108Y1199834D01*
G02X1435738Y1200821I1131J987D01*
G02X1438742I1502J0D01*
G02X1438372Y1199834I-1501J0D01*
G01X1438348Y1199806D01*
X1438323Y1199739D01*
Y1199403D01*
X1438348Y1199336D01*
X1438372Y1199308D01*
G02X1438742Y1198321I-1131J-987D01*
G02X1435738I-1502J0D01*
G02X1436108Y1199308I1501J0D01*
G01X1436132Y1199336D01*
X1436157Y1199403D01*
G37*
G36*
G01X1481188Y1200291D02*
X1480912Y1200577D01*
X1480829Y1200608D01*
X1480785Y1200605D01*
G02X1480675Y1200601I-110J1498D01*
G02X1482177Y1202103I0J1502D01*
G02X1482168Y1201941I-1502J2D01*
G01X1482163Y1201897D01*
X1482192Y1201813D01*
X1482468Y1201527D01*
X1482551Y1201496D01*
X1482595Y1201499D01*
G02X1482705Y1201503I110J-1498D01*
G02X1481203Y1200001I0J-1502D01*
G02X1481212Y1200163I1502J-2D01*
G01X1481217Y1200207D01*
X1481188Y1200291D01*
G37*
G36*
G01X1419542Y1207987D02*
Y1208323D01*
X1419517Y1208390D01*
X1419493Y1208418D01*
G02X1419123Y1209405I1131J987D01*
G02X1422127I1502J0D01*
G02X1421757Y1208418I-1501J0D01*
G01X1421733Y1208390D01*
X1421708Y1208323D01*
Y1207987D01*
X1421733Y1207920D01*
X1421757Y1207892D01*
G02Y1205918I-1131J-987D01*
G01X1421733Y1205890D01*
X1421708Y1205823D01*
Y1205487D01*
X1421733Y1205420D01*
X1421757Y1205392D01*
G02X1422127Y1204405I-1131J-987D01*
G02X1419123I-1502J0D01*
G02X1419493Y1205392I1501J0D01*
G01X1419517Y1205420D01*
X1419542Y1205487D01*
Y1205823D01*
X1419517Y1205890D01*
X1419493Y1205918D01*
G02Y1207892I1131J987D01*
G01X1419517Y1207920D01*
X1419542Y1207987D01*
G37*
G36*
G01X1392612Y1210487D02*
Y1210823D01*
X1392587Y1210890D01*
X1392563Y1210918D01*
G02X1392193Y1211905I1131J987D01*
G02X1395197I1502J0D01*
G02X1394827Y1210918I-1501J0D01*
G01X1394803Y1210890D01*
X1394778Y1210823D01*
Y1210487D01*
X1394803Y1210420D01*
X1394827Y1210392D01*
G02Y1208418I-1131J-987D01*
G01X1394803Y1208390D01*
X1394778Y1208323D01*
Y1207987D01*
X1394803Y1207920D01*
X1394827Y1207892D01*
G02Y1205918I-1131J-987D01*
G01X1394803Y1205890D01*
X1394778Y1205823D01*
Y1205487D01*
X1394803Y1205420D01*
X1394827Y1205392D01*
G02X1395197Y1204405I-1131J-987D01*
G02X1392193I-1502J0D01*
G02X1392563Y1205392I1501J0D01*
G01X1392587Y1205420D01*
X1392612Y1205487D01*
Y1205823D01*
X1392587Y1205890D01*
X1392563Y1205918D01*
G02Y1207892I1131J987D01*
G01X1392587Y1207920D01*
X1392612Y1207987D01*
Y1208323D01*
X1392587Y1208390D01*
X1392563Y1208418D01*
G02Y1210392I1131J987D01*
G01X1392587Y1210420D01*
X1392612Y1210487D01*
G37*
G36*
G01X1406912Y1210699D02*
Y1211035D01*
X1406887Y1211102D01*
X1406863Y1211130D01*
G02X1406493Y1212117I1131J987D01*
G02X1409497I1502J0D01*
G02X1409127Y1211130I-1501J0D01*
G01X1409103Y1211102D01*
X1409078Y1211035D01*
Y1210699D01*
X1409103Y1210632D01*
X1409127Y1210604D01*
G02Y1208630I-1131J-987D01*
G01X1409103Y1208602D01*
X1409078Y1208535D01*
Y1208199D01*
X1409103Y1208132D01*
X1409127Y1208104D01*
G02Y1206130I-1131J-987D01*
G01X1409103Y1206102D01*
X1409078Y1206035D01*
Y1205699D01*
X1409103Y1205632D01*
X1409127Y1205604D01*
G02X1409497Y1204617I-1131J-987D01*
G02X1406493I-1502J0D01*
G02X1406863Y1205604I1501J0D01*
G01X1406887Y1205632D01*
X1406912Y1205699D01*
Y1206035D01*
X1406887Y1206102D01*
X1406863Y1206130D01*
G02Y1208104I1131J987D01*
G01X1406887Y1208132D01*
X1406912Y1208199D01*
Y1208535D01*
X1406887Y1208602D01*
X1406863Y1208630D01*
G02Y1210604I1131J987D01*
G01X1406887Y1210632D01*
X1406912Y1210699D01*
G37*
G36*
G01X1433842D02*
Y1211035D01*
X1433817Y1211102D01*
X1433793Y1211130D01*
G02X1433423Y1212117I1131J987D01*
G02X1436427I1502J0D01*
G02X1436057Y1211130I-1501J0D01*
G01X1436033Y1211102D01*
X1436008Y1211035D01*
Y1210699D01*
X1436033Y1210632D01*
X1436057Y1210604D01*
G02Y1208630I-1131J-987D01*
G01X1436033Y1208602D01*
X1436008Y1208535D01*
Y1208199D01*
X1436033Y1208132D01*
X1436057Y1208104D01*
G02Y1206130I-1131J-987D01*
G01X1436033Y1206102D01*
X1436008Y1206035D01*
Y1205699D01*
X1436033Y1205632D01*
X1436057Y1205604D01*
G02X1436427Y1204617I-1131J-987D01*
G02X1433423I-1502J0D01*
G02X1433793Y1205604I1501J0D01*
G01X1433817Y1205632D01*
X1433842Y1205699D01*
Y1206035D01*
X1433817Y1206102D01*
X1433793Y1206130D01*
G02Y1208104I1131J987D01*
G01X1433817Y1208132D01*
X1433842Y1208199D01*
Y1208535D01*
X1433817Y1208602D01*
X1433793Y1208630D01*
G02Y1210604I1131J987D01*
G01X1433817Y1210632D01*
X1433842Y1210699D01*
G37*
G36*
G01X1417163Y1261006D02*
X1417479D01*
G03X1417636Y1261083I-1J200D01*
G02X1420006I1185J-923D01*
G03X1420163Y1261006I158J123D01*
G01X1420479D01*
G03X1420636Y1261083I-1J200D01*
G02X1421821Y1261662I1185J-923D01*
G02X1423323Y1260160I0J-1502D01*
G02X1422744Y1258975I-1502J0D01*
G03X1422667Y1258818I123J-158D01*
G01Y1258502D01*
G03X1422744Y1258345I200J1D01*
G02X1423323Y1257160I-923J-1185D01*
G02X1421821Y1255658I-1502J0D01*
G02X1420636Y1256237I0J1502D01*
G03X1420479Y1256314I-158J-123D01*
G01X1420163D01*
G03X1420006Y1256237I1J-200D01*
G02X1417636I-1185J923D01*
G03X1417479Y1256314I-158J-123D01*
G01X1417163D01*
G03X1417006Y1256237I1J-200D01*
G02X1414636I-1185J923D01*
G03X1414479Y1256314I-158J-123D01*
G01X1414163D01*
G03X1414006Y1256237I1J-200D01*
G02X1411636I-1185J923D01*
G03X1411479Y1256314I-158J-123D01*
G01X1411163D01*
G03X1411006Y1256237I1J-200D01*
G02X1408636I-1185J923D01*
G03X1408479Y1256314I-158J-123D01*
G01X1408163D01*
G03X1408006Y1256237I1J-200D01*
G02X1405636I-1185J923D01*
G03X1405479Y1256314I-158J-123D01*
G01X1405163D01*
G03X1405006Y1256237I1J-200D01*
G02X1402636I-1185J923D01*
G03X1402479Y1256314I-158J-123D01*
G01X1402163D01*
G03X1402006Y1256237I1J-200D01*
G02X1399636I-1185J923D01*
G03X1399479Y1256314I-158J-123D01*
G01X1399163D01*
G03X1399006Y1256237I1J-200D01*
G02X1396636I-1185J923D01*
G03X1396479Y1256314I-158J-123D01*
G01X1396163D01*
G03X1396006Y1256237I1J-200D01*
G02X1393636I-1185J923D01*
G03X1393479Y1256314I-158J-123D01*
G01X1393163D01*
G03X1393006Y1256237I1J-200D01*
G02X1390636I-1185J923D01*
G03X1390479Y1256314I-158J-123D01*
G01X1390163D01*
G03X1390006Y1256237I1J-200D01*
G02X1387636I-1185J923D01*
G03X1387479Y1256314I-158J-123D01*
G01X1387163D01*
G03X1387006Y1256237I1J-200D01*
G02X1385821Y1255658I-1185J923D01*
G02X1384319Y1257160I0J1502D01*
G02X1384898Y1258345I1502J0D01*
G03X1384975Y1258502I-123J158D01*
G01Y1258818D01*
G03X1384898Y1258975I-200J-1D01*
G02X1384319Y1260160I923J1185D01*
G02X1385821Y1261662I1502J0D01*
G02X1387006Y1261083I0J-1502D01*
G03X1387163Y1261006I158J123D01*
G01X1387479D01*
G03X1387636Y1261083I-1J200D01*
G02X1390006I1185J-923D01*
G03X1390163Y1261006I158J123D01*
G01X1390479D01*
G03X1390636Y1261083I-1J200D01*
G02X1393006I1185J-923D01*
G03X1393163Y1261006I158J123D01*
G01X1393479D01*
G03X1393636Y1261083I-1J200D01*
G02X1396006I1185J-923D01*
G03X1396163Y1261006I158J123D01*
G01X1396479D01*
G03X1396636Y1261083I-1J200D01*
G02X1399006I1185J-923D01*
G03X1399163Y1261006I158J123D01*
G01X1399479D01*
G03X1399636Y1261083I-1J200D01*
G02X1402006I1185J-923D01*
G03X1402163Y1261006I158J123D01*
G01X1402479D01*
G03X1402636Y1261083I-1J200D01*
G02X1405006I1185J-923D01*
G03X1405163Y1261006I158J123D01*
G01X1405479D01*
G03X1405636Y1261083I-1J200D01*
G02X1408006I1185J-923D01*
G03X1408163Y1261006I158J123D01*
G01X1408479D01*
G03X1408636Y1261083I-1J200D01*
G02X1411006I1185J-923D01*
G03X1411163Y1261006I158J123D01*
G01X1411479D01*
G03X1411636Y1261083I-1J200D01*
G02X1414006I1185J-923D01*
G03X1414163Y1261006I158J123D01*
G01X1414479D01*
G03X1414636Y1261083I-1J200D01*
G02X1417006I1185J-923D01*
G03X1417163Y1261006I158J123D01*
G37*
G36*
G01X1522638Y1179699D02*
G02X1522617Y1179921I1181J224D01*
G02X1523819Y1178719I1202J0D01*
G02X1523596Y1178740I1J1202D01*
G03X1523129Y1178273I-74J-393D01*
G02X1523150Y1178051I-1181J-224D01*
G02X1521948Y1179253I-1202J0D01*
G02X1522171Y1179232I-1J-1202D01*
G03X1522638Y1179699I74J393D01*
G37*
G36*
G01X1531570Y1178749D02*
X1531521Y1178740D01*
G02X1531299Y1178719I-224J1181D01*
G02X1532501Y1179921I0J1202D01*
G02X1532480Y1179699I-1202J2D01*
G01X1532471Y1179650D01*
X1532500Y1179557D01*
X1532805Y1179252D01*
X1532898Y1179223D01*
X1532947Y1179232D01*
G02X1533169Y1179253I224J-1181D01*
G02X1534371Y1178051I0J-1202D01*
G02X1534350Y1177828I-1202J1D01*
G01X1534341Y1177780D01*
X1534370Y1177685D01*
X1534674Y1177381D01*
X1534768Y1177352D01*
X1534817Y1177361D01*
G02X1535039Y1177382I224J-1181D01*
G02X1536241Y1176180I0J-1202D01*
G02X1536220Y1175958I-1202J2D01*
G01X1536211Y1175909D01*
X1536240Y1175816D01*
X1536545Y1175511D01*
X1536638Y1175482D01*
X1536687Y1175491D01*
G02X1536909Y1175512I224J-1181D01*
G02X1535707Y1174310I0J-1202D01*
G02X1535728Y1174532I1202J-2D01*
G01X1535737Y1174581D01*
X1535708Y1174674D01*
X1535403Y1174979D01*
X1535310Y1175008D01*
X1535261Y1174999D01*
G02X1535039Y1174978I-224J1181D01*
G02X1534817Y1174999I2J1202D01*
G01X1534768Y1175008D01*
X1534675Y1174979D01*
X1534370Y1174674D01*
X1534341Y1174581D01*
X1534350Y1174532D01*
G02X1534371Y1174310I-1181J-224D01*
G02X1531967I-1202J0D01*
G02X1531976Y1174453I1202J-4D01*
G01X1531981Y1174501D01*
X1531950Y1174588D01*
X1531649Y1174876D01*
X1531560Y1174903D01*
X1531513Y1174895D01*
G02X1531299Y1174878I-210J1285D01*
G01X1531022D01*
G03X1530874Y1174811I1J-200D01*
G01X1530646Y1174558D01*
X1530620Y1174479D01*
X1530624Y1174436D01*
G02X1530631Y1174310I-1195J-130D01*
G02X1528227I-1202J0D01*
G02X1528234Y1174436I1202J-4D01*
G01X1528238Y1174479D01*
X1528212Y1174558D01*
X1527984Y1174811D01*
G03X1527836Y1174878I-149J-133D01*
G01X1527559D01*
G02X1527345Y1174895I-4J1302D01*
G01X1527298Y1174903D01*
X1527209Y1174876D01*
X1526908Y1174588D01*
X1526877Y1174501D01*
X1526882Y1174453D01*
G02X1526891Y1174310I-1193J-147D01*
G02X1525689Y1175512I-1202J0D01*
G02X1525832Y1175503I-4J-1202D01*
G01X1525880Y1175498D01*
X1525967Y1175529D01*
X1526255Y1175830D01*
X1526282Y1175919D01*
X1526274Y1175966D01*
G02X1526256Y1176180I1285J216D01*
G02X1527559Y1177482I1303J-1D01*
G01X1531299D01*
G02X1531513Y1177465I4J-1302D01*
G01X1531560Y1177457D01*
X1531649Y1177484D01*
X1531950Y1177772D01*
X1531981Y1177859D01*
X1531976Y1177907D01*
G02X1531967Y1178051I1193J147D01*
G02X1531988Y1178273I1202J-2D01*
G01X1531997Y1178322D01*
X1531968Y1178415D01*
X1531663Y1178720D01*
X1531570Y1178749D01*
G37*
G36*
G01X1518906Y1183390D02*
X1518897Y1183439D01*
G02X1518876Y1183661I1181J224D01*
G02X1520078Y1182459I1202J0D01*
G02X1519855Y1182480I1J1202D01*
G01X1519807Y1182489D01*
X1519712Y1182460D01*
X1519408Y1182156D01*
X1519379Y1182062D01*
X1519388Y1182013D01*
G02X1519409Y1181791I-1181J-224D01*
G02X1517005I-1202J0D01*
G02X1517026Y1182013I1202J-2D01*
G01X1517035Y1182062D01*
X1517006Y1182155D01*
X1516702Y1182460D01*
X1516609Y1182489D01*
X1516559Y1182479D01*
G02X1516338Y1182459I-218J1182D01*
G02X1516116Y1182480I2J1202D01*
G01X1516067Y1182489D01*
X1515973Y1182460D01*
X1515669Y1182156D01*
X1515640Y1182061D01*
X1515649Y1182013D01*
G02X1515670Y1181790I-1181J-224D01*
G02X1514468Y1182992I-1202J0D01*
G02X1514690Y1182971I-2J-1202D01*
G01X1514739Y1182962D01*
X1514833Y1182991D01*
X1515137Y1183295D01*
X1515166Y1183390D01*
X1515157Y1183438D01*
G02X1515136Y1183661I1181J224D01*
G02X1517540I1202J0D01*
G02X1517519Y1183439I-1202J2D01*
G01X1517510Y1183390D01*
X1517539Y1183297D01*
X1517843Y1182992D01*
X1517936Y1182963D01*
X1517986Y1182973D01*
G02X1518207Y1182993I218J-1182D01*
G02X1518430Y1182972I-1J-1202D01*
G01X1518478Y1182963D01*
X1518573Y1182992D01*
X1518877Y1183296D01*
X1518906Y1183390D01*
G37*
G36*
G01X1541347D02*
X1541338Y1183439D01*
G02X1541317Y1183661I1181J224D01*
G02X1543721I1202J0D01*
G02X1543700Y1183439I-1202J2D01*
G01X1543691Y1183390D01*
X1543720Y1183297D01*
X1544025Y1182992D01*
X1544118Y1182963D01*
X1544167Y1182972D01*
G02X1544389Y1182993I224J-1181D01*
G02X1543187Y1181791I0J-1202D01*
G02X1543208Y1182013I1202J-2D01*
G01X1543217Y1182062D01*
X1543188Y1182155D01*
X1542883Y1182460D01*
X1542790Y1182489D01*
X1542741Y1182480D01*
G02X1542519Y1182459I-224J1181D01*
G02X1542297Y1182480I2J1202D01*
G01X1542248Y1182489D01*
X1542155Y1182460D01*
X1541850Y1182155D01*
X1541821Y1182062D01*
X1541830Y1182013D01*
G02X1541851Y1181791I-1181J-224D01*
G02X1540649Y1180589I-1202J0D01*
G02X1540427Y1180610I2J1202D01*
G01X1540378Y1180619D01*
X1540285Y1180590D01*
X1539980Y1180285D01*
X1539951Y1180192D01*
X1539960Y1180143D01*
G02X1539981Y1179921I-1181J-224D01*
G02X1539960Y1179698I-1202J1D01*
G01X1539951Y1179650D01*
X1539980Y1179555D01*
X1540284Y1179251D01*
X1540378Y1179222D01*
X1540427Y1179231D01*
G02X1540649Y1179252I224J-1181D01*
G02X1539447Y1178050I0J-1202D01*
G02X1539468Y1178273I1202J-1D01*
G01X1539477Y1178321D01*
X1539448Y1178416D01*
X1539144Y1178720D01*
X1539050Y1178749D01*
X1539001Y1178740D01*
G02X1538779Y1178719I-224J1181D01*
G02Y1181123I0J1202D01*
G02X1539001Y1181102I-2J-1202D01*
G01X1539050Y1181093D01*
X1539143Y1181122D01*
X1539448Y1181427D01*
X1539477Y1181520D01*
X1539468Y1181569D01*
G02X1539447Y1181791I1181J224D01*
G02X1539468Y1182013I1202J-2D01*
G01X1539477Y1182062D01*
X1539448Y1182155D01*
X1539143Y1182460D01*
X1539050Y1182489D01*
X1539001Y1182480D01*
G02X1538779Y1182459I-224J1181D01*
G02X1539981Y1183661I0J1202D01*
G02X1539960Y1183439I-1202J2D01*
G01X1539951Y1183390D01*
X1539980Y1183297D01*
X1540285Y1182992D01*
X1540378Y1182963D01*
X1540427Y1182972D01*
G02X1540649Y1182993I224J-1181D01*
G02X1540871Y1182972I-2J-1202D01*
G01X1540920Y1182963D01*
X1541013Y1182992D01*
X1541318Y1183297D01*
X1541347Y1183390D01*
G37*
G36*
G01X1550271Y1193709D02*
X1550222Y1193700D01*
G02X1550000Y1193679I-224J1181D01*
G02X1551202Y1194881I0J1202D01*
G02X1551181Y1194659I-1202J2D01*
G01X1551172Y1194610D01*
X1551201Y1194517D01*
X1551506Y1194212D01*
X1551599Y1194183D01*
X1551648Y1194192D01*
G02X1551870Y1194213I224J-1181D01*
G02Y1191809I0J-1202D01*
G02X1551648Y1191830I2J1202D01*
G01X1551599Y1191839D01*
X1551506Y1191810D01*
X1551201Y1191505D01*
X1551172Y1191412D01*
X1551181Y1191363D01*
G02X1551202Y1191141I-1181J-224D01*
G02X1551181Y1190919I-1202J2D01*
G01X1551172Y1190870D01*
X1551201Y1190777D01*
X1551506Y1190472D01*
X1551599Y1190443D01*
X1551648Y1190452D01*
G02X1551870Y1190473I224J-1181D01*
G02Y1188069I0J-1202D01*
G02X1551648Y1188090I2J1202D01*
G01X1551599Y1188099D01*
X1551506Y1188070D01*
X1551201Y1187765D01*
X1551172Y1187672D01*
X1551181Y1187623D01*
G02X1551202Y1187401I-1181J-224D01*
G02X1551181Y1187179I-1202J2D01*
G01X1551172Y1187130D01*
X1551201Y1187037D01*
X1551506Y1186732D01*
X1551599Y1186703D01*
X1551648Y1186712D01*
G02X1551870Y1186733I224J-1181D01*
G02X1550668Y1185531I0J-1202D01*
G02X1550689Y1185753I1202J-2D01*
G01X1550698Y1185802D01*
X1550669Y1185895D01*
X1550364Y1186200D01*
X1550271Y1186229D01*
X1550222Y1186220D01*
G02X1550000Y1186199I-224J1181D01*
G02X1549778Y1186220I2J1202D01*
G01X1549729Y1186229D01*
X1549636Y1186200D01*
X1549331Y1185895D01*
X1549302Y1185802D01*
X1549311Y1185753D01*
G02X1549332Y1185531I-1181J-224D01*
G02X1546928I-1202J0D01*
G02X1546949Y1185753I1202J-2D01*
G01X1546958Y1185802D01*
X1546929Y1185896D01*
X1546625Y1186200D01*
X1546530Y1186229D01*
X1546482Y1186220D01*
G02X1546259Y1186199I-224J1181D01*
G02X1547461Y1187401I0J1202D01*
G02X1547440Y1187179I-1202J2D01*
G01X1547431Y1187130D01*
X1547460Y1187036D01*
X1547764Y1186732D01*
X1547859Y1186703D01*
X1547907Y1186712D01*
G02X1548130Y1186733I224J-1181D01*
G02X1548352Y1186712I-2J-1202D01*
G01X1548401Y1186703D01*
X1548494Y1186732D01*
X1548799Y1187037D01*
X1548828Y1187130D01*
X1548819Y1187179D01*
G02X1548798Y1187401I1181J224D01*
G02X1550000Y1188603I1202J0D01*
G02X1550222Y1188582I-2J-1202D01*
G01X1550271Y1188573D01*
X1550364Y1188602D01*
X1550669Y1188907D01*
X1550698Y1189000D01*
X1550689Y1189049D01*
G02X1550668Y1189271I1181J224D01*
G02X1550689Y1189493I1202J-2D01*
G01X1550698Y1189542D01*
X1550669Y1189635D01*
X1550364Y1189940D01*
X1550271Y1189969D01*
X1550222Y1189960D01*
G02X1550000Y1189939I-224J1181D01*
G02Y1192343I0J1202D01*
G02X1550222Y1192322I-2J-1202D01*
G01X1550271Y1192313D01*
X1550364Y1192342D01*
X1550669Y1192647D01*
X1550698Y1192740D01*
X1550689Y1192789D01*
G02X1550668Y1193011I1181J224D01*
G02X1550689Y1193233I1202J-2D01*
G01X1550698Y1193282D01*
X1550669Y1193375D01*
X1550364Y1193680D01*
X1550271Y1193709D01*
G37*
G36*
G01X1623638Y1409998D02*
X1627038D01*
G02Y1406992I0J-1503D01*
G01X1623638D01*
G02Y1409998I0J1503D01*
G37*
G36*
G01Y1398086D02*
X1627038D01*
G02Y1395080I0J-1503D01*
G01X1623638D01*
G02Y1398086I0J1503D01*
G37*
G36*
G01X1635878Y1409998D02*
X1639278D01*
G02Y1406992I0J-1503D01*
G01X1635878D01*
G02Y1409998I0J1503D01*
G37*
G36*
G01X1648118Y1398086D02*
X1651518D01*
G02Y1395080I0J-1503D01*
G01X1648118D01*
G02Y1398086I0J1503D01*
G37*
G36*
G01Y1409998D02*
X1651518D01*
G02Y1406992I0J-1503D01*
G01X1648118D01*
G02Y1409998I0J1503D01*
G37*
G36*
G01X1660358D02*
X1663758D01*
G02Y1406992I0J-1503D01*
G01X1660358D01*
G02Y1409998I0J1503D01*
G37*
G36*
G01X1672598D02*
X1675998D01*
G02Y1406992I0J-1503D01*
G01X1672598D01*
G02Y1409998I0J1503D01*
G37*
G36*
G01Y1398086D02*
X1675998D01*
G02Y1395080I0J-1503D01*
G01X1672598D01*
G02Y1398086I0J1503D01*
G37*
G36*
G01X1684838Y1409998D02*
X1688238D01*
G02Y1406992I0J-1503D01*
G01X1684838D01*
G02Y1409998I0J1503D01*
G37*
G36*
G01Y1398086D02*
X1688238D01*
G02Y1395080I0J-1503D01*
G01X1684838D01*
G02Y1398086I0J1503D01*
G37*
G36*
G01X1697078D02*
X1700478D01*
G02Y1395080I0J-1503D01*
G01X1697078D01*
G02Y1398086I0J1503D01*
G37*
G36*
G01Y1409998D02*
X1700478D01*
G02Y1406992I0J-1503D01*
G01X1697078D01*
G02Y1409998I0J1503D01*
G37*
G36*
G01X1709318D02*
X1712718D01*
G02Y1406992I0J-1503D01*
G01X1709318D01*
G02Y1409998I0J1503D01*
G37*
G36*
G01Y1398086D02*
X1712718D01*
G02Y1395080I0J-1503D01*
G01X1709318D01*
G02Y1398086I0J1503D01*
G37*
G36*
G01X1721558Y1409998D02*
X1724958D01*
G02Y1406992I0J-1503D01*
G01X1721558D01*
G02Y1409998I0J1503D01*
G37*
G36*
G01Y1398086D02*
X1724958D01*
G02Y1395080I0J-1503D01*
G01X1721558D01*
G02Y1398086I0J1503D01*
G37*
G36*
G01X1733798Y1409998D02*
X1737198D01*
G02Y1406992I0J-1503D01*
G01X1733798D01*
G02Y1409998I0J1503D01*
G37*
G36*
G01Y1398086D02*
X1737198D01*
G02Y1395080I0J-1503D01*
G01X1733798D01*
G02Y1398086I0J1503D01*
G37*
G36*
G01Y1385800D02*
X1737198D01*
G02Y1382794I0J-1503D01*
G01X1733798D01*
G02Y1385800I0J1503D01*
G37*
G36*
G01Y1373888D02*
X1737198D01*
G02Y1370882I0J-1503D01*
G01X1733798D01*
G02Y1373888I0J1503D01*
G37*
G36*
G01X1721558D02*
X1724958D01*
G02Y1370882I0J-1503D01*
G01X1721558D01*
G02Y1373888I0J1503D01*
G37*
G36*
G01Y1385800D02*
X1724958D01*
G02Y1382794I0J-1503D01*
G01X1721558D01*
G02Y1385800I0J1503D01*
G37*
G36*
G01X1709318D02*
X1712718D01*
G02Y1382794I0J-1503D01*
G01X1709318D01*
G02Y1385800I0J1503D01*
G37*
G36*
G01Y1373888D02*
X1712718D01*
G02Y1370882I0J-1503D01*
G01X1709318D01*
G02Y1373888I0J1503D01*
G37*
G36*
G01X1697078Y1385800D02*
X1700478D01*
G02Y1382794I0J-1503D01*
G01X1697078D01*
G02Y1385800I0J1503D01*
G37*
G36*
G01X1684838D02*
X1688238D01*
G02Y1382794I0J-1503D01*
G01X1684838D01*
G02Y1385800I0J1503D01*
G37*
G36*
G01X1672598D02*
X1675998D01*
G02Y1382794I0J-1503D01*
G01X1672598D01*
G02Y1385800I0J1503D01*
G37*
G36*
G01Y1373888D02*
X1675998D01*
G02Y1370882I0J-1503D01*
G01X1672598D01*
G02Y1373888I0J1503D01*
G37*
G36*
G01X1660358Y1385800D02*
X1663758D01*
G02Y1382794I0J-1503D01*
G01X1660358D01*
G02Y1385800I0J1503D01*
G37*
G36*
G01Y1373888D02*
X1663758D01*
G02Y1370882I0J-1503D01*
G01X1660358D01*
G02Y1373888I0J1503D01*
G37*
G36*
G01X1648118D02*
X1651518D01*
G02Y1370882I0J-1503D01*
G01X1648118D01*
G02Y1373888I0J1503D01*
G37*
G36*
G01Y1385800D02*
X1651518D01*
G02Y1382794I0J-1503D01*
G01X1648118D01*
G02Y1385800I0J1503D01*
G37*
G36*
G01X1635878Y1373888D02*
X1639278D01*
G02Y1370882I0J-1503D01*
G01X1635878D01*
G02Y1373888I0J1503D01*
G37*
G36*
G01X1623638D02*
X1627038D01*
G02Y1370882I0J-1503D01*
G01X1623638D01*
G02Y1373888I0J1503D01*
G37*
G36*
G01Y1385800D02*
X1627038D01*
G02Y1382794I0J-1503D01*
G01X1623638D01*
G02Y1385800I0J1503D01*
G37*
G36*
G01Y1349690D02*
X1627038D01*
G02Y1346684I0J-1503D01*
G01X1623638D01*
G02Y1349690I0J1503D01*
G37*
G36*
G01Y1361602D02*
X1627038D01*
G02Y1358596I0J-1503D01*
G01X1623638D01*
G02Y1361602I0J1503D01*
G37*
G36*
G01X1635878D02*
X1639278D01*
G02Y1358596I0J-1503D01*
G01X1635878D01*
G02Y1361602I0J1503D01*
G37*
G36*
G01Y1349690D02*
X1639278D01*
G02Y1346684I0J-1503D01*
G01X1635878D01*
G02Y1349690I0J1503D01*
G37*
G36*
G01X1648118D02*
X1651518D01*
G02Y1346684I0J-1503D01*
G01X1648118D01*
G02Y1349690I0J1503D01*
G37*
G36*
G01Y1361602D02*
X1651518D01*
G02Y1358596I0J-1503D01*
G01X1648118D01*
G02Y1361602I0J1503D01*
G37*
G36*
G01X1660358D02*
X1663758D01*
G02Y1358596I0J-1503D01*
G01X1660358D01*
G02Y1361602I0J1503D01*
G37*
G36*
G01Y1349690D02*
X1663758D01*
G02Y1346684I0J-1503D01*
G01X1660358D01*
G02Y1349690I0J1503D01*
G37*
G36*
G01X1672598D02*
X1675998D01*
G02Y1346684I0J-1503D01*
G01X1672598D01*
G02Y1349690I0J1503D01*
G37*
G36*
G01Y1361602D02*
X1675998D01*
G02Y1358596I0J-1503D01*
G01X1672598D01*
G02Y1361602I0J1503D01*
G37*
G36*
G01X1684838D02*
X1688238D01*
G02Y1358596I0J-1503D01*
G01X1684838D01*
G02Y1361602I0J1503D01*
G37*
G36*
G01Y1349690D02*
X1688238D01*
G02Y1346684I0J-1503D01*
G01X1684838D01*
G02Y1349690I0J1503D01*
G37*
G36*
G01X1697078D02*
X1700478D01*
G02Y1346684I0J-1503D01*
G01X1697078D01*
G02Y1349690I0J1503D01*
G37*
G36*
G01Y1361602D02*
X1700478D01*
G02Y1358596I0J-1503D01*
G01X1697078D01*
G02Y1361602I0J1503D01*
G37*
G36*
G01X1709318D02*
X1712718D01*
G02Y1358596I0J-1503D01*
G01X1709318D01*
G02Y1361602I0J1503D01*
G37*
G36*
G01Y1349690D02*
X1712718D01*
G02Y1346684I0J-1503D01*
G01X1709318D01*
G02Y1349690I0J1503D01*
G37*
G36*
G01X1721558D02*
X1724958D01*
G02Y1346684I0J-1503D01*
G01X1721558D01*
G02Y1349690I0J1503D01*
G37*
G36*
G01Y1361602D02*
X1724958D01*
G02Y1358596I0J-1503D01*
G01X1721558D01*
G02Y1361602I0J1503D01*
G37*
G36*
G01X1733798D02*
X1737198D01*
G02Y1358596I0J-1503D01*
G01X1733798D01*
G02Y1361602I0J1503D01*
G37*
G36*
G01Y1349690D02*
X1737198D01*
G02Y1346684I0J-1503D01*
G01X1733798D01*
G02Y1349690I0J1503D01*
G37*
G36*
G01X1635878Y1398086D02*
X1639278D01*
G02Y1395080I0J-1503D01*
G01X1635878D01*
G02Y1398086I0J1503D01*
G37*
G36*
G01X1697078Y1373888D02*
X1700478D01*
G02Y1370882I0J-1503D01*
G01X1697078D01*
G02Y1373888I0J1503D01*
G37*
G36*
G01X1684838D02*
X1688238D01*
G02Y1370882I0J-1503D01*
G01X1684838D01*
G02Y1373888I0J1503D01*
G37*
G36*
G01X1635878Y1385800D02*
X1639278D01*
G02Y1382794I0J-1503D01*
G01X1635878D01*
G02Y1385800I0J1503D01*
G37*
G36*
G01X1660358Y1398086D02*
X1663758D01*
G02Y1395080I0J-1503D01*
G01X1660358D01*
G02Y1398086I0J1503D01*
G37*
G36*
G01X1711464Y1229810D02*
G03X1711014Y1230198I-400J-9D01*
G02X1710825Y1230186I-189J1490D01*
G02Y1233190I0J1502D01*
G02X1712327Y1231719I0J-1502D01*
G03X1712777Y1231331I400J9D01*
G02X1712966Y1231343I189J-1490D01*
G02Y1228339I0J-1502D01*
G02X1711464Y1229810I0J1502D01*
G37*
G36*
G01X1811271Y1299696D02*
X1811565D01*
G03X1811712Y1299761I-1J200D01*
G02X1813924I1106J-1017D01*
G03X1814071Y1299696I148J135D01*
G01X1814365D01*
G03X1814512Y1299761I-1J200D01*
G02X1815618Y1300246I1106J-1019D01*
G02X1817120Y1298744I0J-1502D01*
G02X1816635Y1297638I-1504J0D01*
G03X1816570Y1297491I135J-148D01*
G01Y1297197D01*
G03X1816635Y1297050I200J1D01*
G02X1817120Y1295944I-1019J-1106D01*
G02X1815618Y1294442I-1502J0D01*
G02X1814512Y1294927I0J1504D01*
G03X1814365Y1294992I-148J-135D01*
G01X1814071D01*
G03X1813924Y1294927I1J-200D01*
G02X1811712I-1106J1017D01*
G03X1811565Y1294992I-148J-135D01*
G01X1811271D01*
G03X1811124Y1294927I1J-200D01*
G02X1810018Y1294442I-1106J1019D01*
G02X1808516Y1295944I0J1502D01*
G02X1809001Y1297050I1504J0D01*
G03X1809066Y1297197I-135J148D01*
G01Y1297491D01*
G03X1809001Y1297638I-200J-1D01*
G02X1808516Y1298744I1019J1106D01*
G02X1810018Y1300246I1502J0D01*
G02X1811124Y1299761I0J-1504D01*
G03X1811271Y1299696I148J135D01*
G37*
G36*
G01X1649922Y1464825D02*
Y1465951D01*
G02X1650125Y1466154I203J0D01*
G01X1652945D01*
G02X1653148Y1465951I0J-203D01*
G01Y1464825D01*
G03X1653176Y1464722I200J-1D01*
G02Y1462760I-1642J-981D01*
G03X1653148Y1462657I172J-102D01*
G01Y1459706D01*
G03X1653176Y1459603I200J-1D01*
G02Y1457641I-1642J-981D01*
G03X1653148Y1457538I172J-102D01*
G01Y1456413D01*
G02X1652945Y1456210I-203J0D01*
G01X1650125D01*
G02X1649922Y1456413I0J203D01*
G01Y1457538D01*
G03X1649894Y1457641I-200J1D01*
G02Y1459603I1642J981D01*
G03X1649922Y1459706I-172J102D01*
G01Y1462657D01*
G03X1649894Y1462760I-200J1D01*
G02Y1464722I1642J981D01*
G03X1649922Y1464825I-172J102D01*
G37*
G36*
G01X1667246D02*
Y1465951D01*
G02X1667448Y1466154I202J1D01*
G01X1670268D01*
G02X1670470Y1465951I-1J-203D01*
G01Y1464825D01*
G03X1670498Y1464722I200J-1D01*
G02X1670770Y1463741I-1640J-983D01*
G02X1670498Y1462760I-1912J2D01*
G03X1670470Y1462657I172J-102D01*
G01Y1459706D01*
G03X1670498Y1459603I200J-1D01*
G02X1670770Y1458622I-1640J-983D01*
G02X1670498Y1457641I-1912J2D01*
G03X1670470Y1457538I172J-102D01*
G01Y1456413D01*
G02X1670268Y1456210I-202J-1D01*
G01X1667448D01*
G02X1667246Y1456413I1J203D01*
G01Y1457538D01*
G03X1667218Y1457641I-200J1D01*
G02X1666946Y1458622I1640J983D01*
G02X1667218Y1459603I1912J-2D01*
G03X1667246Y1459706I-172J102D01*
G01Y1462657D01*
G03X1667218Y1462760I-200J1D01*
G02X1666946Y1463741I1640J983D01*
G02X1667218Y1464722I1912J-2D01*
G03X1667246Y1464825I-172J102D01*
G37*
G36*
G01X1684568D02*
Y1465951D01*
G02X1684771Y1466154I203J0D01*
G01X1687591D01*
G02X1687794Y1465951I0J-203D01*
G01Y1464825D01*
G03X1687822Y1464722I200J-1D01*
G02Y1462760I-1642J-981D01*
G03X1687794Y1462657I172J-102D01*
G01Y1459706D01*
G03X1687822Y1459603I200J-1D01*
G02Y1457641I-1642J-981D01*
G03X1687794Y1457538I172J-102D01*
G01Y1456413D01*
G02X1687591Y1456210I-203J0D01*
G01X1684771D01*
G02X1684568Y1456413I0J203D01*
G01Y1457538D01*
G03X1684540Y1457641I-200J1D01*
G02Y1459603I1642J981D01*
G03X1684568Y1459706I-172J102D01*
G01Y1462657D01*
G03X1684540Y1462760I-200J1D01*
G02Y1464722I1642J981D01*
G03X1684568Y1464825I-172J102D01*
G37*
G36*
G01X1701890D02*
Y1465951D01*
G02X1702093Y1466154I203J0D01*
G01X1704913D01*
G02X1705116Y1465951I0J-203D01*
G01Y1464825D01*
G03X1705144Y1464722I200J-1D01*
G02Y1462760I-1642J-981D01*
G03X1705116Y1462657I172J-102D01*
G01Y1459706D01*
G03X1705144Y1459603I200J-1D01*
G02Y1457641I-1642J-981D01*
G03X1705116Y1457538I172J-102D01*
G01Y1456413D01*
G02X1704913Y1456210I-203J0D01*
G01X1702093D01*
G02X1701890Y1456413I0J203D01*
G01Y1457538D01*
G03X1701862Y1457641I-200J1D01*
G02Y1459603I1642J981D01*
G03X1701890Y1459706I-172J102D01*
G01Y1462657D01*
G03X1701862Y1462760I-200J1D01*
G02Y1464722I1642J981D01*
G03X1701890Y1464825I-172J102D01*
G37*
G36*
G01X1658584Y1469155D02*
Y1470281D01*
G02X1658786Y1470484I202J1D01*
G01X1661606D01*
G02X1661808Y1470281I-1J-203D01*
G01Y1469155D01*
G03X1661836Y1469052I200J-1D01*
G02X1662108Y1468071I-1640J-983D01*
G02X1661836Y1467090I-1912J2D01*
G03X1661808Y1466987I172J-102D01*
G01Y1464037D01*
G03X1661836Y1463934I200J-1D01*
G02X1662108Y1462953I-1640J-983D01*
G02X1661836Y1461972I-1912J2D01*
G03X1661808Y1461869I172J-102D01*
G01Y1460743D01*
G02X1661606Y1460540I-202J-1D01*
G01X1658786D01*
G02X1658584Y1460743I1J203D01*
G01Y1461869D01*
G03X1658556Y1461972I-200J1D01*
G02X1658284Y1462953I1640J983D01*
G02X1658556Y1463934I1912J-2D01*
G03X1658584Y1464037I-172J102D01*
G01Y1466987D01*
G03X1658556Y1467090I-200J1D01*
G02X1658284Y1468071I1640J983D01*
G02X1658556Y1469052I1912J-2D01*
G03X1658584Y1469155I-172J102D01*
G37*
G36*
G01X1675906D02*
Y1470281D01*
G02X1676109Y1470484I203J0D01*
G01X1678929D01*
G02X1679132Y1470281I0J-203D01*
G01Y1469155D01*
G03X1679160Y1469052I200J-1D01*
G02Y1467090I-1642J-981D01*
G03X1679132Y1466987I172J-102D01*
G01Y1464037D01*
G03X1679160Y1463934I200J-1D01*
G02Y1461972I-1642J-981D01*
G03X1679132Y1461869I172J-102D01*
G01Y1460743D01*
G02X1678929Y1460540I-203J0D01*
G01X1676109D01*
G02X1675906Y1460743I0J203D01*
G01Y1461869D01*
G03X1675878Y1461972I-200J1D01*
G02Y1463934I1642J981D01*
G03X1675906Y1464037I-172J102D01*
G01Y1466987D01*
G03X1675878Y1467090I-200J1D01*
G02Y1469052I1642J981D01*
G03X1675906Y1469155I-172J102D01*
G37*
G36*
G01X1693230D02*
Y1470281D01*
G02X1693432Y1470484I202J1D01*
G01X1696252D01*
G02X1696454Y1470281I-1J-203D01*
G01Y1469155D01*
G03X1696482Y1469052I200J-1D01*
G02X1696754Y1468071I-1640J-983D01*
G02X1696482Y1467090I-1912J2D01*
G03X1696454Y1466987I172J-102D01*
G01Y1464037D01*
G03X1696482Y1463934I200J-1D01*
G02X1696754Y1462953I-1640J-983D01*
G02X1696482Y1461972I-1912J2D01*
G03X1696454Y1461869I172J-102D01*
G01Y1460743D01*
G02X1696252Y1460540I-202J-1D01*
G01X1693432D01*
G02X1693230Y1460743I1J203D01*
G01Y1461869D01*
G03X1693202Y1461972I-200J1D01*
G02X1692930Y1462953I1640J983D01*
G02X1693202Y1463934I1912J-2D01*
G03X1693230Y1464037I-172J102D01*
G01Y1466987D01*
G03X1693202Y1467090I-200J1D01*
G02X1692930Y1468071I1640J983D01*
G02X1693202Y1469052I1912J-2D01*
G03X1693230Y1469155I-172J102D01*
G37*
G36*
G01X1710552D02*
Y1470281D01*
G02X1710755Y1470484I203J0D01*
G01X1713575D01*
G02X1713778Y1470281I0J-203D01*
G01Y1469155D01*
G03X1713806Y1469052I200J-1D01*
G02Y1467090I-1642J-981D01*
G03X1713778Y1466987I172J-102D01*
G01Y1464037D01*
G03X1713806Y1463934I200J-1D01*
G02Y1461972I-1642J-981D01*
G03X1713778Y1461869I172J-102D01*
G01Y1460743D01*
G02X1713575Y1460540I-203J0D01*
G01X1710755D01*
G02X1710552Y1460743I0J203D01*
G01Y1461869D01*
G03X1710524Y1461972I-200J1D01*
G02Y1463934I1642J981D01*
G03X1710552Y1464037I-172J102D01*
G01Y1466987D01*
G03X1710524Y1467090I-200J1D01*
G02Y1469052I1642J981D01*
G03X1710552Y1469155I-172J102D01*
G37*
G36*
G01X1597039Y1473598D02*
G02Y1476602I0J1502D01*
G02X1598143Y1476118I0J-1501D01*
G01X1598144Y1476117D01*
G03X1598282Y1476054I146J137D01*
G01X1598605Y1476041D01*
X1598679Y1476068D01*
X1598708Y1476095D01*
G02X1599725Y1476492I1017J-1105D01*
G01X1599726D01*
G02Y1473488I0J-1502D01*
G02X1598622Y1473972I0J1501D01*
G01X1598621Y1473973D01*
G03X1598483Y1474036I-146J-137D01*
G01X1598160Y1474049D01*
X1598086Y1474022D01*
X1598057Y1473995D01*
G02X1597040Y1473598I-1017J1105D01*
G01X1597039D01*
G37*
G36*
G01X1649922Y1480179D02*
Y1481305D01*
G02X1650125Y1481508I203J0D01*
G01X1652945D01*
G02X1653148Y1481305I0J-203D01*
G01Y1480179D01*
G03X1653176Y1480076I200J-1D01*
G02Y1478114I-1642J-981D01*
G03X1653148Y1478011I172J-102D01*
G01Y1475061D01*
G03X1653176Y1474958I200J-1D01*
G02Y1472996I-1642J-981D01*
G03X1653148Y1472893I172J-102D01*
G01Y1471767D01*
G02X1652945Y1471564I-203J0D01*
G01X1650125D01*
G02X1649922Y1471767I0J203D01*
G01Y1472893D01*
G03X1649894Y1472996I-200J1D01*
G02Y1474958I1642J981D01*
G03X1649922Y1475061I-172J102D01*
G01Y1478011D01*
G03X1649894Y1478114I-200J1D01*
G02Y1480076I1642J981D01*
G03X1649922Y1480179I-172J102D01*
G37*
G36*
G01X1667246D02*
Y1481305D01*
G02X1667448Y1481508I202J1D01*
G01X1670268D01*
G02X1670470Y1481305I-1J-203D01*
G01Y1480179D01*
G03X1670498Y1480076I200J-1D01*
G02X1670770Y1479095I-1640J-983D01*
G02X1670498Y1478114I-1912J2D01*
G03X1670470Y1478011I172J-102D01*
G01Y1475061D01*
G03X1670498Y1474958I200J-1D01*
G02X1670770Y1473977I-1640J-983D01*
G02X1670498Y1472996I-1912J2D01*
G03X1670470Y1472893I172J-102D01*
G01Y1471767D01*
G02X1670268Y1471564I-202J-1D01*
G01X1667448D01*
G02X1667246Y1471767I1J203D01*
G01Y1472893D01*
G03X1667218Y1472996I-200J1D01*
G02X1666946Y1473977I1640J983D01*
G02X1667218Y1474958I1912J-2D01*
G03X1667246Y1475061I-172J102D01*
G01Y1478011D01*
G03X1667218Y1478114I-200J1D01*
G02X1666946Y1479095I1640J983D01*
G02X1667218Y1480076I1912J-2D01*
G03X1667246Y1480179I-172J102D01*
G37*
G36*
G01X1684568D02*
Y1481305D01*
G02X1684771Y1481508I203J0D01*
G01X1687591D01*
G02X1687794Y1481305I0J-203D01*
G01Y1480179D01*
G03X1687822Y1480076I200J-1D01*
G02Y1478114I-1642J-981D01*
G03X1687794Y1478011I172J-102D01*
G01Y1475061D01*
G03X1687822Y1474958I200J-1D01*
G02Y1472996I-1642J-981D01*
G03X1687794Y1472893I172J-102D01*
G01Y1471767D01*
G02X1687591Y1471564I-203J0D01*
G01X1684771D01*
G02X1684568Y1471767I0J203D01*
G01Y1472893D01*
G03X1684540Y1472996I-200J1D01*
G02Y1474958I1642J981D01*
G03X1684568Y1475061I-172J102D01*
G01Y1478011D01*
G03X1684540Y1478114I-200J1D01*
G02Y1480076I1642J981D01*
G03X1684568Y1480179I-172J102D01*
G37*
G36*
G01X1701890D02*
Y1481305D01*
G02X1702093Y1481508I203J0D01*
G01X1704913D01*
G02X1705116Y1481305I0J-203D01*
G01Y1480179D01*
G03X1705144Y1480076I200J-1D01*
G02Y1478114I-1642J-981D01*
G03X1705116Y1478011I172J-102D01*
G01Y1475061D01*
G03X1705144Y1474958I200J-1D01*
G02Y1472996I-1642J-981D01*
G03X1705116Y1472893I172J-102D01*
G01Y1471767D01*
G02X1704913Y1471564I-203J0D01*
G01X1702093D01*
G02X1701890Y1471767I0J203D01*
G01Y1472893D01*
G03X1701862Y1472996I-200J1D01*
G02Y1474958I1642J981D01*
G03X1701890Y1475061I-172J102D01*
G01Y1478011D01*
G03X1701862Y1478114I-200J1D01*
G02Y1480076I1642J981D01*
G03X1701890Y1480179I-172J102D01*
G37*
G36*
G01X1658584Y1484510D02*
Y1485635D01*
G02X1658786Y1485838I202J1D01*
G01X1661606D01*
G02X1661808Y1485635I-1J-203D01*
G01Y1484510D01*
G03X1661836Y1484407I200J-1D01*
G02X1662108Y1483426I-1640J-983D01*
G02X1661836Y1482445I-1912J2D01*
G03X1661808Y1482342I172J-102D01*
G01Y1479392D01*
G03X1661836Y1479289I200J-1D01*
G02X1662108Y1478308I-1640J-983D01*
G02X1661836Y1477327I-1912J2D01*
G03X1661808Y1477224I172J-102D01*
G01Y1476097D01*
G02X1661606Y1475894I-202J-1D01*
G01X1658786D01*
G02X1658584Y1476097I1J203D01*
G01Y1477224D01*
G03X1658556Y1477327I-200J1D01*
G02X1658284Y1478308I1640J983D01*
G02X1658556Y1479289I1912J-2D01*
G03X1658584Y1479392I-172J102D01*
G01Y1482342D01*
G03X1658556Y1482445I-200J1D01*
G02X1658284Y1483426I1640J983D01*
G02X1658556Y1484407I1912J-2D01*
G03X1658584Y1484510I-172J102D01*
G37*
G36*
G01X1675906D02*
Y1485635D01*
G02X1676109Y1485838I203J0D01*
G01X1678929D01*
G02X1679132Y1485635I0J-203D01*
G01Y1484510D01*
G03X1679160Y1484407I200J-1D01*
G02Y1482445I-1642J-981D01*
G03X1679132Y1482342I172J-102D01*
G01Y1479392D01*
G03X1679160Y1479289I200J-1D01*
G02Y1477327I-1642J-981D01*
G03X1679132Y1477224I172J-102D01*
G01Y1476097D01*
G02X1678929Y1475894I-203J0D01*
G01X1676109D01*
G02X1675906Y1476097I0J203D01*
G01Y1477224D01*
G03X1675878Y1477327I-200J1D01*
G02Y1479289I1642J981D01*
G03X1675906Y1479392I-172J102D01*
G01Y1482342D01*
G03X1675878Y1482445I-200J1D01*
G02Y1484407I1642J981D01*
G03X1675906Y1484510I-172J102D01*
G37*
G36*
G01X1693230D02*
Y1485635D01*
G02X1693432Y1485838I202J1D01*
G01X1696252D01*
G02X1696454Y1485635I-1J-203D01*
G01Y1484510D01*
G03X1696482Y1484407I200J-1D01*
G02X1696754Y1483426I-1640J-983D01*
G02X1696482Y1482445I-1912J2D01*
G03X1696454Y1482342I172J-102D01*
G01Y1479392D01*
G03X1696482Y1479289I200J-1D01*
G02X1696754Y1478308I-1640J-983D01*
G02X1696482Y1477327I-1912J2D01*
G03X1696454Y1477224I172J-102D01*
G01Y1476097D01*
G02X1696252Y1475894I-202J-1D01*
G01X1693432D01*
G02X1693230Y1476097I1J203D01*
G01Y1477224D01*
G03X1693202Y1477327I-200J1D01*
G02X1692930Y1478308I1640J983D01*
G02X1693202Y1479289I1912J-2D01*
G03X1693230Y1479392I-172J102D01*
G01Y1482342D01*
G03X1693202Y1482445I-200J1D01*
G02X1692930Y1483426I1640J983D01*
G02X1693202Y1484407I1912J-2D01*
G03X1693230Y1484510I-172J102D01*
G37*
G36*
G01X1710552D02*
Y1485635D01*
G02X1710755Y1485838I203J0D01*
G01X1713575D01*
G02X1713778Y1485635I0J-203D01*
G01Y1484510D01*
G03X1713806Y1484407I200J-1D01*
G02Y1482445I-1642J-981D01*
G03X1713778Y1482342I172J-102D01*
G01Y1479392D01*
G03X1713806Y1479289I200J-1D01*
G02Y1477327I-1642J-981D01*
G03X1713778Y1477224I172J-102D01*
G01Y1476097D01*
G02X1713575Y1475894I-203J0D01*
G01X1710755D01*
G02X1710552Y1476097I0J203D01*
G01Y1477224D01*
G03X1710524Y1477327I-200J1D01*
G02Y1479289I1642J981D01*
G03X1710552Y1479392I-172J102D01*
G01Y1482342D01*
G03X1710524Y1482445I-200J1D01*
G02Y1484407I1642J981D01*
G03X1710552Y1484510I-172J102D01*
G37*
G36*
G01X1649922Y1495533D02*
Y1496659D01*
G02X1650125Y1496862I203J0D01*
G01X1652945D01*
G02X1653148Y1496659I0J-203D01*
G01Y1495533D01*
G03X1653176Y1495430I200J-1D01*
G02Y1493468I-1642J-981D01*
G03X1653148Y1493365I172J-102D01*
G01Y1490415D01*
G03X1653176Y1490312I200J-1D01*
G02Y1488350I-1642J-981D01*
G03X1653148Y1488247I172J-102D01*
G01Y1487121D01*
G02X1652945Y1486918I-203J0D01*
G01X1650125D01*
G02X1649922Y1487121I0J203D01*
G01Y1488247D01*
G03X1649894Y1488350I-200J1D01*
G02Y1490312I1642J981D01*
G03X1649922Y1490415I-172J102D01*
G01Y1493365D01*
G03X1649894Y1493468I-200J1D01*
G02Y1495430I1642J981D01*
G03X1649922Y1495533I-172J102D01*
G37*
G36*
G01X1667246D02*
Y1496659D01*
G02X1667448Y1496862I202J1D01*
G01X1670268D01*
G02X1670470Y1496659I-1J-203D01*
G01Y1495533D01*
G03X1670498Y1495430I200J-1D01*
G02X1670770Y1494449I-1640J-983D01*
G02X1670498Y1493468I-1912J2D01*
G03X1670470Y1493365I172J-102D01*
G01Y1490415D01*
G03X1670498Y1490312I200J-1D01*
G02X1670770Y1489331I-1640J-983D01*
G02X1670498Y1488350I-1912J2D01*
G03X1670470Y1488247I172J-102D01*
G01Y1487121D01*
G02X1670268Y1486918I-202J-1D01*
G01X1667448D01*
G02X1667246Y1487121I1J203D01*
G01Y1488247D01*
G03X1667218Y1488350I-200J1D01*
G02X1666946Y1489331I1640J983D01*
G02X1667218Y1490312I1912J-2D01*
G03X1667246Y1490415I-172J102D01*
G01Y1493365D01*
G03X1667218Y1493468I-200J1D01*
G02X1666946Y1494449I1640J983D01*
G02X1667218Y1495430I1912J-2D01*
G03X1667246Y1495533I-172J102D01*
G37*
G36*
G01X1684568D02*
Y1496659D01*
G02X1684771Y1496862I203J0D01*
G01X1687591D01*
G02X1687794Y1496659I0J-203D01*
G01Y1495533D01*
G03X1687822Y1495430I200J-1D01*
G02Y1493468I-1642J-981D01*
G03X1687794Y1493365I172J-102D01*
G01Y1490415D01*
G03X1687822Y1490312I200J-1D01*
G02Y1488350I-1642J-981D01*
G03X1687794Y1488247I172J-102D01*
G01Y1487121D01*
G02X1687591Y1486918I-203J0D01*
G01X1684771D01*
G02X1684568Y1487121I0J203D01*
G01Y1488247D01*
G03X1684540Y1488350I-200J1D01*
G02Y1490312I1642J981D01*
G03X1684568Y1490415I-172J102D01*
G01Y1493365D01*
G03X1684540Y1493468I-200J1D01*
G02Y1495430I1642J981D01*
G03X1684568Y1495533I-172J102D01*
G37*
G36*
G01X1701890D02*
Y1496659D01*
G02X1702093Y1496862I203J0D01*
G01X1704913D01*
G02X1705116Y1496659I0J-203D01*
G01Y1495533D01*
G03X1705144Y1495430I200J-1D01*
G02Y1493468I-1642J-981D01*
G03X1705116Y1493365I172J-102D01*
G01Y1490415D01*
G03X1705144Y1490312I200J-1D01*
G02Y1488350I-1642J-981D01*
G03X1705116Y1488247I172J-102D01*
G01Y1487121D01*
G02X1704913Y1486918I-203J0D01*
G01X1702093D01*
G02X1701890Y1487121I0J203D01*
G01Y1488247D01*
G03X1701862Y1488350I-200J1D01*
G02Y1490312I1642J981D01*
G03X1701890Y1490415I-172J102D01*
G01Y1493365D01*
G03X1701862Y1493468I-200J1D01*
G02Y1495430I1642J981D01*
G03X1701890Y1495533I-172J102D01*
G37*
G36*
G01X1658584Y1499864D02*
Y1500989D01*
G02X1658786Y1501192I202J1D01*
G01X1661606D01*
G02X1661808Y1500989I-1J-203D01*
G01Y1499864D01*
G03X1661836Y1499761I200J-1D01*
G02X1662108Y1498780I-1640J-983D01*
G02X1661836Y1497799I-1912J2D01*
G03X1661808Y1497696I172J-102D01*
G01Y1494746D01*
G03X1661836Y1494643I200J-1D01*
G02X1662108Y1493662I-1640J-983D01*
G02X1661836Y1492681I-1912J2D01*
G03X1661808Y1492578I172J-102D01*
G01Y1491451D01*
G02X1661606Y1491248I-202J-1D01*
G01X1658786D01*
G02X1658584Y1491451I1J203D01*
G01Y1492578D01*
G03X1658556Y1492681I-200J1D01*
G02X1658284Y1493662I1640J983D01*
G02X1658556Y1494643I1912J-2D01*
G03X1658584Y1494746I-172J102D01*
G01Y1497696D01*
G03X1658556Y1497799I-200J1D01*
G02X1658284Y1498780I1640J983D01*
G02X1658556Y1499761I1912J-2D01*
G03X1658584Y1499864I-172J102D01*
G37*
G36*
G01X1675906D02*
Y1500989D01*
G02X1676109Y1501192I203J0D01*
G01X1678929D01*
G02X1679132Y1500989I0J-203D01*
G01Y1499864D01*
G03X1679160Y1499761I200J-1D01*
G02Y1497799I-1642J-981D01*
G03X1679132Y1497696I172J-102D01*
G01Y1494746D01*
G03X1679160Y1494643I200J-1D01*
G02Y1492681I-1642J-981D01*
G03X1679132Y1492578I172J-102D01*
G01Y1491451D01*
G02X1678929Y1491248I-203J0D01*
G01X1676109D01*
G02X1675906Y1491451I0J203D01*
G01Y1492578D01*
G03X1675878Y1492681I-200J1D01*
G02Y1494643I1642J981D01*
G03X1675906Y1494746I-172J102D01*
G01Y1497696D01*
G03X1675878Y1497799I-200J1D01*
G02Y1499761I1642J981D01*
G03X1675906Y1499864I-172J102D01*
G37*
G36*
G01X1693230D02*
Y1500989D01*
G02X1693432Y1501192I202J1D01*
G01X1696252D01*
G02X1696454Y1500989I-1J-203D01*
G01Y1499864D01*
G03X1696482Y1499761I200J-1D01*
G02X1696754Y1498780I-1640J-983D01*
G02X1696482Y1497799I-1912J2D01*
G03X1696454Y1497696I172J-102D01*
G01Y1494746D01*
G03X1696482Y1494643I200J-1D01*
G02X1696754Y1493662I-1640J-983D01*
G02X1696482Y1492681I-1912J2D01*
G03X1696454Y1492578I172J-102D01*
G01Y1491451D01*
G02X1696252Y1491248I-202J-1D01*
G01X1693432D01*
G02X1693230Y1491451I1J203D01*
G01Y1492578D01*
G03X1693202Y1492681I-200J1D01*
G02X1692930Y1493662I1640J983D01*
G02X1693202Y1494643I1912J-2D01*
G03X1693230Y1494746I-172J102D01*
G01Y1497696D01*
G03X1693202Y1497799I-200J1D01*
G02X1692930Y1498780I1640J983D01*
G02X1693202Y1499761I1912J-2D01*
G03X1693230Y1499864I-172J102D01*
G37*
G36*
G01X1710552D02*
Y1500989D01*
G02X1710755Y1501192I203J0D01*
G01X1713575D01*
G02X1713778Y1500989I0J-203D01*
G01Y1499864D01*
G03X1713806Y1499761I200J-1D01*
G02Y1497799I-1642J-981D01*
G03X1713778Y1497696I172J-102D01*
G01Y1494746D01*
G03X1713806Y1494643I200J-1D01*
G02Y1492681I-1642J-981D01*
G03X1713778Y1492578I172J-102D01*
G01Y1491451D01*
G02X1713575Y1491248I-203J0D01*
G01X1710755D01*
G02X1710552Y1491451I0J203D01*
G01Y1492578D01*
G03X1710524Y1492681I-200J1D01*
G02Y1494643I1642J981D01*
G03X1710552Y1494746I-172J102D01*
G01Y1497696D01*
G03X1710524Y1497799I-200J1D01*
G02Y1499761I1642J981D01*
G03X1710552Y1499864I-172J102D01*
G37*
G36*
G01X1649922Y1510888D02*
Y1512014D01*
G02X1650125Y1512216I203J-1D01*
G01X1652945D01*
G02X1653148Y1512014I1J-202D01*
G01Y1510888D01*
G03X1653176Y1510785I200J-1D01*
G02Y1508823I-1642J-981D01*
G03X1653148Y1508720I172J-102D01*
G01Y1505769D01*
G03X1653176Y1505666I200J-1D01*
G02Y1503704I-1642J-981D01*
G03X1653148Y1503601I172J-102D01*
G01Y1502476D01*
G02X1652945Y1502274I-203J1D01*
G01X1650125D01*
G02X1649922Y1502476I-1J202D01*
G01Y1503601D01*
G03X1649894Y1503704I-200J1D01*
G02Y1505666I1642J981D01*
G03X1649922Y1505769I-172J102D01*
G01Y1508720D01*
G03X1649894Y1508823I-200J1D01*
G02Y1510785I1642J981D01*
G03X1649922Y1510888I-172J102D01*
G37*
G36*
G01X1667246D02*
Y1512014D01*
G02X1667448Y1512216I202J0D01*
G01X1670268D01*
G02X1670470Y1512014I0J-202D01*
G01Y1510888D01*
G03X1670498Y1510785I200J-1D01*
G02X1670770Y1509804I-1640J-983D01*
G02X1670498Y1508823I-1912J2D01*
G03X1670470Y1508720I172J-102D01*
G01Y1505769D01*
G03X1670498Y1505666I200J-1D01*
G02X1670770Y1504685I-1640J-983D01*
G02X1670498Y1503704I-1912J2D01*
G03X1670470Y1503601I172J-102D01*
G01Y1502476D01*
G02X1670268Y1502274I-202J0D01*
G01X1667448D01*
G02X1667246Y1502476I0J202D01*
G01Y1503601D01*
G03X1667218Y1503704I-200J1D01*
G02X1666946Y1504685I1640J983D01*
G02X1667218Y1505666I1912J-2D01*
G03X1667246Y1505769I-172J102D01*
G01Y1508720D01*
G03X1667218Y1508823I-200J1D01*
G02X1666946Y1509804I1640J983D01*
G02X1667218Y1510785I1912J-2D01*
G03X1667246Y1510888I-172J102D01*
G37*
G36*
G01X1684568D02*
Y1512014D01*
G02X1684771Y1512216I203J-1D01*
G01X1687591D01*
G02X1687794Y1512014I1J-202D01*
G01Y1510888D01*
G03X1687822Y1510785I200J-1D01*
G02Y1508823I-1642J-981D01*
G03X1687794Y1508720I172J-102D01*
G01Y1505769D01*
G03X1687822Y1505666I200J-1D01*
G02Y1503704I-1642J-981D01*
G03X1687794Y1503601I172J-102D01*
G01Y1502476D01*
G02X1687591Y1502274I-203J1D01*
G01X1684771D01*
G02X1684568Y1502476I-1J202D01*
G01Y1503601D01*
G03X1684540Y1503704I-200J1D01*
G02Y1505666I1642J981D01*
G03X1684568Y1505769I-172J102D01*
G01Y1508720D01*
G03X1684540Y1508823I-200J1D01*
G02Y1510785I1642J981D01*
G03X1684568Y1510888I-172J102D01*
G37*
G36*
G01X1701890D02*
Y1512014D01*
G02X1702093Y1512216I203J-1D01*
G01X1704913D01*
G02X1705116Y1512014I1J-202D01*
G01Y1510888D01*
G03X1705144Y1510785I200J-1D01*
G02Y1508823I-1642J-981D01*
G03X1705116Y1508720I172J-102D01*
G01Y1505769D01*
G03X1705144Y1505666I200J-1D01*
G02Y1503704I-1642J-981D01*
G03X1705116Y1503601I172J-102D01*
G01Y1502476D01*
G02X1704913Y1502274I-203J1D01*
G01X1702093D01*
G02X1701890Y1502476I-1J202D01*
G01Y1503601D01*
G03X1701862Y1503704I-200J1D01*
G02Y1505666I1642J981D01*
G03X1701890Y1505769I-172J102D01*
G01Y1508720D01*
G03X1701862Y1508823I-200J1D01*
G02Y1510785I1642J981D01*
G03X1701890Y1510888I-172J102D01*
G37*
G36*
G01X1658584Y1515218D02*
Y1516344D01*
G02X1658786Y1516546I202J0D01*
G01X1661606D01*
G02X1661808Y1516344I0J-202D01*
G01Y1515218D01*
G03X1661836Y1515115I200J-1D01*
G02X1662108Y1514134I-1640J-983D01*
G02X1661836Y1513153I-1912J2D01*
G03X1661808Y1513050I172J-102D01*
G01Y1510100D01*
G03X1661836Y1509997I200J-1D01*
G02X1662108Y1509016I-1640J-983D01*
G02X1661836Y1508035I-1912J2D01*
G03X1661808Y1507932I172J-102D01*
G01Y1506806D01*
G02X1661606Y1506604I-202J0D01*
G01X1658786D01*
G02X1658584Y1506806I0J202D01*
G01Y1507932D01*
G03X1658556Y1508035I-200J1D01*
G02X1658284Y1509016I1640J983D01*
G02X1658556Y1509997I1912J-2D01*
G03X1658584Y1510100I-172J102D01*
G01Y1513050D01*
G03X1658556Y1513153I-200J1D01*
G02X1658284Y1514134I1640J983D01*
G02X1658556Y1515115I1912J-2D01*
G03X1658584Y1515218I-172J102D01*
G37*
G36*
G01X1675906D02*
Y1516344D01*
G02X1676109Y1516546I203J-1D01*
G01X1678929D01*
G02X1679132Y1516344I1J-202D01*
G01Y1515218D01*
G03X1679160Y1515115I200J-1D01*
G02Y1513153I-1642J-981D01*
G03X1679132Y1513050I172J-102D01*
G01Y1510100D01*
G03X1679160Y1509997I200J-1D01*
G02Y1508035I-1642J-981D01*
G03X1679132Y1507932I172J-102D01*
G01Y1506806D01*
G02X1678929Y1506604I-203J1D01*
G01X1676109D01*
G02X1675906Y1506806I-1J202D01*
G01Y1507932D01*
G03X1675878Y1508035I-200J1D01*
G02Y1509997I1642J981D01*
G03X1675906Y1510100I-172J102D01*
G01Y1513050D01*
G03X1675878Y1513153I-200J1D01*
G02Y1515115I1642J981D01*
G03X1675906Y1515218I-172J102D01*
G37*
G36*
G01X1693230D02*
Y1516344D01*
G02X1693432Y1516546I202J0D01*
G01X1696252D01*
G02X1696454Y1516344I0J-202D01*
G01Y1515218D01*
G03X1696482Y1515115I200J-1D01*
G02X1696754Y1514134I-1640J-983D01*
G02X1696482Y1513153I-1912J2D01*
G03X1696454Y1513050I172J-102D01*
G01Y1510100D01*
G03X1696482Y1509997I200J-1D01*
G02X1696754Y1509016I-1640J-983D01*
G02X1696482Y1508035I-1912J2D01*
G03X1696454Y1507932I172J-102D01*
G01Y1506806D01*
G02X1696252Y1506604I-202J0D01*
G01X1693432D01*
G02X1693230Y1506806I0J202D01*
G01Y1507932D01*
G03X1693202Y1508035I-200J1D01*
G02X1692930Y1509016I1640J983D01*
G02X1693202Y1509997I1912J-2D01*
G03X1693230Y1510100I-172J102D01*
G01Y1513050D01*
G03X1693202Y1513153I-200J1D01*
G02X1692930Y1514134I1640J983D01*
G02X1693202Y1515115I1912J-2D01*
G03X1693230Y1515218I-172J102D01*
G37*
G36*
G01X1710552D02*
Y1516344D01*
G02X1710755Y1516546I203J-1D01*
G01X1713575D01*
G02X1713778Y1516344I1J-202D01*
G01Y1515218D01*
G03X1713806Y1515115I200J-1D01*
G02Y1513153I-1642J-981D01*
G03X1713778Y1513050I172J-102D01*
G01Y1510100D01*
G03X1713806Y1509997I200J-1D01*
G02Y1508035I-1642J-981D01*
G03X1713778Y1507932I172J-102D01*
G01Y1506806D01*
G02X1713575Y1506604I-203J1D01*
G01X1710755D01*
G02X1710552Y1506806I-1J202D01*
G01Y1507932D01*
G03X1710524Y1508035I-200J1D01*
G02Y1509997I1642J981D01*
G03X1710552Y1510100I-172J102D01*
G01Y1513050D01*
G03X1710524Y1513153I-200J1D01*
G02Y1515115I1642J981D01*
G03X1710552Y1515218I-172J102D01*
G37*
G36*
G01X1649922Y1567187D02*
Y1568313D01*
G02X1650125Y1568516I203J0D01*
G01X1652945D01*
G02X1653148Y1568313I0J-203D01*
G01Y1567187D01*
G03X1653176Y1567084I200J-1D01*
G02Y1565122I-1642J-981D01*
G03X1653148Y1565019I172J-102D01*
G01Y1562069D01*
G03X1653176Y1561966I200J-1D01*
G02Y1560004I-1642J-981D01*
G03X1653148Y1559901I172J-102D01*
G01Y1558775D01*
G02X1652945Y1558572I-203J0D01*
G01X1650125D01*
G02X1649922Y1558775I0J203D01*
G01Y1559901D01*
G03X1649894Y1560004I-200J1D01*
G02Y1561966I1642J981D01*
G03X1649922Y1562069I-172J102D01*
G01Y1565019D01*
G03X1649894Y1565122I-200J1D01*
G02Y1567084I1642J981D01*
G03X1649922Y1567187I-172J102D01*
G37*
G36*
G01X1667246D02*
Y1568313D01*
G02X1667448Y1568516I202J1D01*
G01X1670268D01*
G02X1670470Y1568313I-1J-203D01*
G01Y1567187D01*
G03X1670498Y1567084I200J-1D01*
G02X1670770Y1566103I-1640J-983D01*
G02X1670498Y1565122I-1912J2D01*
G03X1670470Y1565019I172J-102D01*
G01Y1562069D01*
G03X1670498Y1561966I200J-1D01*
G02X1670770Y1560985I-1640J-983D01*
G02X1670498Y1560004I-1912J2D01*
G03X1670470Y1559901I172J-102D01*
G01Y1558775D01*
G02X1670268Y1558572I-202J-1D01*
G01X1667448D01*
G02X1667246Y1558775I1J203D01*
G01Y1559901D01*
G03X1667218Y1560004I-200J1D01*
G02X1666946Y1560985I1640J983D01*
G02X1667218Y1561966I1912J-2D01*
G03X1667246Y1562069I-172J102D01*
G01Y1565019D01*
G03X1667218Y1565122I-200J1D01*
G02X1666946Y1566103I1640J983D01*
G02X1667218Y1567084I1912J-2D01*
G03X1667246Y1567187I-172J102D01*
G37*
G36*
G01X1684568D02*
Y1568313D01*
G02X1684771Y1568516I203J0D01*
G01X1687591D01*
G02X1687794Y1568313I0J-203D01*
G01Y1567187D01*
G03X1687822Y1567084I200J-1D01*
G02Y1565122I-1642J-981D01*
G03X1687794Y1565019I172J-102D01*
G01Y1562069D01*
G03X1687822Y1561966I200J-1D01*
G02Y1560004I-1642J-981D01*
G03X1687794Y1559901I172J-102D01*
G01Y1558775D01*
G02X1687591Y1558572I-203J0D01*
G01X1684771D01*
G02X1684568Y1558775I0J203D01*
G01Y1559901D01*
G03X1684540Y1560004I-200J1D01*
G02Y1561966I1642J981D01*
G03X1684568Y1562069I-172J102D01*
G01Y1565019D01*
G03X1684540Y1565122I-200J1D01*
G02Y1567084I1642J981D01*
G03X1684568Y1567187I-172J102D01*
G37*
G36*
G01X1701890D02*
Y1568313D01*
G02X1702093Y1568516I203J0D01*
G01X1704913D01*
G02X1705116Y1568313I0J-203D01*
G01Y1567187D01*
G03X1705144Y1567084I200J-1D01*
G02Y1565122I-1642J-981D01*
G03X1705116Y1565019I172J-102D01*
G01Y1562069D01*
G03X1705144Y1561966I200J-1D01*
G02Y1560004I-1642J-981D01*
G03X1705116Y1559901I172J-102D01*
G01Y1558775D01*
G02X1704913Y1558572I-203J0D01*
G01X1702093D01*
G02X1701890Y1558775I0J203D01*
G01Y1559901D01*
G03X1701862Y1560004I-200J1D01*
G02Y1561966I1642J981D01*
G03X1701890Y1562069I-172J102D01*
G01Y1565019D01*
G03X1701862Y1565122I-200J1D01*
G02Y1567084I1642J981D01*
G03X1701890Y1567187I-172J102D01*
G37*
G36*
G01X1658584Y1571518D02*
Y1572644D01*
G02X1658786Y1572846I202J0D01*
G01X1661606D01*
G02X1661808Y1572644I0J-202D01*
G01Y1571518D01*
G03X1661836Y1571415I200J-1D01*
G02X1662108Y1570434I-1640J-983D01*
G02X1661836Y1569453I-1912J2D01*
G03X1661808Y1569350I172J-102D01*
G01Y1566399D01*
G03X1661836Y1566296I200J-1D01*
G02X1662108Y1565315I-1640J-983D01*
G02X1661836Y1564334I-1912J2D01*
G03X1661808Y1564231I172J-102D01*
G01Y1563106D01*
G02X1661606Y1562904I-202J0D01*
G01X1658786D01*
G02X1658584Y1563106I0J202D01*
G01Y1564231D01*
G03X1658556Y1564334I-200J1D01*
G02X1658284Y1565315I1640J983D01*
G02X1658556Y1566296I1912J-2D01*
G03X1658584Y1566399I-172J102D01*
G01Y1569350D01*
G03X1658556Y1569453I-200J1D01*
G02X1658284Y1570434I1640J983D01*
G02X1658556Y1571415I1912J-2D01*
G03X1658584Y1571518I-172J102D01*
G37*
G36*
G01X1675906D02*
Y1572644D01*
G02X1676109Y1572846I203J-1D01*
G01X1678929D01*
G02X1679132Y1572644I1J-202D01*
G01Y1571518D01*
G03X1679160Y1571415I200J-1D01*
G02Y1569453I-1642J-981D01*
G03X1679132Y1569350I172J-102D01*
G01Y1566399D01*
G03X1679160Y1566296I200J-1D01*
G02Y1564334I-1642J-981D01*
G03X1679132Y1564231I172J-102D01*
G01Y1563106D01*
G02X1678929Y1562904I-203J1D01*
G01X1676109D01*
G02X1675906Y1563106I-1J202D01*
G01Y1564231D01*
G03X1675878Y1564334I-200J1D01*
G02Y1566296I1642J981D01*
G03X1675906Y1566399I-172J102D01*
G01Y1569350D01*
G03X1675878Y1569453I-200J1D01*
G02Y1571415I1642J981D01*
G03X1675906Y1571518I-172J102D01*
G37*
G36*
G01X1693230D02*
Y1572644D01*
G02X1693432Y1572846I202J0D01*
G01X1696252D01*
G02X1696454Y1572644I0J-202D01*
G01Y1571518D01*
G03X1696482Y1571415I200J-1D01*
G02X1696754Y1570434I-1640J-983D01*
G02X1696482Y1569453I-1912J2D01*
G03X1696454Y1569350I172J-102D01*
G01Y1566399D01*
G03X1696482Y1566296I200J-1D01*
G02X1696754Y1565315I-1640J-983D01*
G02X1696482Y1564334I-1912J2D01*
G03X1696454Y1564231I172J-102D01*
G01Y1563106D01*
G02X1696252Y1562904I-202J0D01*
G01X1693432D01*
G02X1693230Y1563106I0J202D01*
G01Y1564231D01*
G03X1693202Y1564334I-200J1D01*
G02X1692930Y1565315I1640J983D01*
G02X1693202Y1566296I1912J-2D01*
G03X1693230Y1566399I-172J102D01*
G01Y1569350D01*
G03X1693202Y1569453I-200J1D01*
G02X1692930Y1570434I1640J983D01*
G02X1693202Y1571415I1912J-2D01*
G03X1693230Y1571518I-172J102D01*
G37*
G36*
G01X1710552D02*
Y1572644D01*
G02X1710755Y1572846I203J-1D01*
G01X1713575D01*
G02X1713778Y1572644I1J-202D01*
G01Y1571518D01*
G03X1713806Y1571415I200J-1D01*
G02Y1569453I-1642J-981D01*
G03X1713778Y1569350I172J-102D01*
G01Y1566399D01*
G03X1713806Y1566296I200J-1D01*
G02Y1564334I-1642J-981D01*
G03X1713778Y1564231I172J-102D01*
G01Y1563106D01*
G02X1713575Y1562904I-203J1D01*
G01X1710755D01*
G02X1710552Y1563106I-1J202D01*
G01Y1564231D01*
G03X1710524Y1564334I-200J1D01*
G02Y1566296I1642J981D01*
G03X1710552Y1566399I-172J102D01*
G01Y1569350D01*
G03X1710524Y1569453I-200J1D01*
G02Y1571415I1642J981D01*
G03X1710552Y1571518I-172J102D01*
G37*
G36*
G01X1649922Y1582541D02*
Y1583667D01*
G02X1650125Y1583870I203J0D01*
G01X1652945D01*
G02X1653148Y1583667I0J-203D01*
G01Y1582541D01*
G03X1653176Y1582438I200J-1D01*
G02Y1580476I-1642J-981D01*
G03X1653148Y1580373I172J-102D01*
G01Y1577423D01*
G03X1653176Y1577320I200J-1D01*
G02Y1575358I-1642J-981D01*
G03X1653148Y1575255I172J-102D01*
G01Y1574129D01*
G02X1652945Y1573926I-203J0D01*
G01X1650125D01*
G02X1649922Y1574129I0J203D01*
G01Y1575255D01*
G03X1649894Y1575358I-200J1D01*
G02Y1577320I1642J981D01*
G03X1649922Y1577423I-172J102D01*
G01Y1580373D01*
G03X1649894Y1580476I-200J1D01*
G02Y1582438I1642J981D01*
G03X1649922Y1582541I-172J102D01*
G37*
G36*
G01X1667246D02*
Y1583667D01*
G02X1667448Y1583870I202J1D01*
G01X1670268D01*
G02X1670470Y1583667I-1J-203D01*
G01Y1582541D01*
G03X1670498Y1582438I200J-1D01*
G02X1670770Y1581457I-1640J-983D01*
G02X1670498Y1580476I-1912J2D01*
G03X1670470Y1580373I172J-102D01*
G01Y1577423D01*
G03X1670498Y1577320I200J-1D01*
G02X1670770Y1576339I-1640J-983D01*
G02X1670498Y1575358I-1912J2D01*
G03X1670470Y1575255I172J-102D01*
G01Y1574129D01*
G02X1670268Y1573926I-202J-1D01*
G01X1667448D01*
G02X1667246Y1574129I1J203D01*
G01Y1575255D01*
G03X1667218Y1575358I-200J1D01*
G02X1666946Y1576339I1640J983D01*
G02X1667218Y1577320I1912J-2D01*
G03X1667246Y1577423I-172J102D01*
G01Y1580373D01*
G03X1667218Y1580476I-200J1D01*
G02X1666946Y1581457I1640J983D01*
G02X1667218Y1582438I1912J-2D01*
G03X1667246Y1582541I-172J102D01*
G37*
G36*
G01X1684568D02*
Y1583667D01*
G02X1684771Y1583870I203J0D01*
G01X1687591D01*
G02X1687794Y1583667I0J-203D01*
G01Y1582541D01*
G03X1687822Y1582438I200J-1D01*
G02Y1580476I-1642J-981D01*
G03X1687794Y1580373I172J-102D01*
G01Y1577423D01*
G03X1687822Y1577320I200J-1D01*
G02Y1575358I-1642J-981D01*
G03X1687794Y1575255I172J-102D01*
G01Y1574129D01*
G02X1687591Y1573926I-203J0D01*
G01X1684771D01*
G02X1684568Y1574129I0J203D01*
G01Y1575255D01*
G03X1684540Y1575358I-200J1D01*
G02Y1577320I1642J981D01*
G03X1684568Y1577423I-172J102D01*
G01Y1580373D01*
G03X1684540Y1580476I-200J1D01*
G02Y1582438I1642J981D01*
G03X1684568Y1582541I-172J102D01*
G37*
G36*
G01X1701890D02*
Y1583667D01*
G02X1702093Y1583870I203J0D01*
G01X1704913D01*
G02X1705116Y1583667I0J-203D01*
G01Y1582541D01*
G03X1705144Y1582438I200J-1D01*
G02Y1580476I-1642J-981D01*
G03X1705116Y1580373I172J-102D01*
G01Y1577423D01*
G03X1705144Y1577320I200J-1D01*
G02Y1575358I-1642J-981D01*
G03X1705116Y1575255I172J-102D01*
G01Y1574129D01*
G02X1704913Y1573926I-203J0D01*
G01X1702093D01*
G02X1701890Y1574129I0J203D01*
G01Y1575255D01*
G03X1701862Y1575358I-200J1D01*
G02Y1577320I1642J981D01*
G03X1701890Y1577423I-172J102D01*
G01Y1580373D01*
G03X1701862Y1580476I-200J1D01*
G02Y1582438I1642J981D01*
G03X1701890Y1582541I-172J102D01*
G37*
G36*
G01X1658584Y1586872D02*
Y1587998D01*
G02X1658786Y1588200I202J0D01*
G01X1661606D01*
G02X1661808Y1587998I0J-202D01*
G01Y1586872D01*
G03X1661836Y1586769I200J-1D01*
G02X1662108Y1585788I-1640J-983D01*
G02X1661836Y1584807I-1912J2D01*
G03X1661808Y1584704I172J-102D01*
G01Y1581754D01*
G03X1661836Y1581651I200J-1D01*
G02X1662108Y1580670I-1640J-983D01*
G02X1661836Y1579689I-1912J2D01*
G03X1661808Y1579586I172J-102D01*
G01Y1578460D01*
G02X1661606Y1578258I-202J0D01*
G01X1658786D01*
G02X1658584Y1578460I0J202D01*
G01Y1579586D01*
G03X1658556Y1579689I-200J1D01*
G02X1658284Y1580670I1640J983D01*
G02X1658556Y1581651I1912J-2D01*
G03X1658584Y1581754I-172J102D01*
G01Y1584704D01*
G03X1658556Y1584807I-200J1D01*
G02X1658284Y1585788I1640J983D01*
G02X1658556Y1586769I1912J-2D01*
G03X1658584Y1586872I-172J102D01*
G37*
G36*
G01X1675906D02*
Y1587998D01*
G02X1676109Y1588200I203J-1D01*
G01X1678929D01*
G02X1679132Y1587998I1J-202D01*
G01Y1586872D01*
G03X1679160Y1586769I200J-1D01*
G02Y1584807I-1642J-981D01*
G03X1679132Y1584704I172J-102D01*
G01Y1581754D01*
G03X1679160Y1581651I200J-1D01*
G02Y1579689I-1642J-981D01*
G03X1679132Y1579586I172J-102D01*
G01Y1578460D01*
G02X1678929Y1578258I-203J1D01*
G01X1676109D01*
G02X1675906Y1578460I-1J202D01*
G01Y1579586D01*
G03X1675878Y1579689I-200J1D01*
G02Y1581651I1642J981D01*
G03X1675906Y1581754I-172J102D01*
G01Y1584704D01*
G03X1675878Y1584807I-200J1D01*
G02Y1586769I1642J981D01*
G03X1675906Y1586872I-172J102D01*
G37*
G36*
G01X1693230D02*
Y1587998D01*
G02X1693432Y1588200I202J0D01*
G01X1696252D01*
G02X1696454Y1587998I0J-202D01*
G01Y1586872D01*
G03X1696482Y1586769I200J-1D01*
G02X1696754Y1585788I-1640J-983D01*
G02X1696482Y1584807I-1912J2D01*
G03X1696454Y1584704I172J-102D01*
G01Y1581754D01*
G03X1696482Y1581651I200J-1D01*
G02X1696754Y1580670I-1640J-983D01*
G02X1696482Y1579689I-1912J2D01*
G03X1696454Y1579586I172J-102D01*
G01Y1578460D01*
G02X1696252Y1578258I-202J0D01*
G01X1693432D01*
G02X1693230Y1578460I0J202D01*
G01Y1579586D01*
G03X1693202Y1579689I-200J1D01*
G02X1692930Y1580670I1640J983D01*
G02X1693202Y1581651I1912J-2D01*
G03X1693230Y1581754I-172J102D01*
G01Y1584704D01*
G03X1693202Y1584807I-200J1D01*
G02X1692930Y1585788I1640J983D01*
G02X1693202Y1586769I1912J-2D01*
G03X1693230Y1586872I-172J102D01*
G37*
G36*
G01X1710552D02*
Y1587998D01*
G02X1710755Y1588200I203J-1D01*
G01X1713575D01*
G02X1713778Y1587998I1J-202D01*
G01Y1586872D01*
G03X1713806Y1586769I200J-1D01*
G02Y1584807I-1642J-981D01*
G03X1713778Y1584704I172J-102D01*
G01Y1581754D01*
G03X1713806Y1581651I200J-1D01*
G02Y1579689I-1642J-981D01*
G03X1713778Y1579586I172J-102D01*
G01Y1578460D01*
G02X1713575Y1578258I-203J1D01*
G01X1710755D01*
G02X1710552Y1578460I-1J202D01*
G01Y1579586D01*
G03X1710524Y1579689I-200J1D01*
G02Y1581651I1642J981D01*
G03X1710552Y1581754I-172J102D01*
G01Y1584704D01*
G03X1710524Y1584807I-200J1D01*
G02Y1586769I1642J981D01*
G03X1710552Y1586872I-172J102D01*
G37*
G36*
G01X1649922Y1597895D02*
Y1599021D01*
G02X1650125Y1599224I203J0D01*
G01X1652945D01*
G02X1653148Y1599021I0J-203D01*
G01Y1597895D01*
G03X1653176Y1597792I200J-1D01*
G02Y1595830I-1642J-981D01*
G03X1653148Y1595727I172J-102D01*
G01Y1592777D01*
G03X1653176Y1592674I200J-1D01*
G02Y1590712I-1642J-981D01*
G03X1653148Y1590609I172J-102D01*
G01Y1589483D01*
G02X1652945Y1589280I-203J0D01*
G01X1650125D01*
G02X1649922Y1589483I0J203D01*
G01Y1590609D01*
G03X1649894Y1590712I-200J1D01*
G02Y1592674I1642J981D01*
G03X1649922Y1592777I-172J102D01*
G01Y1595727D01*
G03X1649894Y1595830I-200J1D01*
G02Y1597792I1642J981D01*
G03X1649922Y1597895I-172J102D01*
G37*
G36*
G01X1667246D02*
Y1599021D01*
G02X1667448Y1599224I202J1D01*
G01X1670268D01*
G02X1670470Y1599021I-1J-203D01*
G01Y1597895D01*
G03X1670498Y1597792I200J-1D01*
G02X1670770Y1596811I-1640J-983D01*
G02X1670498Y1595830I-1912J2D01*
G03X1670470Y1595727I172J-102D01*
G01Y1592777D01*
G03X1670498Y1592674I200J-1D01*
G02X1670770Y1591693I-1640J-983D01*
G02X1670498Y1590712I-1912J2D01*
G03X1670470Y1590609I172J-102D01*
G01Y1589483D01*
G02X1670268Y1589280I-202J-1D01*
G01X1667448D01*
G02X1667246Y1589483I1J203D01*
G01Y1590609D01*
G03X1667218Y1590712I-200J1D01*
G02X1666946Y1591693I1640J983D01*
G02X1667218Y1592674I1912J-2D01*
G03X1667246Y1592777I-172J102D01*
G01Y1595727D01*
G03X1667218Y1595830I-200J1D01*
G02X1666946Y1596811I1640J983D01*
G02X1667218Y1597792I1912J-2D01*
G03X1667246Y1597895I-172J102D01*
G37*
G36*
G01X1684568D02*
Y1599021D01*
G02X1684771Y1599224I203J0D01*
G01X1687591D01*
G02X1687794Y1599021I0J-203D01*
G01Y1597895D01*
G03X1687822Y1597792I200J-1D01*
G02Y1595830I-1642J-981D01*
G03X1687794Y1595727I172J-102D01*
G01Y1592777D01*
G03X1687822Y1592674I200J-1D01*
G02Y1590712I-1642J-981D01*
G03X1687794Y1590609I172J-102D01*
G01Y1589483D01*
G02X1687591Y1589280I-203J0D01*
G01X1684771D01*
G02X1684568Y1589483I0J203D01*
G01Y1590609D01*
G03X1684540Y1590712I-200J1D01*
G02Y1592674I1642J981D01*
G03X1684568Y1592777I-172J102D01*
G01Y1595727D01*
G03X1684540Y1595830I-200J1D01*
G02Y1597792I1642J981D01*
G03X1684568Y1597895I-172J102D01*
G37*
G36*
G01X1701890D02*
Y1599021D01*
G02X1702093Y1599224I203J0D01*
G01X1704913D01*
G02X1705116Y1599021I0J-203D01*
G01Y1597895D01*
G03X1705144Y1597792I200J-1D01*
G02Y1595830I-1642J-981D01*
G03X1705116Y1595727I172J-102D01*
G01Y1592777D01*
G03X1705144Y1592674I200J-1D01*
G02Y1590712I-1642J-981D01*
G03X1705116Y1590609I172J-102D01*
G01Y1589483D01*
G02X1704913Y1589280I-203J0D01*
G01X1702093D01*
G02X1701890Y1589483I0J203D01*
G01Y1590609D01*
G03X1701862Y1590712I-200J1D01*
G02Y1592674I1642J981D01*
G03X1701890Y1592777I-172J102D01*
G01Y1595727D01*
G03X1701862Y1595830I-200J1D01*
G02Y1597792I1642J981D01*
G03X1701890Y1597895I-172J102D01*
G37*
G36*
G01X1658584Y1602226D02*
Y1603352D01*
G02X1658786Y1603554I202J0D01*
G01X1661606D01*
G02X1661808Y1603352I0J-202D01*
G01Y1602226D01*
G03X1661836Y1602123I200J-1D01*
G02X1662108Y1601142I-1640J-983D01*
G02X1661836Y1600161I-1912J2D01*
G03X1661808Y1600058I172J-102D01*
G01Y1597108D01*
G03X1661836Y1597005I200J-1D01*
G02X1662108Y1596024I-1640J-983D01*
G02X1661836Y1595043I-1912J2D01*
G03X1661808Y1594940I172J-102D01*
G01Y1593814D01*
G02X1661606Y1593612I-202J0D01*
G01X1658786D01*
G02X1658584Y1593814I0J202D01*
G01Y1594940D01*
G03X1658556Y1595043I-200J1D01*
G02X1658284Y1596024I1640J983D01*
G02X1658556Y1597005I1912J-2D01*
G03X1658584Y1597108I-172J102D01*
G01Y1600058D01*
G03X1658556Y1600161I-200J1D01*
G02X1658284Y1601142I1640J983D01*
G02X1658556Y1602123I1912J-2D01*
G03X1658584Y1602226I-172J102D01*
G37*
G36*
G01X1675906D02*
Y1603352D01*
G02X1676109Y1603554I203J-1D01*
G01X1678929D01*
G02X1679132Y1603352I1J-202D01*
G01Y1602226D01*
G03X1679160Y1602123I200J-1D01*
G02Y1600161I-1642J-981D01*
G03X1679132Y1600058I172J-102D01*
G01Y1597108D01*
G03X1679160Y1597005I200J-1D01*
G02Y1595043I-1642J-981D01*
G03X1679132Y1594940I172J-102D01*
G01Y1593814D01*
G02X1678929Y1593612I-203J1D01*
G01X1676109D01*
G02X1675906Y1593814I-1J202D01*
G01Y1594940D01*
G03X1675878Y1595043I-200J1D01*
G02Y1597005I1642J981D01*
G03X1675906Y1597108I-172J102D01*
G01Y1600058D01*
G03X1675878Y1600161I-200J1D01*
G02Y1602123I1642J981D01*
G03X1675906Y1602226I-172J102D01*
G37*
G36*
G01X1693230D02*
Y1603352D01*
G02X1693432Y1603554I202J0D01*
G01X1696252D01*
G02X1696454Y1603352I0J-202D01*
G01Y1602226D01*
G03X1696482Y1602123I200J-1D01*
G02X1696754Y1601142I-1640J-983D01*
G02X1696482Y1600161I-1912J2D01*
G03X1696454Y1600058I172J-102D01*
G01Y1597108D01*
G03X1696482Y1597005I200J-1D01*
G02X1696754Y1596024I-1640J-983D01*
G02X1696482Y1595043I-1912J2D01*
G03X1696454Y1594940I172J-102D01*
G01Y1593814D01*
G02X1696252Y1593612I-202J0D01*
G01X1693432D01*
G02X1693230Y1593814I0J202D01*
G01Y1594940D01*
G03X1693202Y1595043I-200J1D01*
G02X1692930Y1596024I1640J983D01*
G02X1693202Y1597005I1912J-2D01*
G03X1693230Y1597108I-172J102D01*
G01Y1600058D01*
G03X1693202Y1600161I-200J1D01*
G02X1692930Y1601142I1640J983D01*
G02X1693202Y1602123I1912J-2D01*
G03X1693230Y1602226I-172J102D01*
G37*
G36*
G01X1710552D02*
Y1603352D01*
G02X1710755Y1603554I203J-1D01*
G01X1713575D01*
G02X1713778Y1603352I1J-202D01*
G01Y1602226D01*
G03X1713806Y1602123I200J-1D01*
G02Y1600161I-1642J-981D01*
G03X1713778Y1600058I172J-102D01*
G01Y1597108D01*
G03X1713806Y1597005I200J-1D01*
G02Y1595043I-1642J-981D01*
G03X1713778Y1594940I172J-102D01*
G01Y1593814D01*
G02X1713575Y1593612I-203J1D01*
G01X1710755D01*
G02X1710552Y1593814I-1J202D01*
G01Y1594940D01*
G03X1710524Y1595043I-200J1D01*
G02Y1597005I1642J981D01*
G03X1710552Y1597108I-172J102D01*
G01Y1600058D01*
G03X1710524Y1600161I-200J1D01*
G02Y1602123I1642J981D01*
G03X1710552Y1602226I-172J102D01*
G37*
G36*
G01X1649922Y1613250D02*
Y1614376D01*
G02X1650125Y1614578I203J-1D01*
G01X1652945D01*
G02X1653148Y1614376I1J-202D01*
G01Y1613250D01*
G03X1653176Y1613147I200J-1D01*
G02Y1611185I-1642J-981D01*
G03X1653148Y1611082I172J-102D01*
G01Y1608132D01*
G03X1653176Y1608029I200J-1D01*
G02Y1606067I-1642J-981D01*
G03X1653148Y1605964I172J-102D01*
G01Y1604838D01*
G02X1652945Y1604636I-203J1D01*
G01X1650125D01*
G02X1649922Y1604838I-1J202D01*
G01Y1605964D01*
G03X1649894Y1606067I-200J1D01*
G02Y1608029I1642J981D01*
G03X1649922Y1608132I-172J102D01*
G01Y1611082D01*
G03X1649894Y1611185I-200J1D01*
G02Y1613147I1642J981D01*
G03X1649922Y1613250I-172J102D01*
G37*
G36*
G01X1667246D02*
Y1614376D01*
G02X1667448Y1614578I202J0D01*
G01X1670268D01*
G02X1670470Y1614376I0J-202D01*
G01Y1613250D01*
G03X1670498Y1613147I200J-1D01*
G02X1670770Y1612166I-1640J-983D01*
G02X1670498Y1611185I-1912J2D01*
G03X1670470Y1611082I172J-102D01*
G01Y1608132D01*
G03X1670498Y1608029I200J-1D01*
G02X1670770Y1607048I-1640J-983D01*
G02X1670498Y1606067I-1912J2D01*
G03X1670470Y1605964I172J-102D01*
G01Y1604838D01*
G02X1670268Y1604636I-202J0D01*
G01X1667448D01*
G02X1667246Y1604838I0J202D01*
G01Y1605964D01*
G03X1667218Y1606067I-200J1D01*
G02X1666946Y1607048I1640J983D01*
G02X1667218Y1608029I1912J-2D01*
G03X1667246Y1608132I-172J102D01*
G01Y1611082D01*
G03X1667218Y1611185I-200J1D01*
G02X1666946Y1612166I1640J983D01*
G02X1667218Y1613147I1912J-2D01*
G03X1667246Y1613250I-172J102D01*
G37*
G36*
G01X1684568D02*
Y1614376D01*
G02X1684771Y1614578I203J-1D01*
G01X1687591D01*
G02X1687794Y1614376I1J-202D01*
G01Y1613250D01*
G03X1687822Y1613147I200J-1D01*
G02Y1611185I-1642J-981D01*
G03X1687794Y1611082I172J-102D01*
G01Y1608132D01*
G03X1687822Y1608029I200J-1D01*
G02Y1606067I-1642J-981D01*
G03X1687794Y1605964I172J-102D01*
G01Y1604838D01*
G02X1687591Y1604636I-203J1D01*
G01X1684771D01*
G02X1684568Y1604838I-1J202D01*
G01Y1605964D01*
G03X1684540Y1606067I-200J1D01*
G02Y1608029I1642J981D01*
G03X1684568Y1608132I-172J102D01*
G01Y1611082D01*
G03X1684540Y1611185I-200J1D01*
G02Y1613147I1642J981D01*
G03X1684568Y1613250I-172J102D01*
G37*
G36*
G01X1701890D02*
Y1614376D01*
G02X1702093Y1614578I203J-1D01*
G01X1704913D01*
G02X1705116Y1614376I1J-202D01*
G01Y1613250D01*
G03X1705144Y1613147I200J-1D01*
G02Y1611185I-1642J-981D01*
G03X1705116Y1611082I172J-102D01*
G01Y1608132D01*
G03X1705144Y1608029I200J-1D01*
G02Y1606067I-1642J-981D01*
G03X1705116Y1605964I172J-102D01*
G01Y1604838D01*
G02X1704913Y1604636I-203J1D01*
G01X1702093D01*
G02X1701890Y1604838I-1J202D01*
G01Y1605964D01*
G03X1701862Y1606067I-200J1D01*
G02Y1608029I1642J981D01*
G03X1701890Y1608132I-172J102D01*
G01Y1611082D01*
G03X1701862Y1611185I-200J1D01*
G02Y1613147I1642J981D01*
G03X1701890Y1613250I-172J102D01*
G37*
G36*
G01X1658584Y1617580D02*
Y1618706D01*
G02X1658786Y1618908I202J0D01*
G01X1661606D01*
G02X1661808Y1618706I0J-202D01*
G01Y1617580D01*
G03X1661836Y1617477I200J-1D01*
G02X1662108Y1616496I-1640J-983D01*
G02X1661836Y1615515I-1912J2D01*
G03X1661808Y1615412I172J-102D01*
G01Y1612462D01*
G03X1661836Y1612359I200J-1D01*
G02X1662108Y1611378I-1640J-983D01*
G02X1661836Y1610397I-1912J2D01*
G03X1661808Y1610294I172J-102D01*
G01Y1609168D01*
G02X1661606Y1608966I-202J0D01*
G01X1658786D01*
G02X1658584Y1609168I0J202D01*
G01Y1610294D01*
G03X1658556Y1610397I-200J1D01*
G02X1658284Y1611378I1640J983D01*
G02X1658556Y1612359I1912J-2D01*
G03X1658584Y1612462I-172J102D01*
G01Y1615412D01*
G03X1658556Y1615515I-200J1D01*
G02X1658284Y1616496I1640J983D01*
G02X1658556Y1617477I1912J-2D01*
G03X1658584Y1617580I-172J102D01*
G37*
G36*
G01X1675906D02*
Y1618706D01*
G02X1676109Y1618908I203J-1D01*
G01X1678929D01*
G02X1679132Y1618706I1J-202D01*
G01Y1617580D01*
G03X1679160Y1617477I200J-1D01*
G02Y1615515I-1642J-981D01*
G03X1679132Y1615412I172J-102D01*
G01Y1612462D01*
G03X1679160Y1612359I200J-1D01*
G02Y1610397I-1642J-981D01*
G03X1679132Y1610294I172J-102D01*
G01Y1609168D01*
G02X1678929Y1608966I-203J1D01*
G01X1676109D01*
G02X1675906Y1609168I-1J202D01*
G01Y1610294D01*
G03X1675878Y1610397I-200J1D01*
G02Y1612359I1642J981D01*
G03X1675906Y1612462I-172J102D01*
G01Y1615412D01*
G03X1675878Y1615515I-200J1D01*
G02Y1617477I1642J981D01*
G03X1675906Y1617580I-172J102D01*
G37*
G36*
G01X1693230D02*
Y1618706D01*
G02X1693432Y1618908I202J0D01*
G01X1696252D01*
G02X1696454Y1618706I0J-202D01*
G01Y1617580D01*
G03X1696482Y1617477I200J-1D01*
G02X1696754Y1616496I-1640J-983D01*
G02X1696482Y1615515I-1912J2D01*
G03X1696454Y1615412I172J-102D01*
G01Y1612462D01*
G03X1696482Y1612359I200J-1D01*
G02X1696754Y1611378I-1640J-983D01*
G02X1696482Y1610397I-1912J2D01*
G03X1696454Y1610294I172J-102D01*
G01Y1609168D01*
G02X1696252Y1608966I-202J0D01*
G01X1693432D01*
G02X1693230Y1609168I0J202D01*
G01Y1610294D01*
G03X1693202Y1610397I-200J1D01*
G02X1692930Y1611378I1640J983D01*
G02X1693202Y1612359I1912J-2D01*
G03X1693230Y1612462I-172J102D01*
G01Y1615412D01*
G03X1693202Y1615515I-200J1D01*
G02X1692930Y1616496I1640J983D01*
G02X1693202Y1617477I1912J-2D01*
G03X1693230Y1617580I-172J102D01*
G37*
G36*
G01X1710552D02*
Y1618706D01*
G02X1710755Y1618908I203J-1D01*
G01X1713575D01*
G02X1713778Y1618706I1J-202D01*
G01Y1617580D01*
G03X1713806Y1617477I200J-1D01*
G02Y1615515I-1642J-981D01*
G03X1713778Y1615412I172J-102D01*
G01Y1612462D01*
G03X1713806Y1612359I200J-1D01*
G02Y1610397I-1642J-981D01*
G03X1713778Y1610294I172J-102D01*
G01Y1609168D01*
G02X1713575Y1608966I-203J1D01*
G01X1710755D01*
G02X1710552Y1609168I-1J202D01*
G01Y1610294D01*
G03X1710524Y1610397I-200J1D01*
G02Y1612359I1642J981D01*
G03X1710552Y1612462I-172J102D01*
G01Y1615412D01*
G03X1710524Y1615515I-200J1D01*
G02Y1617477I1642J981D01*
G03X1710552Y1617580I-172J102D01*
G37*
G36*
G01X1591968Y1459365D02*
G02X1591141Y1460707I675J1342D01*
G02X1594145I1502J0D01*
G02X1593614Y1459561I-1502J0D01*
G03X1593694Y1458899I259J-305D01*
G02X1594521Y1457557I-675J-1342D01*
G02X1591517I-1502J0D01*
G02X1592048Y1458703I1502J0D01*
G03X1591968Y1459365I-259J305D01*
G37*
G36*
G01X1802710Y1466164D02*
G02X1802260Y1467236I1052J1072D01*
G02X1805264I1502J0D01*
G02X1804064Y1465765I-1502J0D01*
G03X1803865Y1465087I81J-392D01*
G02X1804315Y1464015I-1052J-1072D01*
G02X1801311I-1502J0D01*
G02X1802511Y1465486I1502J0D01*
G03X1802710Y1466164I-81J392D01*
G37*
G36*
G01X1506965Y1010637D02*
X1506959Y1011046D01*
X1506918Y1011127D01*
X1506881Y1011156D01*
G02X1506284Y1012354I905J1199D01*
G02X1509288I1502J0D01*
G02X1508727Y1011183I-1503J0D01*
G01X1508691Y1011154D01*
X1508652Y1011071D01*
X1508658Y1010662D01*
X1508699Y1010581D01*
X1508736Y1010552D01*
G02X1509333Y1009354I-905J-1199D01*
G02X1506329I-1502J0D01*
G02X1506890Y1010525I1503J0D01*
G01X1506926Y1010554D01*
X1506965Y1010637D01*
G37*
G36*
G01Y1023237D02*
X1506959Y1023646D01*
X1506918Y1023727D01*
X1506881Y1023756D01*
G02X1506284Y1024954I905J1199D01*
G02X1509288I1502J0D01*
G02X1508727Y1023783I-1503J0D01*
G01X1508691Y1023754D01*
X1508652Y1023671D01*
X1508658Y1023262D01*
X1508699Y1023181D01*
X1508736Y1023152D01*
G02X1509333Y1021954I-905J-1199D01*
G02X1506329I-1502J0D01*
G02X1506890Y1023125I1503J0D01*
G01X1506926Y1023154D01*
X1506965Y1023237D01*
G37*
G36*
G01X1474888Y1029826D02*
X1474572D01*
G03X1474415Y1029749I1J-200D01*
G02X1473230Y1029170I-1185J923D01*
G02Y1032174I0J1502D01*
G02X1474415Y1031595I0J-1502D01*
G03X1474572Y1031518I158J123D01*
G01X1474888D01*
G03X1475045Y1031595I-1J200D01*
G02X1476230Y1032174I1185J-923D01*
G02Y1029170I0J-1502D01*
G02X1475045Y1029749I0J1502D01*
G03X1474888Y1029826I-158J-123D01*
G37*
G36*
G01X1495319Y1103374D02*
X1495313Y1103783D01*
X1495272Y1103864D01*
X1495235Y1103893D01*
G02X1494638Y1105091I905J1199D01*
G02X1497642I1502J0D01*
G02X1497081Y1103920I-1503J0D01*
G01X1497045Y1103891D01*
X1497006Y1103808D01*
X1497012Y1103399D01*
X1497053Y1103318D01*
X1497090Y1103289D01*
G02X1497687Y1102091I-905J-1199D01*
G02X1494683I-1502J0D01*
G02X1495244Y1103262I1503J0D01*
G01X1495280Y1103291D01*
X1495319Y1103374D01*
G37*
G36*
G01Y1115974D02*
X1495313Y1116383D01*
X1495272Y1116464D01*
X1495235Y1116493D01*
G02X1494638Y1117691I905J1199D01*
G02X1497642I1502J0D01*
G02X1497081Y1116520I-1503J0D01*
G01X1497045Y1116491D01*
X1497006Y1116408D01*
X1497012Y1115999D01*
X1497053Y1115918D01*
X1497090Y1115889D01*
G02X1497687Y1114691I-905J-1199D01*
G02X1494683I-1502J0D01*
G02X1495244Y1115862I1503J0D01*
G01X1495280Y1115891D01*
X1495319Y1115974D01*
G37*
G36*
G01X1769063Y921922D02*
X1765663D01*
G02Y925526I0J1802D01*
G01X1769063D01*
G02Y921922I0J-1802D01*
G37*
G36*
G01X1746557Y899314D02*
X1746243D01*
G03X1746085Y899237I0J-200D01*
G02X1744900Y898658I-1185J923D01*
G02Y901662I0J1502D01*
G02X1746085Y901083I0J-1502D01*
G03X1746243Y901006I158J123D01*
G01X1746557D01*
G03X1746715Y901083I0J200D01*
G02X1747900Y901662I1185J-923D01*
G02Y898658I0J-1502D01*
G02X1746715Y899237I0J1502D01*
G03X1746557Y899314I-158J-123D01*
G37*
G36*
G01X1772943Y929006D02*
Y929320D01*
G03X1772866Y929478I-200J0D01*
G02X1772287Y930663I923J1185D01*
G02X1775291I1502J0D01*
G02X1774712Y929478I-1502J0D01*
G03X1774635Y929320I123J-158D01*
G01Y929006D01*
G03X1774712Y928848I200J0D01*
G02X1775291Y927663I-923J-1185D01*
G02X1772287I-1502J0D01*
G02X1772866Y928848I1502J0D01*
G03X1772943Y929006I-123J158D01*
G37*
G36*
G01X1513926Y910754D02*
G02Y907148I0J-1803D01*
G01X1510526D01*
G02Y910754I0J1803D01*
G01X1513926D01*
G37*
G36*
G01X1522031Y899796D02*
G02X1521379Y901034I849J1238D01*
G02X1524383I1502J0D01*
G02X1523789Y899837I-1503J0D01*
G03X1523804Y899189I242J-319D01*
G02X1524456Y897951I-849J-1238D01*
G02X1521452I-1502J0D01*
G02X1522046Y899148I1503J0D01*
G03X1522031Y899796I-242J319D01*
G37*
G36*
G01X1557935Y587658D02*
X1565235D01*
G02Y580256I0J-3701D01*
G01X1557935D01*
G02Y587658I0J3701D01*
G37*
G36*
G01X1574852Y560000D02*
Y560337D01*
X1574827Y560404D01*
X1574803Y560432D01*
G02X1574432Y561420I1130J988D01*
G02X1577436I1502J0D01*
G02X1577065Y560432I-1501J0D01*
G01X1577041Y560404D01*
X1577016Y560337D01*
Y560000D01*
X1577041Y559933D01*
X1577065Y559905D01*
G02X1577436Y558917I-1130J-988D01*
G02X1574432I-1502J0D01*
G02X1574803Y559905I1501J0D01*
G01X1574827Y559933D01*
X1574852Y560000D01*
G37*
G36*
G01X1556628Y560573D02*
G03X1556257Y560944I-399J-28D01*
G02X1554857Y562443I103J1499D01*
G02X1556359Y563945I1502J0D01*
G02X1557858Y562545I0J-1503D01*
G03X1558229Y562174I399J28D01*
G02X1559629Y560675I-103J-1499D01*
G02X1558127Y559173I-1502J0D01*
G02X1556628Y560573I0J1503D01*
G37*
G36*
G01X1542482Y570379D02*
X1542314Y570681D01*
X1542258Y570727D01*
X1542222Y570739D01*
G02X1541202Y572162I483J1423D01*
G02X1544206I1502J0D01*
G02X1544167Y571820I-1502J-2D01*
G01X1544158Y571783D01*
X1544168Y571711D01*
X1544336Y571409D01*
X1544392Y571363D01*
X1544428Y571351D01*
G02X1544508Y571321I-487J-1421D01*
G03X1544664Y571323I76J185D01*
G01X1544779Y571374D01*
G03X1544886Y571487I-80J183D01*
G02X1546293Y572464I1407J-525D01*
G02X1547769Y571243I0J-1503D01*
G01X1547776Y571206D01*
X1547815Y571142D01*
X1548093Y570936D01*
X1548165Y570916D01*
X1548203Y570920D01*
G02X1548359Y570928I155J-1494D01*
G02X1549861Y569426I0J-1502D01*
G02X1549592Y568568I-1503J0D01*
G01X1549571Y568538D01*
X1549553Y568469D01*
X1549592Y568132D01*
X1549624Y568068D01*
X1549652Y568043D01*
G02X1550147Y566929I-1006J-1114D01*
G02X1548645Y565427I-1502J0D01*
G02X1547153Y566759I0J1502D01*
G01X1547147Y566807D01*
X1547097Y566885D01*
X1546741Y567096D01*
X1546648Y567102D01*
X1546604Y567085D01*
G02X1546036Y566973I-569J1390D01*
G02X1544574Y568132I0J1502D01*
G01X1544565Y568169D01*
X1544524Y568229D01*
X1544242Y568425D01*
X1544172Y568443D01*
X1544134Y568438D01*
G02X1543946Y568426I-189J1490D01*
G02X1542444Y569928I0J1502D01*
G02X1542483Y570270I1502J2D01*
G01X1542492Y570307D01*
X1542482Y570379D01*
G37*
G36*
G01X1557169Y572232D02*
G03X1556798Y572603I-399J-28D01*
G02X1555398Y574102I103J1499D01*
G02X1556900Y575604I1502J0D01*
G02X1558399Y574204I0J-1503D01*
G03X1558770Y573833I399J28D01*
G02X1560170Y572334I-103J-1499D01*
G02X1558668Y570832I-1502J0D01*
G02X1557169Y572232I0J1503D01*
G37*
G36*
G01X1573917Y573996D02*
Y574332D01*
X1573892Y574399D01*
X1573868Y574427D01*
G02X1573498Y575414I1131J987D01*
G02X1576502I1502J0D01*
G02X1576132Y574427I-1501J0D01*
G01X1576108Y574399D01*
X1576083Y574332D01*
Y573996D01*
X1576108Y573929D01*
X1576132Y573901D01*
G02Y571927I-1131J-987D01*
G01X1576108Y571899D01*
X1576083Y571832D01*
Y571496D01*
X1576108Y571429D01*
X1576132Y571401D01*
G02Y569427I-1131J-987D01*
G01X1576108Y569399D01*
X1576083Y569332D01*
Y568996D01*
X1576108Y568929D01*
X1576132Y568901D01*
G02Y566927I-1131J-987D01*
G01X1576108Y566899D01*
X1576083Y566832D01*
Y566496D01*
X1576108Y566429D01*
X1576132Y566401D01*
G02X1576502Y565414I-1131J-987D01*
G02X1573498I-1502J0D01*
G02X1573868Y566401I1501J0D01*
G01X1573892Y566429D01*
X1573917Y566496D01*
Y566832D01*
X1573892Y566899D01*
X1573868Y566927D01*
G02Y568901I1131J987D01*
G01X1573892Y568929D01*
X1573917Y568996D01*
Y569332D01*
X1573892Y569399D01*
X1573868Y569427D01*
G02Y571401I1131J987D01*
G01X1573892Y571429D01*
X1573917Y571496D01*
Y571832D01*
X1573892Y571899D01*
X1573868Y571927D01*
G02Y573901I1131J987D01*
G01X1573892Y573929D01*
X1573917Y573996D01*
G37*
G36*
G01X1517321Y599077D02*
X1517624Y599351D01*
X1517658Y599436D01*
X1517655Y599482D01*
G02X1517651Y599588I1498J110D01*
G02X1519153Y598086I1502J0D01*
G02X1518753Y598140I-1J1502D01*
G03X1518565Y598096I-54J-193D01*
G01X1518389Y597937D01*
G02X1518401Y597882I-1461J-348D01*
G01X1518409Y597842D01*
X1518453Y597778D01*
X1518754Y597577D01*
X1518830Y597562D01*
X1518869Y597569D01*
G02X1519156Y597597I289J-1474D01*
G02Y594593I0J-1502D01*
G02X1518814Y594632I-2J1502D01*
G01X1518775Y594642D01*
X1518697Y594629D01*
X1518388Y594436D01*
X1518342Y594371D01*
X1518333Y594332D01*
G02X1518329Y594315I-1464J336D01*
G01X1518319Y594275D01*
X1518333Y594195D01*
X1518534Y593882D01*
X1518600Y593836D01*
X1518641Y593828D01*
G02X1519856Y592354I-287J-1474D01*
G02X1519395Y591271I-1503J0D01*
G01X1519364Y591242D01*
X1519333Y591166D01*
X1519341Y590786D01*
X1519376Y590711D01*
X1519408Y590683D01*
G02X1519917Y589556I-993J-1127D01*
G02X1516913I-1502J0D01*
G02X1517374Y590639I1503J0D01*
G01X1517405Y590668D01*
X1517436Y590744D01*
X1517428Y591124D01*
X1517393Y591199D01*
X1517361Y591227D01*
G02X1516852Y592354I993J1127D01*
G02X1516894Y592707I1502J0D01*
G01X1516904Y592747D01*
X1516890Y592827D01*
X1516689Y593140D01*
X1516623Y593186D01*
X1516582Y593194D01*
G02X1515367Y594668I287J1474D01*
G02X1515927Y595838I1502J0D01*
G01X1515962Y595866D01*
X1516001Y595944D01*
X1516009Y596341D01*
X1515974Y596421D01*
X1515940Y596450D01*
G02X1515428Y597580I991J1130D01*
G02X1516930Y599082I1502J0D01*
G02X1517187Y599060I1J-1502D01*
G01X1517233Y599052D01*
X1517321Y599077D01*
G37*
G36*
G01X1578832Y611475D02*
X1578776Y611471D01*
G02X1578679Y611468I-97J1576D01*
G02X1580258Y613047I0J1579D01*
G02X1580004Y612190I-1578J2D01*
G01X1579974Y612142D01*
X1579971Y612031D01*
X1580203Y611624D01*
X1580300Y611570D01*
X1580357Y611573D01*
G02X1580418Y611574I55J-1501D01*
G02Y608570I0J-1502D01*
G02X1580072Y608610I-2J1502D01*
G01X1580018Y608623D01*
X1579914Y608591D01*
X1579605Y608247D01*
X1579584Y608141D01*
X1579603Y608088D01*
G02X1579692Y607563I-1489J-523D01*
G02X1579398Y606644I-1578J-2D01*
G01X1579369Y606604D01*
X1579355Y606506D01*
X1579504Y606102D01*
X1579577Y606036D01*
X1579626Y606024D01*
G02X1580762Y604567I-366J-1457D01*
G02X1577758I-1502J0D01*
G02X1578015Y605408I1502J1D01*
G01X1578043Y605449D01*
X1578054Y605548D01*
X1577895Y605947D01*
X1577820Y606011D01*
X1577771Y606022D01*
G02X1576879Y606580I343J1541D01*
G01X1576844Y606624D01*
X1576741Y606662D01*
X1576286Y606581D01*
X1576203Y606509D01*
X1576186Y606457D01*
G02X1574760Y605427I-1426J472D01*
G02Y608431I0J1502D01*
G02X1575915Y607889I0J-1502D01*
G01X1575951Y607846D01*
X1576054Y607810D01*
X1576507Y607900D01*
X1576589Y607974D01*
X1576605Y608027D01*
G02X1578114Y609142I1509J-464D01*
G02X1578511Y609091I-1J-1579D01*
G01X1578565Y609077D01*
X1578669Y609107D01*
X1578985Y609444D01*
X1579009Y609550D01*
X1578991Y609603D01*
G02X1578916Y610072I1427J469D01*
G02X1579140Y610862I1502J1D01*
G01X1579170Y610910D01*
X1579171Y611021D01*
X1578931Y611423D01*
X1578832Y611475D01*
G37*
G36*
G01X1575581Y631571D02*
X1575577Y631626D01*
G02X1575575Y631712I1500J78D01*
G02X1577077Y630210I1502J0D01*
G02X1576380Y630382I1J1502D01*
G01X1576331Y630407D01*
X1576223Y630402D01*
X1575839Y630148D01*
X1575791Y630051D01*
X1575796Y629996D01*
G02X1575800Y629871I-1574J-113D01*
G02X1575772Y629573I-1578J-2D01*
G01X1575763Y629526D01*
X1575787Y629438D01*
X1576061Y629130D01*
X1576145Y629095D01*
X1576193Y629098D01*
G02X1576297Y629102I110J-1498D01*
G02X1574795Y627600I0J-1502D01*
G02X1574814Y627839I1502J1D01*
G01X1574822Y627886D01*
X1574795Y627973D01*
X1574512Y628273D01*
X1574427Y628305D01*
X1574379Y628300D01*
G02X1574222Y628292I-159J1571D01*
G02Y631450I0J1579D01*
G02X1574985Y631253I-1J-1579D01*
G01X1575033Y631226D01*
X1575141Y631229D01*
X1575531Y631475D01*
X1575581Y631571D01*
G37*
G36*
G01X1794460Y1075632D02*
X1794812D01*
X1794881Y1075660D01*
X1794909Y1075686D01*
G02X1796963I1027J-1096D01*
G01X1796991Y1075660D01*
X1797060Y1075632D01*
X1797412D01*
X1797481Y1075660D01*
X1797509Y1075686D01*
G02X1798536Y1076092I1027J-1096D01*
G02X1800038Y1074590I0J-1502D01*
G02X1799668Y1073603I-1501J0D01*
G01X1799644Y1073575D01*
X1799619Y1073508D01*
Y1073172D01*
X1799644Y1073105D01*
X1799668Y1073077D01*
G02X1800038Y1072090I-1131J-987D01*
G02X1798536Y1070588I-1502J0D01*
G02X1797509Y1070994I0J1502D01*
G01X1797481Y1071020D01*
X1797412Y1071048D01*
X1797060D01*
X1796991Y1071020D01*
X1796963Y1070994D01*
G02X1794909I-1027J1096D01*
G01X1794881Y1071020D01*
X1794812Y1071048D01*
X1794460D01*
X1794391Y1071020D01*
X1794363Y1070994D01*
G02X1792309I-1027J1096D01*
G01X1792281Y1071020D01*
X1792212Y1071048D01*
X1791860D01*
X1791791Y1071020D01*
X1791763Y1070994D01*
G02X1790736Y1070588I-1027J1096D01*
G02X1789234Y1072090I0J1502D01*
G02X1789604Y1073077I1501J0D01*
G01X1789628Y1073105D01*
X1789653Y1073172D01*
Y1073508D01*
X1789628Y1073575D01*
X1789604Y1073603D01*
G02X1789234Y1074590I1131J987D01*
G02X1790736Y1076092I1502J0D01*
G02X1791763Y1075686I0J-1502D01*
G01X1791791Y1075660D01*
X1791860Y1075632D01*
X1792212D01*
X1792281Y1075660D01*
X1792309Y1075686D01*
G02X1794363I1027J-1096D01*
G01X1794391Y1075660D01*
X1794460Y1075632D01*
G37*
G36*
G01X1779722Y1075749D02*
X1780074D01*
X1780143Y1075777D01*
X1780171Y1075803D01*
G02X1782225I1027J-1096D01*
G01X1782253Y1075777D01*
X1782322Y1075749D01*
X1782674D01*
X1782743Y1075777D01*
X1782771Y1075803D01*
G02X1783798Y1076209I1027J-1096D01*
G02X1785300Y1074707I0J-1502D01*
G02X1784930Y1073720I-1501J0D01*
G01X1784906Y1073692D01*
X1784881Y1073625D01*
Y1073289D01*
X1784906Y1073222D01*
X1784930Y1073194D01*
G02X1785300Y1072207I-1131J-987D01*
G02X1783798Y1070705I-1502J0D01*
G02X1782771Y1071111I0J1502D01*
G01X1782743Y1071137D01*
X1782674Y1071165D01*
X1782322D01*
X1782253Y1071137D01*
X1782225Y1071111D01*
G02X1780171I-1027J1096D01*
G01X1780143Y1071137D01*
X1780074Y1071165D01*
X1779722D01*
X1779653Y1071137D01*
X1779625Y1071111D01*
G02X1777571I-1027J1096D01*
G01X1777543Y1071137D01*
X1777474Y1071165D01*
X1777122D01*
X1777053Y1071137D01*
X1777025Y1071111D01*
G02X1775998Y1070705I-1027J1096D01*
G02X1774496Y1072207I0J1502D01*
G02X1774866Y1073194I1501J0D01*
G01X1774890Y1073222D01*
X1774915Y1073289D01*
Y1073625D01*
X1774890Y1073692D01*
X1774866Y1073720D01*
G02X1774496Y1074707I1131J987D01*
G02X1775998Y1076209I1502J0D01*
G02X1777025Y1075803I0J-1502D01*
G01X1777053Y1075777D01*
X1777122Y1075749D01*
X1777474D01*
X1777543Y1075777D01*
X1777571Y1075803D01*
G02X1779625I1027J-1096D01*
G01X1779653Y1075777D01*
X1779722Y1075749D01*
G37*
G36*
G01X1789555Y1083668D02*
X1789546Y1084014D01*
X1789517Y1084082D01*
X1789491Y1084109D01*
G02X1789070Y1085152I1081J1043D01*
G02X1792074I1502J0D01*
G02X1791706Y1084167I-1502J0D01*
G01X1791681Y1084139D01*
X1791656Y1084069D01*
X1791665Y1083723D01*
X1791694Y1083655D01*
X1791720Y1083628D01*
G02X1792141Y1082585I-1081J-1043D01*
G02X1789137I-1502J0D01*
G02X1789505Y1083570I1502J0D01*
G01X1789530Y1083598D01*
X1789555Y1083668D01*
G37*
G36*
G01X1778850Y1093393D02*
X1779202D01*
X1779271Y1093421D01*
X1779299Y1093447D01*
G02X1781353I1027J-1096D01*
G01X1781381Y1093421D01*
X1781450Y1093393D01*
X1781802D01*
X1781871Y1093421D01*
X1781899Y1093447D01*
G02X1782926Y1093853I1027J-1096D01*
G02X1784428Y1092351I0J-1502D01*
G02X1784058Y1091364I-1501J0D01*
G01X1784034Y1091336D01*
X1784009Y1091269D01*
Y1090933D01*
X1784034Y1090866D01*
X1784058Y1090838D01*
G02X1784428Y1089851I-1131J-987D01*
G02X1782926Y1088349I-1502J0D01*
G02X1781899Y1088755I0J1502D01*
G01X1781871Y1088781D01*
X1781802Y1088809D01*
X1781450D01*
X1781381Y1088781D01*
X1781353Y1088755D01*
G02X1779299I-1027J1096D01*
G01X1779271Y1088781D01*
X1779202Y1088809D01*
X1778850D01*
X1778781Y1088781D01*
X1778753Y1088755D01*
G02X1776699I-1027J1096D01*
G01X1776671Y1088781D01*
X1776602Y1088809D01*
X1776250D01*
X1776181Y1088781D01*
X1776153Y1088755D01*
G02X1775126Y1088349I-1027J1096D01*
G02X1773624Y1089851I0J1502D01*
G02X1773994Y1090838I1501J0D01*
G01X1774018Y1090866D01*
X1774043Y1090933D01*
Y1091269D01*
X1774018Y1091336D01*
X1773994Y1091364D01*
G02X1773624Y1092351I1131J987D01*
G02X1775126Y1093853I1502J0D01*
G02X1776153Y1093447I0J-1502D01*
G01X1776181Y1093421D01*
X1776250Y1093393D01*
X1776602D01*
X1776671Y1093421D01*
X1776699Y1093447D01*
G02X1778753I1027J-1096D01*
G01X1778781Y1093421D01*
X1778850Y1093393D01*
G37*
G36*
G01X1815910Y1095487D02*
Y1095803D01*
G03X1815833Y1095960I-200J-1D01*
G02X1815254Y1097145I923J1185D01*
G02X1818258I1502J0D01*
G02X1817679Y1095960I-1502J0D01*
G03X1817602Y1095803I123J-158D01*
G01Y1095487D01*
G03X1817679Y1095330I200J1D01*
G02X1818258Y1094145I-923J-1185D01*
G02X1815254I-1502J0D01*
G02X1815833Y1095330I1502J0D01*
G03X1815910Y1095487I-123J158D01*
G37*
G36*
G01X1779090Y1112080D02*
X1779442D01*
X1779511Y1112108D01*
X1779539Y1112134D01*
G02X1781593I1027J-1096D01*
G01X1781621Y1112108D01*
X1781690Y1112080D01*
X1782042D01*
X1782111Y1112108D01*
X1782139Y1112134D01*
G02X1783166Y1112540I1027J-1096D01*
G02X1784668Y1111038I0J-1502D01*
G02X1784290Y1110041I-1502J-1D01*
G01X1784264Y1110012D01*
X1784238Y1109940D01*
X1784251Y1109586D01*
X1784282Y1109516D01*
X1784310Y1109489D01*
G02X1784764Y1108413I-1048J-1076D01*
G02X1783262Y1106911I-1502J0D01*
G02X1782235Y1107317I0J1502D01*
G01X1782207Y1107343D01*
X1782138Y1107371D01*
X1781786D01*
X1781717Y1107343D01*
X1781689Y1107317D01*
G02X1779635I-1027J1096D01*
G01X1779607Y1107343D01*
X1779538Y1107371D01*
X1779186D01*
X1779117Y1107343D01*
X1779089Y1107317D01*
G02X1777035I-1027J1096D01*
G01X1777007Y1107343D01*
X1776938Y1107371D01*
X1776586D01*
X1776517Y1107343D01*
X1776489Y1107317D01*
G02X1775462Y1106911I-1027J1096D01*
G02X1773960Y1108413I0J1502D01*
G02X1774338Y1109410I1502J1D01*
G01X1774364Y1109439D01*
X1774390Y1109511D01*
X1774377Y1109865D01*
X1774346Y1109935D01*
X1774318Y1109962D01*
G02X1773864Y1111038I1048J1076D01*
G02X1775366Y1112540I1502J0D01*
G02X1776393Y1112134I0J-1502D01*
G01X1776421Y1112108D01*
X1776490Y1112080D01*
X1776842D01*
X1776911Y1112108D01*
X1776939Y1112134D01*
G02X1778993I1027J-1096D01*
G01X1779021Y1112108D01*
X1779090Y1112080D01*
G37*
G36*
G01X1802030Y1115631D02*
X1802382D01*
X1802451Y1115659D01*
X1802479Y1115685D01*
G02X1803506Y1116091I1027J-1096D01*
G02X1804572Y1115647I0J-1502D01*
G01X1804600Y1115618D01*
X1804674Y1115588D01*
X1805038D01*
X1805112Y1115618D01*
X1805140Y1115647D01*
G02X1806206Y1116091I1066J-1058D01*
G02Y1113087I0J-1502D01*
G02X1805140Y1113531I0J1502D01*
G01X1805112Y1113560D01*
X1805038Y1113590D01*
X1804674D01*
X1804600Y1113560D01*
X1804572Y1113531D01*
G02X1803506Y1113087I-1066J1058D01*
G02X1802479Y1113493I0J1502D01*
G01X1802451Y1113519D01*
X1802382Y1113547D01*
X1802030D01*
X1801961Y1113519D01*
X1801933Y1113493D01*
G02X1799879I-1027J1096D01*
G01X1799851Y1113519D01*
X1799782Y1113547D01*
X1799430D01*
X1799361Y1113519D01*
X1799333Y1113493D01*
G02X1798306Y1113087I-1027J1096D01*
G02Y1116091I0J1502D01*
G02X1799333Y1115685I0J-1502D01*
G01X1799361Y1115659D01*
X1799430Y1115631D01*
X1799782D01*
X1799851Y1115659D01*
X1799879Y1115685D01*
G02X1801933I1027J-1096D01*
G01X1801961Y1115659D01*
X1802030Y1115631D01*
G37*
G36*
G01X1818752D02*
X1819104D01*
X1819173Y1115659D01*
X1819201Y1115685D01*
G02X1820228Y1116091I1027J-1096D01*
G02X1821294Y1115647I0J-1502D01*
G01X1821322Y1115618D01*
X1821396Y1115588D01*
X1821760D01*
X1821834Y1115618D01*
X1821862Y1115647D01*
G02X1822928Y1116091I1066J-1058D01*
G02Y1113087I0J-1502D01*
G02X1821862Y1113531I0J1502D01*
G01X1821834Y1113560D01*
X1821760Y1113590D01*
X1821396D01*
X1821322Y1113560D01*
X1821294Y1113531D01*
G02X1820228Y1113087I-1066J1058D01*
G02X1819201Y1113493I0J1502D01*
G01X1819173Y1113519D01*
X1819104Y1113547D01*
X1818752D01*
X1818683Y1113519D01*
X1818655Y1113493D01*
G02X1816601I-1027J1096D01*
G01X1816573Y1113519D01*
X1816504Y1113547D01*
X1816152D01*
X1816083Y1113519D01*
X1816055Y1113493D01*
G02X1815028Y1113087I-1027J1096D01*
G02Y1116091I0J1502D01*
G02X1816055Y1115685I0J-1502D01*
G01X1816083Y1115659D01*
X1816152Y1115631D01*
X1816504D01*
X1816573Y1115659D01*
X1816601Y1115685D01*
G02X1818655I1027J-1096D01*
G01X1818683Y1115659D01*
X1818752Y1115631D01*
G37*
G36*
G01X1741726Y1117768D02*
X1741880Y1118145D01*
X1741874Y1118236D01*
X1741851Y1118276D01*
G02X1741646Y1119055I1373J778D01*
G02X1744802I1578J0D01*
G02X1744608Y1118296I-1578J-1D01*
G01X1744585Y1118255D01*
X1744582Y1118161D01*
X1744750Y1117784D01*
X1744822Y1117725D01*
X1744868Y1117714D01*
G02X1746031Y1116251I-339J-1463D01*
G02X1744529Y1114749I-1502J0D01*
G02X1743542Y1115119I0J1501D01*
G01X1743514Y1115143D01*
X1743447Y1115168D01*
X1743111D01*
X1743044Y1115143D01*
X1743016Y1115119D01*
G02X1742029Y1114749I-987J1131D01*
G02X1740527Y1116251I0J1502D01*
G02X1741614Y1117694I1501J0D01*
G01X1741658Y1117707D01*
X1741726Y1117768D01*
G37*
G36*
G01X1770623Y1122164D02*
X1770975D01*
X1771044Y1122192D01*
X1771072Y1122218D01*
G02X1772099Y1122624I1027J-1096D01*
G02X1773165Y1122180I0J-1502D01*
G01X1773193Y1122151D01*
X1773267Y1122121D01*
X1773631D01*
X1773705Y1122151D01*
X1773733Y1122180D01*
G02X1774799Y1122624I1066J-1058D01*
G02Y1119620I0J-1502D01*
G02X1773733Y1120064I0J1502D01*
G01X1773705Y1120093D01*
X1773631Y1120123D01*
X1773267D01*
X1773193Y1120093D01*
X1773165Y1120064D01*
G02X1772099Y1119620I-1066J1058D01*
G02X1771072Y1120026I0J1502D01*
G01X1771044Y1120052D01*
X1770975Y1120080D01*
X1770623D01*
X1770554Y1120052D01*
X1770526Y1120026D01*
G02X1768472I-1027J1096D01*
G01X1768444Y1120052D01*
X1768375Y1120080D01*
X1768023D01*
X1767954Y1120052D01*
X1767926Y1120026D01*
G02X1766899Y1119620I-1027J1096D01*
G02Y1122624I0J1502D01*
G02X1767926Y1122218I0J-1502D01*
G01X1767954Y1122192D01*
X1768023Y1122164D01*
X1768375D01*
X1768444Y1122192D01*
X1768472Y1122218D01*
G02X1770526I1027J-1096D01*
G01X1770554Y1122192D01*
X1770623Y1122164D01*
G37*
G36*
G01X1789045D02*
X1789397D01*
X1789466Y1122192D01*
X1789494Y1122218D01*
G02X1790521Y1122624I1027J-1096D01*
G02X1791587Y1122180I0J-1502D01*
G01X1791615Y1122151D01*
X1791689Y1122121D01*
X1792053D01*
X1792127Y1122151D01*
X1792155Y1122180D01*
G02X1793221Y1122624I1066J-1058D01*
G02Y1119620I0J-1502D01*
G02X1792155Y1120064I0J1502D01*
G01X1792127Y1120093D01*
X1792053Y1120123D01*
X1791689D01*
X1791615Y1120093D01*
X1791587Y1120064D01*
G02X1790521Y1119620I-1066J1058D01*
G02X1789494Y1120026I0J1502D01*
G01X1789466Y1120052D01*
X1789397Y1120080D01*
X1789045D01*
X1788976Y1120052D01*
X1788948Y1120026D01*
G02X1786894I-1027J1096D01*
G01X1786866Y1120052D01*
X1786797Y1120080D01*
X1786445D01*
X1786376Y1120052D01*
X1786348Y1120026D01*
G02X1785321Y1119620I-1027J1096D01*
G02Y1122624I0J1502D01*
G02X1786348Y1122218I0J-1502D01*
G01X1786376Y1122192D01*
X1786445Y1122164D01*
X1786797D01*
X1786866Y1122192D01*
X1786894Y1122218D01*
G02X1788948I1027J-1096D01*
G01X1788976Y1122192D01*
X1789045Y1122164D01*
G37*
G36*
G01X1818852Y1125331D02*
X1819204D01*
X1819273Y1125359D01*
X1819301Y1125385D01*
G02X1820328Y1125791I1027J-1096D01*
G02X1821394Y1125347I0J-1502D01*
G01X1821422Y1125318D01*
X1821496Y1125288D01*
X1821860D01*
X1821934Y1125318D01*
X1821962Y1125347D01*
G02X1823028Y1125791I1066J-1058D01*
G02Y1122787I0J-1502D01*
G02X1821962Y1123231I0J1502D01*
G01X1821934Y1123260D01*
X1821860Y1123290D01*
X1821496D01*
X1821422Y1123260D01*
X1821394Y1123231D01*
G02X1820328Y1122787I-1066J1058D01*
G02X1819301Y1123193I0J1502D01*
G01X1819273Y1123219D01*
X1819204Y1123247D01*
X1818852D01*
X1818783Y1123219D01*
X1818755Y1123193D01*
G02X1816701I-1027J1096D01*
G01X1816673Y1123219D01*
X1816604Y1123247D01*
X1816252D01*
X1816183Y1123219D01*
X1816155Y1123193D01*
G02X1815128Y1122787I-1027J1096D01*
G02Y1125791I0J1502D01*
G02X1816155Y1125385I0J-1502D01*
G01X1816183Y1125359D01*
X1816252Y1125331D01*
X1816604D01*
X1816673Y1125359D01*
X1816701Y1125385D01*
G02X1818755I1027J-1096D01*
G01X1818783Y1125359D01*
X1818852Y1125331D01*
G37*
G36*
G01X1802426Y1125370D02*
X1802778D01*
X1802847Y1125398D01*
X1802875Y1125424D01*
G02X1803902Y1125830I1027J-1096D01*
G02X1804968Y1125386I0J-1502D01*
G01X1804996Y1125357D01*
X1805070Y1125327D01*
X1805434D01*
X1805508Y1125357D01*
X1805536Y1125386D01*
G02X1806602Y1125830I1066J-1058D01*
G02Y1122826I0J-1502D01*
G02X1805536Y1123270I0J1502D01*
G01X1805508Y1123299D01*
X1805434Y1123329D01*
X1805070D01*
X1804996Y1123299D01*
X1804968Y1123270D01*
G02X1803902Y1122826I-1066J1058D01*
G02X1802875Y1123232I0J1502D01*
G01X1802847Y1123258D01*
X1802778Y1123286D01*
X1802426D01*
X1802357Y1123258D01*
X1802329Y1123232D01*
G02X1800275I-1027J1096D01*
G01X1800247Y1123258D01*
X1800178Y1123286D01*
X1799826D01*
X1799757Y1123258D01*
X1799729Y1123232D01*
G02X1798702Y1122826I-1027J1096D01*
G02Y1125830I0J1502D01*
G02X1799729Y1125424I0J-1502D01*
G01X1799757Y1125398D01*
X1799826Y1125370D01*
X1800178D01*
X1800247Y1125398D01*
X1800275Y1125424D01*
G02X1802329I1027J-1096D01*
G01X1802357Y1125398D01*
X1802426Y1125370D01*
G37*
G36*
G01X1770723Y1131864D02*
X1771075D01*
X1771144Y1131892D01*
X1771172Y1131918D01*
G02X1772199Y1132324I1027J-1096D01*
G02X1773265Y1131880I0J-1502D01*
G01X1773293Y1131851D01*
X1773367Y1131821D01*
X1773731D01*
X1773805Y1131851D01*
X1773833Y1131880D01*
G02X1774899Y1132324I1066J-1058D01*
G02Y1129320I0J-1502D01*
G02X1773833Y1129764I0J1502D01*
G01X1773805Y1129793D01*
X1773731Y1129823D01*
X1773367D01*
X1773293Y1129793D01*
X1773265Y1129764D01*
G02X1772199Y1129320I-1066J1058D01*
G02X1771172Y1129726I0J1502D01*
G01X1771144Y1129752D01*
X1771075Y1129780D01*
X1770723D01*
X1770654Y1129752D01*
X1770626Y1129726D01*
G02X1768572I-1027J1096D01*
G01X1768544Y1129752D01*
X1768475Y1129780D01*
X1768123D01*
X1768054Y1129752D01*
X1768026Y1129726D01*
G02X1766999Y1129320I-1027J1096D01*
G02Y1132324I0J1502D01*
G02X1768026Y1131918I0J-1502D01*
G01X1768054Y1131892D01*
X1768123Y1131864D01*
X1768475D01*
X1768544Y1131892D01*
X1768572Y1131918D01*
G02X1770626I1027J-1096D01*
G01X1770654Y1131892D01*
X1770723Y1131864D01*
G37*
G36*
G01X1789045D02*
X1789397D01*
X1789466Y1131892D01*
X1789494Y1131918D01*
G02X1790521Y1132324I1027J-1096D01*
G02X1791587Y1131880I0J-1502D01*
G01X1791615Y1131851D01*
X1791689Y1131821D01*
X1792053D01*
X1792127Y1131851D01*
X1792155Y1131880D01*
G02X1793221Y1132324I1066J-1058D01*
G02Y1129320I0J-1502D01*
G02X1792155Y1129764I0J1502D01*
G01X1792127Y1129793D01*
X1792053Y1129823D01*
X1791689D01*
X1791615Y1129793D01*
X1791587Y1129764D01*
G02X1790521Y1129320I-1066J1058D01*
G02X1789494Y1129726I0J1502D01*
G01X1789466Y1129752D01*
X1789397Y1129780D01*
X1789045D01*
X1788976Y1129752D01*
X1788948Y1129726D01*
G02X1786894I-1027J1096D01*
G01X1786866Y1129752D01*
X1786797Y1129780D01*
X1786445D01*
X1786376Y1129752D01*
X1786348Y1129726D01*
G02X1785321Y1129320I-1027J1096D01*
G02Y1132324I0J1502D01*
G02X1786348Y1131918I0J-1502D01*
G01X1786376Y1131892D01*
X1786445Y1131864D01*
X1786797D01*
X1786866Y1131892D01*
X1786894Y1131918D01*
G02X1788948I1027J-1096D01*
G01X1788976Y1131892D01*
X1789045Y1131864D01*
G37*
G36*
G01X1806064Y1132357D02*
X1805700D01*
X1805626Y1132327D01*
X1805598Y1132298D01*
G02X1804532Y1131854I-1066J1058D01*
G02Y1134858I0J1502D01*
G02X1805598Y1134414I0J-1502D01*
G01X1805626Y1134385D01*
X1805700Y1134355D01*
X1806064D01*
X1806138Y1134385D01*
X1806166Y1134414D01*
G02X1807232Y1134858I1066J-1058D01*
G02Y1131854I0J-1502D01*
G02X1806166Y1132298I0J1502D01*
G01X1806138Y1132327D01*
X1806064Y1132357D01*
G37*
G36*
G01X1808453Y1135829D02*
X1808117D01*
X1808050Y1135804D01*
X1808022Y1135780D01*
G02X1807035Y1135410I-987J1131D01*
G02Y1138414I0J1502D01*
G02X1808022Y1138044I0J-1501D01*
G01X1808050Y1138020D01*
X1808117Y1137995D01*
X1808453D01*
X1808520Y1138020D01*
X1808548Y1138044D01*
G02X1809535Y1138414I987J-1131D01*
G02Y1135410I0J-1502D01*
G02X1808548Y1135780I0J1501D01*
G01X1808520Y1135804D01*
X1808453Y1135829D01*
G37*
G36*
G01X1815303D02*
X1814967D01*
X1814900Y1135804D01*
X1814872Y1135780D01*
G02X1813885Y1135410I-987J1131D01*
G02Y1138414I0J1502D01*
G02X1814872Y1138044I0J-1501D01*
G01X1814900Y1138020D01*
X1814967Y1137995D01*
X1815303D01*
X1815370Y1138020D01*
X1815398Y1138044D01*
G02X1816385Y1138414I987J-1131D01*
G02Y1135410I0J-1502D01*
G02X1815398Y1135780I0J1501D01*
G01X1815370Y1135804D01*
X1815303Y1135829D01*
G37*
G36*
G01X1776317Y1138739D02*
X1775981D01*
X1775914Y1138714D01*
X1775886Y1138690D01*
G02X1774899Y1138320I-987J1131D01*
G02Y1141324I0J1502D01*
G02X1775886Y1140954I0J-1501D01*
G01X1775914Y1140930D01*
X1775981Y1140905D01*
X1776317D01*
X1776384Y1140930D01*
X1776412Y1140954D01*
G02X1777399Y1141324I987J-1131D01*
G02Y1138320I0J-1502D01*
G02X1776412Y1138690I0J1501D01*
G01X1776384Y1138714D01*
X1776317Y1138739D01*
G37*
G36*
G01X1783292D02*
X1782956D01*
X1782889Y1138714D01*
X1782861Y1138690D01*
G02X1781874Y1138320I-987J1131D01*
G02Y1141324I0J1502D01*
G02X1782861Y1140954I0J-1501D01*
G01X1782889Y1140930D01*
X1782956Y1140905D01*
X1783292D01*
X1783359Y1140930D01*
X1783387Y1140954D01*
G02X1784374Y1141324I987J-1131D01*
G02Y1138320I0J-1502D01*
G02X1783387Y1138690I0J1501D01*
G01X1783359Y1138714D01*
X1783292Y1138739D01*
G37*
G36*
G01X1808453Y1143829D02*
X1808117D01*
X1808050Y1143804D01*
X1808022Y1143780D01*
G02X1807035Y1143410I-987J1131D01*
G02Y1146414I0J1502D01*
G02X1808022Y1146044I0J-1501D01*
G01X1808050Y1146020D01*
X1808117Y1145995D01*
X1808453D01*
X1808520Y1146020D01*
X1808548Y1146044D01*
G02X1809535Y1146414I987J-1131D01*
G02Y1143410I0J-1502D01*
G02X1808548Y1143780I0J1501D01*
G01X1808520Y1143804D01*
X1808453Y1143829D01*
G37*
G36*
G01X1815303D02*
X1814967D01*
X1814900Y1143804D01*
X1814872Y1143780D01*
G02X1813885Y1143410I-987J1131D01*
G02Y1146414I0J1502D01*
G02X1814872Y1146044I0J-1501D01*
G01X1814900Y1146020D01*
X1814967Y1145995D01*
X1815303D01*
X1815370Y1146020D01*
X1815398Y1146044D01*
G02X1816385Y1146414I987J-1131D01*
G02Y1143410I0J-1502D01*
G02X1815398Y1143780I0J1501D01*
G01X1815370Y1143804D01*
X1815303Y1143829D01*
G37*
G36*
G01X1776317Y1146739D02*
X1775981D01*
X1775914Y1146714D01*
X1775886Y1146690D01*
G02X1774899Y1146320I-987J1131D01*
G02Y1149324I0J1502D01*
G02X1775886Y1148954I0J-1501D01*
G01X1775914Y1148930D01*
X1775981Y1148905D01*
X1776317D01*
X1776384Y1148930D01*
X1776412Y1148954D01*
G02X1777399Y1149324I987J-1131D01*
G02Y1146320I0J-1502D01*
G02X1776412Y1146690I0J1501D01*
G01X1776384Y1146714D01*
X1776317Y1146739D01*
G37*
G36*
G01X1783220D02*
X1782884D01*
X1782817Y1146714D01*
X1782789Y1146690D01*
G02X1781802Y1146320I-987J1131D01*
G02Y1149324I0J1502D01*
G02X1782789Y1148954I0J-1501D01*
G01X1782817Y1148930D01*
X1782884Y1148905D01*
X1783220D01*
X1783287Y1148930D01*
X1783315Y1148954D01*
G02X1784302Y1149324I987J-1131D01*
G02Y1146320I0J-1502D01*
G02X1783315Y1146690I0J1501D01*
G01X1783287Y1146714D01*
X1783220Y1146739D01*
G37*
G36*
G01X1711219Y1195283D02*
X1711322Y1195656D01*
X1711309Y1195741D01*
X1711285Y1195777D01*
G02X1711040Y1196600I1257J822D01*
G02X1714044I1502J0D01*
G02X1713199Y1195249I-1503J0D01*
G01X1713160Y1195230D01*
X1713106Y1195165D01*
X1713003Y1194792D01*
X1713016Y1194707D01*
X1713040Y1194671D01*
G02X1713285Y1193848I-1257J-822D01*
G02X1710281I-1502J0D01*
G02X1711126Y1195199I1503J0D01*
G01X1711165Y1195218D01*
X1711219Y1195283D01*
G37*
G36*
G01X1588099Y1114197D02*
X1588090Y1114246D01*
G02X1588069Y1114468I1181J224D01*
G02X1589271Y1113266I1202J0D01*
G02X1589049Y1113287I2J1202D01*
G01X1589000Y1113296D01*
X1588907Y1113267D01*
X1588602Y1112962D01*
X1588573Y1112869D01*
X1588582Y1112820D01*
G02X1588603Y1112598I-1181J-224D01*
G02X1586199I-1202J0D01*
G02X1586220Y1112820I1202J-2D01*
G01X1586229Y1112869D01*
X1586200Y1112962D01*
X1585895Y1113267D01*
X1585802Y1113296D01*
X1585753Y1113287D01*
G02X1585531Y1113266I-224J1181D01*
G02X1586733Y1114468I0J1202D01*
G02X1586712Y1114246I-1202J2D01*
G01X1586703Y1114197D01*
X1586732Y1114104D01*
X1587037Y1113799D01*
X1587130Y1113770D01*
X1587179Y1113779D01*
G02X1587401Y1113800I224J-1181D01*
G02X1587623Y1113779I-2J-1202D01*
G01X1587672Y1113770D01*
X1587765Y1113799D01*
X1588070Y1114104D01*
X1588099Y1114197D01*
G37*
G36*
G01X1718961Y1134041D02*
G02X1717626Y1133227I-1335J688D01*
G02Y1136231I0J1502D01*
G02X1718961Y1135417I0J-1502D01*
G03X1719673I356J183D01*
G02X1721008Y1136231I1335J-688D01*
G02Y1133227I0J-1502D01*
G02X1719673Y1134041I0J1502D01*
G03X1718961I-356J-183D01*
G37*
G36*
G01X1731427Y1134347D02*
X1731416Y1134397D01*
G02X1731379Y1134729I1465J331D01*
G02X1732881Y1133227I1502J0D01*
G02X1732653Y1133244I-3J1502D01*
G01X1732603Y1133252D01*
X1732509Y1133219D01*
X1732217Y1132897D01*
X1732192Y1132799D01*
X1732205Y1132750D01*
G02X1732254Y1132361I-1520J-389D01*
G02X1729096I-1579J0D01*
G02X1729144Y1132746I1579J-1D01*
G01X1729155Y1132788D01*
X1729140Y1132871D01*
X1728924Y1133190D01*
X1728852Y1133234D01*
X1728809Y1133240D01*
G02X1728620Y1133278I201J1489D01*
G03X1728388Y1132999I-52J-193D01*
G02X1728542Y1132319I-1424J-680D01*
G02X1725384I-1579J0D01*
G02X1725420Y1132650I1579J-4D01*
G01X1725429Y1132695D01*
X1725408Y1132783D01*
X1725152Y1133096D01*
X1725070Y1133135D01*
X1725024Y1133134D01*
X1725008D01*
G02X1726510Y1134636I0J1502D01*
G02X1726486Y1134367I-1502J-2D01*
G01X1726478Y1134322D01*
X1726501Y1134235D01*
X1726767Y1133930D01*
X1726850Y1133894D01*
X1726896Y1133896D01*
G02X1726963Y1133898I81J-1577D01*
G02X1727118Y1133890I-4J-1579D01*
G01X1727167Y1133885D01*
X1727257Y1133920D01*
X1727535Y1134240D01*
X1727558Y1134333D01*
X1727547Y1134381D01*
G02X1727506Y1134729I1461J349D01*
G02X1730510I1502J0D01*
G02X1730477Y1134414I-1502J-2D01*
G01X1730467Y1134371D01*
X1730485Y1134289D01*
X1730712Y1133978D01*
X1730785Y1133936D01*
X1730829Y1133932D01*
G02X1730955Y1133914I-160J-1570D01*
G01X1731005Y1133905D01*
X1731100Y1133937D01*
X1731401Y1134251D01*
X1731427Y1134347D01*
G37*
G36*
G01X1670383Y1136638D02*
X1670374Y1136687D01*
G02X1670353Y1136909I1181J224D01*
G02X1672757I1202J0D01*
G02X1672747Y1136754I-1202J0D01*
G01X1672741Y1136707D01*
X1672772Y1136618D01*
X1673073Y1136328D01*
X1673163Y1136301D01*
X1673210Y1136308D01*
G02X1673425Y1136326I214J-1269D01*
G02X1672138Y1135039I0J-1287D01*
G02X1672156Y1135254I1287J1D01*
G01X1672163Y1135301D01*
X1672136Y1135391D01*
X1671846Y1135692D01*
X1671757Y1135723D01*
X1671710Y1135717D01*
G02X1671555Y1135707I-155J1192D01*
G02X1671333Y1135728I2J1202D01*
G01X1671284Y1135737D01*
X1671191Y1135708D01*
X1670886Y1135403D01*
X1670857Y1135310D01*
X1670866Y1135261D01*
G02X1670887Y1135039I-1181J-224D01*
G02X1669685Y1136241I-1202J0D01*
G02X1669907Y1136220I-2J-1202D01*
G01X1669956Y1136211D01*
X1670049Y1136240D01*
X1670354Y1136545D01*
X1670383Y1136638D01*
G37*
G36*
G01X1696564D02*
X1696555Y1136687D01*
G02X1696534Y1136909I1181J224D01*
G02X1697736Y1138111I1202J0D01*
G02X1698674Y1137661I0J-1203D01*
G03X1698830Y1137586I156J125D01*
G01X1699142D01*
G03X1699298Y1137661I0J200D01*
G02X1700236Y1138111I938J-753D01*
G02Y1135707I0J-1202D01*
G02X1699298Y1136157I0J1203D01*
G03X1699142Y1136232I-156J-125D01*
G01X1698830D01*
G03X1698674Y1136157I0J-200D01*
G02X1697736Y1135707I-938J753D01*
G02X1697514Y1135728I2J1202D01*
G01X1697465Y1135737D01*
X1697372Y1135708D01*
X1697067Y1135403D01*
X1697038Y1135310D01*
X1697047Y1135261D01*
G02X1697068Y1135039I-1181J-224D01*
G02X1694664I-1202J0D01*
G02X1694685Y1135261I1202J-2D01*
G01X1694694Y1135310D01*
X1694665Y1135403D01*
X1694360Y1135708D01*
X1694267Y1135737D01*
X1694218Y1135728D01*
G02X1693996Y1135707I-224J1181D01*
G02X1693774Y1135728I2J1202D01*
G01X1693725Y1135737D01*
X1693632Y1135708D01*
X1693327Y1135403D01*
X1693298Y1135310D01*
X1693307Y1135261D01*
G02X1693328Y1135039I-1181J-224D01*
G02X1690924I-1202J0D01*
G02X1690945Y1135261I1202J-2D01*
G01X1690954Y1135310D01*
X1690925Y1135403D01*
X1690620Y1135708D01*
X1690527Y1135737D01*
X1690478Y1135728D01*
G02X1690256Y1135707I-224J1181D01*
G02X1690101Y1135717I0J1202D01*
G01X1690053Y1135723D01*
X1689964Y1135692D01*
X1689674Y1135391D01*
X1689646Y1135301D01*
X1689654Y1135254D01*
G02X1689672Y1135039I-1269J-214D01*
G02X1687098I-1287J0D01*
G02X1687116Y1135254I1287J1D01*
G01X1687123Y1135301D01*
X1687096Y1135391D01*
X1686806Y1135692D01*
X1686717Y1135723D01*
X1686670Y1135717D01*
G02X1686515Y1135707I-155J1192D01*
G02X1686360Y1135717I0J1202D01*
G01X1686313Y1135723D01*
X1686224Y1135692D01*
X1685934Y1135391D01*
X1685907Y1135301D01*
X1685914Y1135254D01*
G02X1685932Y1135039I-1269J-214D01*
G02X1683358I-1287J0D01*
G02X1683376Y1135254I1287J1D01*
G01X1683383Y1135301D01*
X1683356Y1135391D01*
X1683066Y1135692D01*
X1682977Y1135723D01*
X1682930Y1135717D01*
G02X1682775Y1135707I-155J1192D01*
G02X1682553Y1135728I2J1202D01*
G01X1682504Y1135737D01*
X1682411Y1135708D01*
X1682106Y1135403D01*
X1682077Y1135310D01*
X1682086Y1135261D01*
G02X1682107Y1135039I-1181J-224D01*
G02X1680905Y1136241I-1202J0D01*
G02X1681127Y1136220I-2J-1202D01*
G01X1681176Y1136211D01*
X1681269Y1136240D01*
X1681574Y1136545D01*
X1681603Y1136638D01*
X1681594Y1136687D01*
G02X1681573Y1136909I1181J224D01*
G02X1683977I1202J0D01*
G02X1683967Y1136754I-1202J0D01*
G01X1683961Y1136707D01*
X1683992Y1136618D01*
X1684293Y1136328D01*
X1684383Y1136301D01*
X1684430Y1136308D01*
G02X1684645Y1136326I214J-1269D01*
G02X1684860Y1136308I1J-1287D01*
G01X1684907Y1136301D01*
X1684997Y1136328D01*
X1685298Y1136618D01*
X1685329Y1136707D01*
X1685323Y1136754D01*
G02X1685313Y1136909I1192J155D01*
G02X1687717I1202J0D01*
G02X1687707Y1136754I-1202J0D01*
G01X1687701Y1136707D01*
X1687732Y1136618D01*
X1688033Y1136328D01*
X1688123Y1136301D01*
X1688170Y1136308D01*
G02X1688385Y1136326I214J-1269D01*
G02X1688600Y1136308I1J-1287D01*
G01X1688648Y1136300D01*
X1688738Y1136328D01*
X1689039Y1136617D01*
X1689070Y1136707D01*
X1689064Y1136754D01*
G02X1689054Y1136909I1192J155D01*
G02X1691458I1202J0D01*
G02X1691437Y1136687I-1202J2D01*
G01X1691428Y1136638D01*
X1691457Y1136545D01*
X1691762Y1136240D01*
X1691855Y1136211D01*
X1691904Y1136220D01*
G02X1692126Y1136241I224J-1181D01*
G02X1692348Y1136220I-2J-1202D01*
G01X1692397Y1136211D01*
X1692490Y1136240D01*
X1692795Y1136545D01*
X1692824Y1136638D01*
X1692815Y1136687D01*
G02X1692794Y1136909I1181J224D01*
G02X1695198I1202J0D01*
G02X1695177Y1136687I-1202J2D01*
G01X1695168Y1136638D01*
X1695197Y1136545D01*
X1695502Y1136240D01*
X1695595Y1136211D01*
X1695644Y1136220D01*
G02X1695866Y1136241I224J-1181D01*
G02X1696088Y1136220I-2J-1202D01*
G01X1696137Y1136211D01*
X1696230Y1136240D01*
X1696535Y1136545D01*
X1696564Y1136638D01*
G37*
G36*
G01X1662903Y1140378D02*
X1662894Y1140427D01*
G02X1662873Y1140649I1181J224D01*
G02X1664075Y1139447I1202J0D01*
G02X1663852Y1139468I1J1202D01*
G01X1663804Y1139477D01*
X1663709Y1139448D01*
X1663405Y1139144D01*
X1663376Y1139050D01*
X1663385Y1139001D01*
G02X1663406Y1138779I-1181J-224D01*
G02X1661002I-1202J0D01*
G02X1661023Y1139001I1202J-2D01*
G01X1661032Y1139050D01*
X1661003Y1139143D01*
X1660698Y1139448D01*
X1660605Y1139477D01*
X1660556Y1139468D01*
G02X1660334Y1139447I-224J1181D01*
G02X1661536Y1140649I0J1202D01*
G02X1661515Y1140427I-1202J2D01*
G01X1661506Y1140378D01*
X1661535Y1140285D01*
X1661840Y1139980D01*
X1661933Y1139951D01*
X1661982Y1139960D01*
G02X1662204Y1139981I224J-1181D01*
G02X1662427Y1139960I-1J-1202D01*
G01X1662475Y1139951D01*
X1662570Y1139980D01*
X1662874Y1140284D01*
X1662903Y1140378D01*
G37*
G36*
G01X1739075Y1148843D02*
G02X1738415Y1150087I842J1244D01*
G02X1741419I1502J0D01*
G02X1740759Y1148843I-1502J0D01*
G03Y1148181I224J-331D01*
G02X1741419Y1146937I-842J-1244D01*
G02X1738415I-1502J0D01*
G02X1739075Y1148181I1502J0D01*
G03Y1148843I-224J331D01*
G37*
G36*
G01X1723896Y1158669D02*
G02X1723796Y1158666I-95J1499D01*
G02X1725298Y1160168I0J1502D01*
G02X1725184Y1159594I-1502J0D01*
G03X1725580Y1159043I370J-152D01*
G02X1725680Y1159046I95J-1499D01*
G02X1724178Y1157544I0J-1502D01*
G02X1724292Y1158118I1502J0D01*
G03X1723896Y1158669I-370J152D01*
G37*
G36*
G01X1704313Y1173207D02*
G02X1703400Y1172898I-913J1194D01*
G02Y1175902I0J1502D01*
G02X1704896Y1174538I0J-1502D01*
G03X1705537Y1174258I398J37D01*
G02X1706450Y1174567I913J-1194D01*
G02Y1171563I0J-1502D01*
G02X1704954Y1172927I0J1502D01*
G03X1704313Y1173207I-398J-37D01*
G37*
G36*
G01X1669907Y1193700D02*
G02X1669685Y1193679I-224J1181D01*
G02X1670887Y1194881I0J1202D01*
G02X1670866Y1194659I-1202J2D01*
G03X1671333Y1194192I393J-74D01*
G02X1671555Y1194213I224J-1181D01*
G02X1670353Y1193011I0J-1202D01*
G02X1670374Y1193233I1202J-2D01*
G03X1669907Y1193700I-393J74D01*
G37*
G36*
G01X1679733Y1194610D02*
X1679724Y1194659D01*
G02X1679703Y1194881I1181J224D01*
G02X1682107I1202J0D01*
G02X1682086Y1194659I-1202J2D01*
G01X1682077Y1194610D01*
X1682106Y1194517D01*
X1682411Y1194212D01*
X1682504Y1194183D01*
X1682553Y1194192D01*
G02X1682775Y1194213I224J-1181D01*
G02X1681573Y1193011I0J-1202D01*
G02X1681594Y1193233I1202J-2D01*
G01X1681603Y1193282D01*
X1681574Y1193375D01*
X1681269Y1193680D01*
X1681176Y1193709D01*
X1681127Y1193700D01*
G02X1680905Y1193679I-224J1181D01*
G02X1680683Y1193700I2J1202D01*
G01X1680634Y1193709D01*
X1680541Y1193680D01*
X1680236Y1193375D01*
X1680207Y1193282D01*
X1680216Y1193233D01*
G02X1680237Y1193011I-1181J-224D01*
G02X1679035Y1194213I-1202J0D01*
G02X1679257Y1194192I-2J-1202D01*
G01X1679306Y1194183D01*
X1679399Y1194212D01*
X1679704Y1194517D01*
X1679733Y1194610D01*
G37*
G36*
G01X1720177Y1201265D02*
G02X1721662Y1202545I1485J-221D01*
G02Y1199541I0J-1502D01*
G02X1720749Y1199850I0J1503D01*
G03X1720110Y1199592I-243J-317D01*
G02X1718625Y1198312I-1485J221D01*
G02Y1201316I0J1502D01*
G02X1719538Y1201007I0J-1503D01*
G03X1720177Y1201265I243J317D01*
G37*
G36*
G01X1664684Y1205840D02*
X1664676Y1205887D01*
G02X1664658Y1206102I1269J214D01*
G02X1665945Y1204814I1287J-1D01*
G02X1665730Y1204833I5J1288D01*
G01X1665682Y1204841D01*
X1665592Y1204813D01*
X1665291Y1204524D01*
X1665260Y1204434D01*
X1665266Y1204387D01*
G02X1665276Y1204232I-1192J-155D01*
G02X1665255Y1204010I-1202J2D01*
G01X1665246Y1203961D01*
X1665275Y1203867D01*
X1665579Y1203563D01*
X1665674Y1203534D01*
X1665722Y1203543D01*
G02X1665945Y1203564I224J-1181D01*
G02X1664743Y1202362I0J-1202D01*
G02X1664764Y1202584I1202J-2D01*
G01X1664773Y1202633D01*
X1664744Y1202727D01*
X1664440Y1203031D01*
X1664345Y1203060D01*
X1664297Y1203051D01*
G02X1664074Y1203030I-224J1181D01*
G02Y1205434I0J1202D01*
G02X1664229Y1205424I0J-1202D01*
G01X1664277Y1205418D01*
X1664366Y1205449D01*
X1664656Y1205750D01*
X1664684Y1205840D01*
G37*
G36*
G01X1734541Y1214055D02*
X1734529Y1214107D01*
G02X1734487Y1214458I1460J353D01*
G02X1735989Y1212956I1502J0D01*
G02X1735638Y1212998I2J1502D01*
G01X1735586Y1213010D01*
X1735487Y1212982D01*
X1735171Y1212666D01*
X1735143Y1212567D01*
X1735155Y1212515D01*
G02X1735197Y1212164I-1460J-353D01*
G02X1733695Y1210662I-1502J0D01*
G02X1733551Y1210669I1J1502D01*
G01X1733506Y1210673D01*
X1733422Y1210643D01*
X1733140Y1210361D01*
X1733110Y1210278D01*
X1733114Y1210233D01*
G02X1733121Y1210089I-1495J-145D01*
G02X1731619Y1211591I-1502J0D01*
G02X1731763Y1211584I-1J-1502D01*
G01X1731808Y1211580D01*
X1731892Y1211610D01*
X1732174Y1211892D01*
X1732204Y1211975D01*
X1732200Y1212020D01*
G02X1732193Y1212164I1495J145D01*
G02X1733695Y1213666I1502J0D01*
G02X1734046Y1213624I-2J-1502D01*
G01X1734098Y1213612D01*
X1734197Y1213640D01*
X1734513Y1213956D01*
X1734541Y1214055D01*
G37*
G36*
G01X1795927Y1264627D02*
X1796263D01*
X1796330Y1264652D01*
X1796358Y1264676D01*
G02X1798332I987J-1131D01*
G01X1798360Y1264652D01*
X1798427Y1264627D01*
X1798763D01*
X1798830Y1264652D01*
X1798858Y1264676D01*
G02X1799845Y1265046I987J-1131D01*
G02X1801347Y1263544I0J-1502D01*
G02X1800977Y1262557I-1501J0D01*
G01X1800953Y1262529D01*
X1800928Y1262462D01*
Y1262126D01*
X1800953Y1262059D01*
X1800977Y1262031D01*
G02X1801347Y1261044I-1131J-987D01*
G02X1799845Y1259542I-1502J0D01*
G02X1798858Y1259912I0J1501D01*
G01X1798830Y1259936D01*
X1798763Y1259961D01*
X1798427D01*
X1798360Y1259936D01*
X1798332Y1259912D01*
G02X1796358I-987J1131D01*
G01X1796330Y1259936D01*
X1796263Y1259961D01*
X1795927D01*
X1795860Y1259936D01*
X1795832Y1259912D01*
G02X1794845Y1259542I-987J1131D01*
G02X1793343Y1261044I0J1502D01*
G02X1793713Y1262031I1501J0D01*
G01X1793737Y1262059D01*
X1793762Y1262126D01*
Y1262462D01*
X1793737Y1262529D01*
X1793713Y1262557D01*
G02X1793343Y1263544I1131J987D01*
G02X1794845Y1265046I1502J0D01*
G02X1795832Y1264676I0J-1501D01*
G01X1795860Y1264652D01*
X1795927Y1264627D01*
G37*
G54D47*
X98943Y200864D03*
X19859Y1520657D03*
X71910Y1625009D03*
X60554Y1615152D03*
X69816Y1592527D03*
X74909Y1593009D03*
X82291Y1633801D03*
X78291D03*
Y1625743D03*
X70291Y1633801D03*
X83689Y1624736D03*
X753035Y141247D03*
X885884Y255118D03*
X368067Y925136D03*
X368626Y931346D03*
X250790Y1539759D03*
X275123Y847874D03*
X237580Y1528604D03*
X239949Y1541327D03*
X244912Y1539389D03*
X226971Y1514578D03*
X227552Y1530675D03*
X232622Y1531104D03*
X226971Y1522578D03*
X219981Y1530797D03*
X223322Y1518578D03*
X222119Y1539941D03*
X227882Y1540816D03*
X233753Y1539752D03*
X217985Y1483055D03*
X218021Y1494724D03*
X217614Y1489671D03*
X122887Y888000D03*
X123387Y892000D03*
X110887Y884000D03*
X103692Y900295D03*
X91387Y905295D03*
X68598Y859415D03*
X63969Y869475D03*
X63930Y874694D03*
X68100Y910122D03*
X71528Y913190D03*
X64632Y901500D03*
X59962Y910251D03*
X53197Y1017759D03*
Y1014205D03*
X55699Y1072761D03*
X61588Y1074481D03*
X60269Y1198820D03*
X63094Y1207604D03*
X55596Y1210466D03*
X48704Y1017982D03*
X47314Y1072228D03*
X41172Y1079064D03*
X48585Y1123867D03*
X55188Y1205179D03*
X51023Y1201416D03*
X48842Y1211109D03*
X53479Y1216256D03*
X31631Y1198651D03*
X52077Y905295D03*
X47264Y919649D03*
X38823Y1009273D03*
X44999Y1009510D03*
X50541Y1009589D03*
X42470Y1006738D03*
X48683Y1006510D03*
X38197Y1017759D03*
X44197D03*
X41197Y1014205D03*
X47197D03*
X20216Y1009748D03*
X14357Y1009906D03*
X17033Y1006819D03*
X20197Y1017759D03*
Y1014205D03*
X14197Y1017759D03*
Y1014205D03*
X26155Y1009985D03*
X32093Y1009748D03*
X24456Y1006401D03*
X30479Y1006509D03*
X36529Y1006321D03*
X35197Y1014205D03*
X26197Y1017759D03*
X32197D03*
X29197Y1014205D03*
X795011Y95111D03*
X769609Y124283D03*
X775118Y110784D03*
X780118D03*
X779697Y124663D03*
X774675Y124879D03*
X25819Y527726D03*
X44563Y482165D03*
X62224Y473045D03*
X41643Y473419D03*
Y464919D03*
X49643Y464419D03*
X48596Y451419D03*
X63154Y462371D03*
X48643Y442919D03*
X57857Y446071D03*
X65737Y445603D03*
X67670Y464818D03*
X1745231Y489036D03*
X337078Y551381D03*
X335399Y544718D03*
X318660Y539315D03*
X320785Y553287D03*
X327456Y550065D03*
X321119Y622912D03*
X248090Y691114D03*
X254634Y698241D03*
X245362Y542712D03*
Y546712D03*
X244267Y696911D03*
X235790Y754332D03*
X225500Y530000D03*
X225000Y540500D03*
X222289Y590895D03*
X221693Y594982D03*
X220333Y617930D03*
X220255Y629749D03*
X200495Y577937D03*
X208000Y604567D03*
X203500Y606929D03*
X208500Y595500D03*
X209094Y616317D03*
X209158Y610072D03*
X203741Y612592D03*
X203460Y618400D03*
X208540Y621591D03*
X205941Y668934D03*
X185328Y545528D03*
X194063Y577716D03*
X142024Y552466D03*
X149469Y634190D03*
X152658Y645389D03*
X86788Y581659D03*
X87684Y605443D03*
X95539Y664443D03*
X84159Y578986D03*
X78733Y578405D03*
X77734Y596782D03*
X72515Y596089D03*
X83684Y596729D03*
X79684Y605443D03*
X84845Y659857D03*
X73914Y660107D03*
X82648Y670679D03*
X79043Y667391D03*
X84314Y686107D03*
X82562Y680037D03*
X78735Y683426D03*
X63859Y590801D03*
X64408Y582747D03*
X67684Y605637D03*
X63684Y597130D03*
X67684Y597232D03*
X59684Y605443D03*
X63684D03*
X58181Y627908D03*
X66530Y625013D03*
X64692Y642184D03*
X43948Y492108D03*
X45256Y495993D03*
X43804Y500202D03*
X40362Y610548D03*
X47179Y633736D03*
X49192Y628078D03*
X42172Y633716D03*
X54192Y633473D03*
X35650Y495982D03*
Y491982D03*
X34732Y534909D03*
X34359Y541135D03*
X30177Y534211D03*
X25819Y544726D03*
X34448Y552726D03*
X34425Y546553D03*
X25819Y548726D03*
X36306Y622285D03*
X36494Y616905D03*
X27686Y621311D03*
X30123Y611071D03*
X36575Y627713D03*
X36692Y633724D03*
X27686Y625311D03*
Y629311D03*
X113505Y796856D03*
X109591Y796905D03*
X118467Y796785D03*
X658392Y200864D03*
X1786170Y448931D03*
X1792527Y452799D03*
X1786693Y459170D03*
X1804758Y294429D03*
X1793524Y303343D03*
X1805196Y300952D03*
X1803700Y440101D03*
X1803530Y431112D03*
X1803335Y452718D03*
X1797907Y452987D03*
X1796933Y461607D03*
X1796136Y471334D03*
X1768586Y467560D03*
X1764903Y470382D03*
X1776561Y467560D03*
X1779232Y55513D03*
X1775457Y68581D03*
X1785246Y60660D03*
X1781832Y60513D03*
X1775470Y80581D03*
X1781960Y85731D03*
X1779600Y88801D03*
X1782517Y94351D03*
X1777653Y103621D03*
X1785886Y168665D03*
Y176665D03*
X1777172Y172665D03*
X1777109Y178560D03*
X1785779Y192665D03*
X1785886Y196665D03*
X1777289Y200864D03*
X1785999Y186778D03*
X1785918Y204864D03*
X1777378Y212455D03*
X1777312Y207037D03*
X1785918Y208864D03*
X1781559Y219379D03*
X1782187Y228631D03*
X1761941Y106186D03*
X1773364Y112083D03*
X1771714Y171523D03*
X1762102Y168697D03*
X1763190Y191941D03*
X1771244Y192490D03*
X1776519Y190185D03*
X1767202Y192300D03*
X1774679Y221642D03*
X1759112Y256303D03*
X1763887Y266114D03*
X1761360Y281982D03*
X1753784Y265701D03*
X1758871Y265896D03*
X1755419Y281716D03*
X1748497Y371060D03*
X1750135Y379088D03*
X1755433Y379028D03*
X1744180Y383966D03*
X1756553Y466409D03*
X1767552Y76587D03*
Y72615D03*
X1762010Y97475D03*
X1768991Y100625D03*
X1738824Y456034D03*
Y461034D03*
X1751456Y98551D03*
X1755006Y103783D03*
X1758848Y177616D03*
X1759429Y172190D03*
X1712226Y344028D03*
X1715590Y331719D03*
X1721746Y377173D03*
X1715228Y387966D03*
X1718851Y391533D03*
X1720571Y385644D03*
X1725746Y385123D03*
X1718318Y399918D03*
X1725154Y406060D03*
X1721423Y412106D03*
X1716310Y454334D03*
X1724627Y459330D03*
X1724580Y454214D03*
X1743175Y92874D03*
X1729896Y90615D03*
X1734267Y95236D03*
X1734217Y99961D03*
X1736333Y258880D03*
X1744524Y379429D03*
X1741746Y377173D03*
X1737786D03*
X1729751D03*
X1737746Y385123D03*
X1741420Y391569D03*
X1739847Y401066D03*
X1697984Y226320D03*
X1705686Y230556D03*
X1709941Y228747D03*
X1700945Y228646D03*
X1704671Y242078D03*
X1699902Y232971D03*
X1696552Y244571D03*
X1703895Y256394D03*
X1703609Y287320D03*
X1698292Y303962D03*
X1713788Y97667D03*
X1724584Y90650D03*
X1724334Y95236D03*
X1714531Y230117D03*
X1710547Y238714D03*
X1716755Y326179D03*
X1683556Y204864D03*
Y208864D03*
X1679197Y219379D03*
X1693932Y249108D03*
X1685313Y248371D03*
X1683523Y324518D03*
X1677810Y324466D03*
X1686408Y332584D03*
X1687424Y347937D03*
X1692676Y348015D03*
X1688593Y353470D03*
X1691182Y357016D03*
X1680518Y377912D03*
Y381912D03*
Y397912D03*
X1704934Y97667D03*
X1709184Y95111D03*
X1700590Y102495D03*
X1698851Y125107D03*
X1700324Y142862D03*
X1707465Y143762D03*
X1701365Y148717D03*
X1673203Y328867D03*
X1668979Y339559D03*
X1673723Y353881D03*
X1670323Y353534D03*
X1670260Y377912D03*
X1669260Y391496D03*
X1663618Y393858D03*
X1663780Y384410D03*
X1666959Y382047D03*
X1670260Y386500D03*
X1669260Y409000D03*
X1665260Y398583D03*
X1670348Y397912D03*
X1667260Y403500D03*
X1688011Y86012D03*
Y94374D03*
X1683152Y86046D03*
X1680155Y94351D03*
X1684104Y94279D03*
X1694291Y110784D03*
X1689291D03*
X1683782Y124283D03*
X1693870Y124663D03*
X1688848Y124879D03*
X1695214Y138838D03*
X1682189Y161306D03*
X1679440Y157370D03*
X1683524Y168665D03*
Y176665D03*
Y192665D03*
X1683637Y186778D03*
X1649773Y449961D03*
X1653490Y458572D03*
X1645826Y446606D03*
X1647133Y463479D03*
X1676870Y55513D03*
X1673095Y68581D03*
X1673108Y80581D03*
X1665190Y76587D03*
Y72615D03*
X1679598Y85731D03*
X1677238Y88801D03*
X1675291Y103621D03*
X1666629Y100625D03*
X1671002Y112083D03*
X1667208Y141247D03*
X1671695Y143518D03*
X1669352Y171523D03*
X1674810Y172665D03*
X1674747Y178560D03*
X1674157Y190185D03*
X1668882Y192490D03*
X1667318Y198828D03*
X1674927Y200864D03*
X1664840Y192300D03*
X1674950Y207037D03*
X1675016Y212455D03*
X1672317Y221642D03*
X1679825Y228631D03*
X1658645Y143740D03*
X1656025Y148277D03*
X1656486Y177616D03*
X1659740Y168697D03*
X1657067Y172190D03*
X1660828Y191941D03*
X1656750Y256303D03*
X1656509Y265896D03*
X1661525Y266114D03*
X1651422Y265701D03*
X1653057Y281716D03*
X1658998Y281982D03*
X1654771Y352088D03*
X1650044Y435158D03*
X1649789Y440489D03*
X1646209Y442606D03*
X1650087Y444841D03*
X1635170Y442856D03*
X1632439Y452265D03*
X1633225Y458455D03*
X1636271Y453881D03*
X1635185Y446595D03*
X1649094Y98551D03*
X1659648Y97475D03*
X1659579Y106186D03*
X1652644Y103783D03*
X1651178Y141247D03*
X1640813Y92874D03*
X1631905Y95236D03*
X1631855Y99961D03*
X1633971Y258880D03*
X1640030Y335550D03*
X1636561Y343072D03*
X1630691Y347432D03*
X1603324Y230556D03*
X1607579Y227824D03*
X1612169Y230117D03*
X1598583Y228646D03*
X1608185Y238714D03*
X1602309Y242078D03*
X1597540Y232971D03*
X1604677Y253198D03*
X1596691Y287397D03*
X1596197Y293477D03*
X1599527Y396718D03*
X1622222Y90650D03*
X1627534Y90615D03*
X1621972Y95236D03*
X1626147Y351033D03*
X1628636Y422088D03*
X1623955Y442956D03*
X1625772Y438323D03*
X1621596Y456386D03*
X1625938Y445873D03*
X1620385Y465874D03*
X1592635Y455911D03*
X1591443Y465332D03*
X1602572Y97667D03*
X1611426D03*
X1606822Y95111D03*
X1598228Y102495D03*
X1597962Y142862D03*
X1605103Y143762D03*
X1599003Y148717D03*
X1586929Y110784D03*
X1591929D03*
X1586486Y124879D03*
X1591508Y124663D03*
X1596489Y125107D03*
X1592852Y138838D03*
X1581162Y168665D03*
Y176665D03*
Y192665D03*
Y196665D03*
X1581275Y186778D03*
X1581194Y204864D03*
X1595622Y226320D03*
X1594190Y244571D03*
X1591570Y249108D03*
X1582951Y248371D03*
X1585649Y86012D03*
Y94374D03*
X1580790Y86046D03*
X1571895Y58013D03*
X1570733Y68581D03*
X1570746Y80581D03*
X1577236Y85731D03*
X1574876Y88801D03*
X1581742Y94279D03*
X1577793Y94351D03*
X1572929Y103621D03*
X1568640Y112083D03*
X1581420Y124283D03*
X1569333Y143518D03*
X1579827Y161306D03*
X1577078Y157370D03*
X1566990Y171523D03*
X1572385Y178560D03*
X1572448Y172665D03*
X1571795Y190185D03*
X1566520Y192490D03*
X1572565Y200864D03*
X1572654Y212455D03*
X1572588Y207037D03*
X1581194Y208864D03*
X1569955Y221642D03*
X1576835Y219379D03*
X1577463Y228631D03*
X1557378Y168697D03*
X1554705Y172190D03*
X1554124Y177616D03*
X1558466Y191941D03*
X1554388Y256303D03*
X1559163Y266114D03*
X1554147Y265896D03*
X1556636Y281982D03*
X1550695Y281716D03*
X1562828Y72615D03*
Y76587D03*
X1564267Y100625D03*
X1557286Y97475D03*
X1550282Y103783D03*
X1557217Y106186D03*
X1548816Y141247D03*
X1564846D03*
X1556283Y143740D03*
X1553663Y148277D03*
X1546732Y98551D03*
X1538451Y92874D03*
X1531609Y258880D03*
X1549060Y265701D03*
X1525172Y90615D03*
X1519860Y90650D03*
X1529493Y99961D03*
X1529543Y95236D03*
X1519610D03*
X1502741Y143762D03*
X1509807Y230117D03*
X1500962Y230556D03*
X1505217Y227824D03*
X1505823Y238714D03*
X1499947Y242078D03*
X1503884Y295549D03*
X1493260Y226320D03*
X1496221Y228646D03*
X1495178Y232971D03*
X1491828Y244571D03*
X1489208Y249108D03*
X1499171Y256394D03*
X1497446Y295877D03*
X1715930Y340969D03*
X1509064Y97667D03*
X1504460Y95111D03*
X1484124Y124879D03*
X1477465Y161306D03*
X1474716Y157370D03*
X1478800Y168665D03*
Y176665D03*
X1470023Y178560D03*
X1470086Y172665D03*
X1469433Y190185D03*
X1478800Y192665D03*
Y196665D03*
X1470203Y200864D03*
X1478913Y186778D03*
X1478832Y204864D03*
X1470292Y212455D03*
X1470226Y207037D03*
X1478832Y208864D03*
X1467593Y221642D03*
X1474473Y219379D03*
X1475101Y228631D03*
X1480589Y248371D03*
X1498621Y19043D03*
X1489556Y17645D03*
X1498621Y31043D03*
Y23043D03*
X1489829Y29424D03*
X1490563Y23043D03*
X1500210Y97667D03*
X1483287Y94374D03*
X1495866Y102495D03*
X1489567Y110784D03*
X1494127Y125107D03*
X1489146Y124663D03*
X1495600Y142862D03*
X1496641Y148717D03*
X1490490Y138838D03*
X1452026Y256303D03*
X1456801Y266114D03*
X1454274Y281982D03*
X1479972Y40780D03*
X1472146Y55513D03*
X1468371Y68581D03*
X1474874Y85731D03*
X1483287Y86012D03*
X1468384Y80581D03*
X1472514Y88801D03*
X1478428Y86046D03*
X1475431Y94351D03*
X1479380Y94279D03*
X1470567Y103621D03*
X1466278Y112083D03*
X1484567Y110784D03*
X1479058Y124283D03*
X1457347Y31518D03*
X1457829Y26425D03*
X1460466Y76587D03*
Y72615D03*
X1461905Y100625D03*
X1454924Y97475D03*
X1454855Y106186D03*
X1462484Y141247D03*
X1466971Y143518D03*
X1453921Y143740D03*
X1455016Y168697D03*
X1452343Y172190D03*
X1464628Y171523D03*
X1464158Y192490D03*
X1456104Y191941D03*
X1447920Y103783D03*
X1446454Y141247D03*
X1451301Y148277D03*
X1451762Y177616D03*
X1451785Y265896D03*
X1446698Y265701D03*
X1448333Y281716D03*
X1422810Y90615D03*
X1427131Y99961D03*
X1427181Y95236D03*
X1429247Y258880D03*
X1444370Y98551D03*
X1436089Y92874D03*
X1406702Y97667D03*
X1417498Y90650D03*
X1417248Y95236D03*
X1402098Y95111D03*
X1407445Y230117D03*
X1403461Y238714D03*
X1397848Y97667D03*
X1393504Y102495D03*
X1391765Y125107D03*
X1393238Y142862D03*
X1400379Y143762D03*
X1394279Y148717D03*
X1388128Y138838D03*
X1390898Y226320D03*
X1402855Y227824D03*
X1398600Y230556D03*
X1393859Y228646D03*
X1397585Y242078D03*
X1392816Y232971D03*
X1389466Y244571D03*
X1396809Y256394D03*
X1382205Y110784D03*
X1387205D03*
X1386784Y124663D03*
X1376696Y124283D03*
X1381762Y124879D03*
X1375103Y161306D03*
X1372354Y157370D03*
X1386846Y249108D03*
X1378227Y248371D03*
X1336646Y22627D03*
X1336551Y26534D03*
X1351559Y143740D03*
X1348939Y148277D03*
X1360122Y141247D03*
X1364609Y143518D03*
X1324120Y22742D03*
X1328318Y27333D03*
X1336623Y30483D03*
X1322853Y37530D03*
X1328799Y168665D03*
Y192665D03*
Y196665D03*
X1328912Y186778D03*
X1328831Y208864D03*
X1324472Y219379D03*
X1325100Y228631D03*
X1320085Y172665D03*
X1320022Y178560D03*
X1306103Y191941D03*
X1319432Y190185D03*
X1314157Y192490D03*
X1320202Y200864D03*
X1310115Y192300D03*
X1320225Y207037D03*
X1320291Y212455D03*
X1317592Y221642D03*
X1306800Y266114D03*
X1310853Y37543D03*
X1314887Y45448D03*
X1318859D03*
X1311904Y100625D03*
X1320566Y103621D03*
X1305015Y168697D03*
X1314627Y171523D03*
X1297785Y33768D03*
X1302139Y26325D03*
X1302785Y31168D03*
X1294369Y98551D03*
X1304923Y97475D03*
X1301761Y177616D03*
X1302342Y172190D03*
X1296697Y265701D03*
X1301784Y265896D03*
X1304273Y281982D03*
X1298332Y281716D03*
X1279246Y258880D03*
X1271571Y281185D03*
X1257444Y230117D03*
X1262665Y302730D03*
X1286088Y92874D03*
X1272809Y90615D03*
X1277130Y99961D03*
X1277180Y95236D03*
X1243503Y102495D03*
X1241764Y125107D03*
X1243237Y142862D03*
X1250378Y143762D03*
X1244278Y148717D03*
X1240897Y226320D03*
X1248599Y230556D03*
X1252854Y227824D03*
X1243858Y228646D03*
X1253460Y238714D03*
X1247584Y242078D03*
X1242815Y232971D03*
X1246808Y256394D03*
X1267497Y90650D03*
X1267247Y95236D03*
X1232204Y110784D03*
X1237204D03*
X1236783Y124663D03*
X1226695Y124283D03*
X1231761Y124879D03*
X1238127Y138838D03*
X1226437Y176665D03*
Y168665D03*
Y192665D03*
X1226550Y186778D03*
X1226469Y204864D03*
Y208864D03*
X1239465Y244571D03*
X1236845Y249108D03*
X1228226Y248371D03*
X1247847Y97667D03*
X1256701D03*
X1252097Y95111D03*
X1217070Y190185D03*
X1207753Y192300D03*
X1211795Y192490D03*
X1210268Y198671D03*
X1217863Y207037D03*
X1217929Y212455D03*
X1215230Y221642D03*
X1222110Y219379D03*
X1222738Y228631D03*
X1230924Y86012D03*
Y94374D03*
X1226065Y86046D03*
X1227017Y94279D03*
X1223068Y94351D03*
X1219783Y55513D03*
X1216008Y68581D03*
X1216021Y80581D03*
X1208103Y72615D03*
Y76587D03*
X1222511Y85731D03*
X1220151Y88801D03*
X1218204Y103621D03*
X1209542Y100625D03*
X1210121Y141247D03*
X1212265Y171523D03*
X1217723Y172665D03*
X1217660Y178560D03*
X1217840Y200864D03*
X1192007Y98551D03*
X1202561Y97475D03*
X1190319Y147540D03*
X1194091Y141247D03*
X1201558Y143740D03*
X1198938Y148277D03*
X1199980Y172190D03*
X1202653Y168697D03*
X1199399Y177616D03*
X1203741Y191941D03*
X1199422Y265896D03*
X1204438Y266114D03*
X1201911Y281982D03*
X1195970Y281716D03*
X1183726Y92874D03*
X1174818Y95236D03*
X1148016Y143762D03*
X1146237Y230556D03*
X1155082Y230117D03*
X1150492Y227824D03*
X1151098Y238714D03*
X1145222Y242078D03*
X1147590Y253198D03*
X1170447Y90615D03*
X1165135Y90650D03*
X1174768Y99961D03*
X1164885Y95236D03*
X1138535Y226320D03*
X1141496Y228646D03*
X1140453Y232971D03*
X1137103Y244571D03*
X1134483Y249108D03*
X1125864Y248371D03*
X1145485Y97667D03*
X1154339D03*
X1149735Y95111D03*
X1128562Y86012D03*
Y94374D03*
X1141141Y102495D03*
X1129842Y110784D03*
X1134842D03*
X1139402Y125107D03*
X1129399Y124879D03*
X1134421Y124663D03*
X1140875Y142862D03*
X1141916Y148717D03*
X1135765Y138838D03*
X1114781Y58013D03*
X1113646Y68581D03*
X1113659Y80581D03*
X1120149Y85731D03*
X1117789Y88801D03*
X1123703Y86046D03*
X1120706Y94351D03*
X1124655Y94279D03*
X1115842Y103621D03*
X1124333Y124283D03*
X1112246Y143518D03*
X1122740Y161306D03*
X1119991Y157370D03*
X1124075Y168665D03*
Y176665D03*
X1115298Y178560D03*
X1115361Y172665D03*
X1115478Y200864D03*
X1114708Y190185D03*
X1124188Y186778D03*
X1124107Y204864D03*
X1115501Y207037D03*
X1115567Y212455D03*
X1124107Y208864D03*
X1112868Y221642D03*
X1119748Y219379D03*
X1120376Y228631D03*
X1102076Y266114D03*
X1097060Y265896D03*
X1099549Y281982D03*
X1105741Y76587D03*
Y72615D03*
X1100199Y97475D03*
X1107180Y100625D03*
X1107759Y141247D03*
X1099196Y143740D03*
X1096576Y148277D03*
X1100291Y168697D03*
X1097618Y172190D03*
X1109903Y171523D03*
X1097037Y177616D03*
X1101379Y191941D03*
X1109433Y192490D03*
X1087957Y147540D03*
X1091729Y141247D03*
X1093608Y281716D03*
X1074522Y258880D03*
X1089645Y98551D03*
X1081364Y92874D03*
X1062773Y90650D03*
X1068085Y90615D03*
X1072456Y95236D03*
X1072406Y99961D03*
X1062523Y95236D03*
X1051977Y97667D03*
X1047373Y95111D03*
X1052720Y230117D03*
X1048130Y227824D03*
X1048736Y238714D03*
X1043123Y97667D03*
X1038779Y102495D03*
X1032480Y110784D03*
X1037040Y125107D03*
X1032059Y124663D03*
X1038513Y142862D03*
X1045654Y143762D03*
X1039554Y148717D03*
X1033403Y138838D03*
X1036173Y226320D03*
X1043875Y230556D03*
X1039134Y228646D03*
X1042860Y242078D03*
X1038091Y232971D03*
X1034741Y244571D03*
X1032121Y249108D03*
X1042084Y256394D03*
X1015059Y55513D03*
X1026200Y86012D03*
X1017787Y85731D03*
X1026200Y94374D03*
X1015427Y88801D03*
X1022293Y94279D03*
X1018344Y94351D03*
X1021341Y86046D03*
X1027480Y110784D03*
X1021971Y124283D03*
X1027037Y124879D03*
X1020378Y161306D03*
X1017629Y157370D03*
X1021713Y176665D03*
Y168665D03*
Y196665D03*
X1021826Y186778D03*
X1021713Y192665D03*
X1021745Y204864D03*
Y208864D03*
X1017386Y219379D03*
X1018014Y228631D03*
X1023502Y248371D03*
X1011297Y80581D03*
X1003379Y72615D03*
Y76587D03*
X1004818Y100625D03*
X997837Y97475D03*
X1013480Y103621D03*
X1009191Y112083D03*
X1005397Y141247D03*
X1009884Y143518D03*
X1012936Y178560D03*
X997929Y168697D03*
X1012999Y172665D03*
X999017Y191941D03*
X1003029Y192300D03*
X1012346Y190185D03*
X1007071Y192490D03*
X1013139Y207037D03*
X1013205Y212455D03*
X1010506Y221642D03*
X999714Y266114D03*
X994675Y177616D03*
X994939Y256303D03*
X989611Y265701D03*
X994698Y265896D03*
X1011284Y68581D03*
X987283Y98551D03*
X985595Y147540D03*
X989367Y141247D03*
X996834Y143740D03*
X994214Y148277D03*
X995256Y172190D03*
X950177Y215730D03*
X947040Y223885D03*
X948741Y229468D03*
X948785Y242464D03*
X951278Y250583D03*
X946482Y255940D03*
X979002Y92874D03*
X965723Y90615D03*
X970094Y95236D03*
X970044Y99961D03*
X972160Y258880D03*
X934678Y125107D03*
X936151Y142862D03*
X943292Y143762D03*
X937192Y148717D03*
X934477Y211491D03*
X946234Y213390D03*
X942179Y215727D03*
X937438Y213817D03*
X936395Y218142D03*
X933403Y245507D03*
X936962Y249807D03*
X944248Y239844D03*
X949615Y97667D03*
X960411Y90650D03*
X960161Y95236D03*
X940761Y97667D03*
X945011Y95111D03*
X936417Y102495D03*
X930118Y110784D03*
X925118D03*
X924675Y124879D03*
X929697Y124663D03*
X919609Y124283D03*
X931041Y138838D03*
X918016Y161306D03*
X915267Y157370D03*
X916453Y167975D03*
X919577Y240945D03*
Y250394D03*
Y264567D03*
X907522Y143518D03*
X899573Y158195D03*
X910977Y243307D03*
Y262205D03*
Y248032D03*
X883233Y147540D03*
X887005Y141247D03*
X894472Y143740D03*
X891852Y148277D03*
X895064Y250186D03*
X891383Y243203D03*
X896034Y243307D03*
X887148Y249670D03*
X897004Y257480D03*
X892484Y260860D03*
X895140Y265236D03*
X886496Y268968D03*
X883118Y262687D03*
X876200Y86012D03*
X867787Y85731D03*
X865427Y88801D03*
X876200Y94374D03*
X872293Y94279D03*
X868344Y94351D03*
X871341Y86046D03*
X871713Y168665D03*
Y196665D03*
Y192665D03*
X871826Y186778D03*
X871745Y208864D03*
X867386Y219379D03*
X853379Y76587D03*
Y72615D03*
X854818Y100625D03*
X859191Y112083D03*
X863480Y103621D03*
X862999Y172665D03*
X862936Y178560D03*
X849017Y191941D03*
X857071Y192490D03*
X862346Y190185D03*
X853029Y192300D03*
X863205Y212455D03*
X863139Y207037D03*
X860506Y221642D03*
X866015Y224536D03*
X865059Y55513D03*
X861284Y68581D03*
X861297Y80581D03*
X844939Y256303D03*
X844698Y265896D03*
X839611Y265701D03*
X849714Y266114D03*
X837283Y98551D03*
X847837Y97475D03*
X847768Y106186D03*
X840833Y103783D03*
X847929Y168697D03*
X844675Y177616D03*
X845256Y172190D03*
X829002Y92874D03*
X820094Y95236D03*
X820044Y99961D03*
X822160Y258880D03*
X810411Y90650D03*
X815723Y90615D03*
X810161Y95236D03*
X786151Y142862D03*
X793292Y143762D03*
X787192Y148717D03*
X800358Y230117D03*
X795768Y227824D03*
X791513Y230556D03*
X786772Y228646D03*
X796374Y238714D03*
X790498Y242078D03*
X785729Y232971D03*
X789722Y256394D03*
X769351Y176665D03*
Y168665D03*
Y192665D03*
X769464Y186778D03*
X769383Y204864D03*
X783811Y226320D03*
X782379Y244571D03*
X779759Y249108D03*
X771140Y248371D03*
X799615Y97667D03*
X790761D03*
X786417Y102495D03*
X773838Y86012D03*
Y94374D03*
X768979Y86046D03*
X784678Y125107D03*
X781041Y138838D03*
X768016Y161306D03*
X762697Y55513D03*
X758922Y68581D03*
X758935Y80581D03*
X763065Y88801D03*
X765982Y94351D03*
X769931Y94279D03*
X765425Y85731D03*
X761118Y103621D03*
X756829Y112083D03*
X757522Y143518D03*
X765267Y157370D03*
X760637Y172665D03*
X760574Y178560D03*
X754709Y192490D03*
X759984Y190185D03*
X753182Y198671D03*
X769383Y208864D03*
X760843Y212455D03*
X760777Y207037D03*
X758144Y221642D03*
X765024Y219379D03*
X763653Y224536D03*
X741852Y148277D03*
X745567Y168697D03*
X742894Y172190D03*
X742313Y177616D03*
X746655Y191941D03*
X750667Y192300D03*
X742577Y256303D03*
X747352Y266114D03*
X742336Y265896D03*
X744825Y281982D03*
X738884Y281716D03*
X751017Y76587D03*
Y72615D03*
X752456Y100625D03*
X745475Y97475D03*
X738471Y103783D03*
X745406Y106186D03*
X737005Y141247D03*
X744472Y143740D03*
X719798Y258880D03*
X737249Y265701D03*
X726640Y92874D03*
X734921Y98551D03*
X708049Y90650D03*
X713361Y90615D03*
X717732Y95236D03*
X717682Y99961D03*
X707799Y95236D03*
X690930Y143762D03*
X697996Y230117D03*
X689151Y230556D03*
X693406Y227824D03*
X694012Y238714D03*
X688136Y242078D03*
X690504Y253198D03*
X697253Y97667D03*
X692649Y95111D03*
X688399Y97667D03*
X671476Y94374D03*
X684055Y102495D03*
X677756Y110784D03*
X672756D03*
X682316Y125107D03*
X677335Y124663D03*
X683789Y142862D03*
X684830Y148717D03*
X678679Y138838D03*
X681449Y226320D03*
X684410Y228646D03*
X683367Y232971D03*
X677397Y249108D03*
X680017Y244571D03*
X657507Y58013D03*
X656560Y68581D03*
X671476Y86012D03*
X656573Y80581D03*
X660703Y88801D03*
X663620Y94351D03*
X667569Y94279D03*
X663063Y85731D03*
X666617Y86046D03*
X658756Y103621D03*
X654467Y112083D03*
X667247Y124283D03*
X672313Y124879D03*
X665654Y161306D03*
X662905Y157370D03*
X666989Y176665D03*
Y168665D03*
X658275Y172665D03*
X658212Y178560D03*
X657622Y190185D03*
X666989Y196665D03*
Y192665D03*
X667102Y186778D03*
X667021Y204864D03*
Y208864D03*
X658481Y212455D03*
X658415Y207037D03*
X655782Y221642D03*
X662662Y219379D03*
X663290Y228631D03*
X668886Y248371D03*
X640215Y256303D03*
X644990Y266114D03*
X642463Y281982D03*
X648655Y76587D03*
Y72615D03*
X650094Y100625D03*
X643113Y97475D03*
X643044Y106186D03*
X655160Y143518D03*
X642110Y143740D03*
X640532Y172190D03*
X643205Y168697D03*
X644293Y191941D03*
X652347Y192490D03*
X639974Y265896D03*
X634887Y265701D03*
X636522Y281716D03*
X624278Y92874D03*
X632559Y98551D03*
X636109Y103783D03*
X634643Y141247D03*
X639490Y148277D03*
X639951Y177616D03*
X610999Y90615D03*
X615370Y95236D03*
X615320Y99961D03*
X605437Y95236D03*
X617436Y258880D03*
X594891Y97667D03*
X605687Y90650D03*
X590287Y95111D03*
X595634Y230117D03*
X591650Y238714D03*
X586037Y97667D03*
X581693Y102495D03*
X575394Y110784D03*
X579954Y125107D03*
X581427Y142862D03*
X588568Y143762D03*
X582468Y148717D03*
X576317Y138838D03*
X579087Y226320D03*
X586789Y230556D03*
X591044Y227824D03*
X582048Y228646D03*
X585774Y242078D03*
X581005Y232971D03*
X577655Y244571D03*
X584998Y256394D03*
X557973Y55513D03*
X569114Y86012D03*
X558341Y88801D03*
X569114Y94374D03*
X561258Y94351D03*
X565207Y94279D03*
X560701Y85731D03*
X564255Y86046D03*
X570394Y110784D03*
X574973Y124663D03*
X564885Y124283D03*
X569951Y124879D03*
X563292Y161306D03*
X560543Y157370D03*
X564627Y176665D03*
Y168665D03*
Y196665D03*
Y192665D03*
X564740Y186778D03*
X564659Y204864D03*
Y208864D03*
X560300Y219379D03*
X560928Y228631D03*
X575035Y249108D03*
X566416Y248371D03*
X554198Y68581D03*
X554211Y80581D03*
X546293Y76587D03*
Y72615D03*
X547732Y100625D03*
X552105Y112083D03*
X556394Y103621D03*
X540682Y106186D03*
X552798Y143518D03*
X540843Y168697D03*
X555850Y178560D03*
X555913Y172665D03*
X541931Y191941D03*
X555260Y190185D03*
X549985Y192490D03*
X556119Y212455D03*
X556053Y207037D03*
X553420Y221642D03*
X542628Y266114D03*
X530197Y98551D03*
X540751Y97475D03*
X533747Y103783D03*
X532281Y141247D03*
X528509Y147540D03*
X539748Y143740D03*
X537128Y148277D03*
X538170Y172190D03*
X537589Y177616D03*
X537853Y256303D03*
X532525Y265701D03*
X537612Y265896D03*
X534160Y281716D03*
X540101Y281982D03*
X512958Y99961D03*
X515074Y258880D03*
X482636Y256394D03*
X503325Y90650D03*
X508637Y90615D03*
X503075Y95236D03*
X513008D03*
X521916Y92874D03*
X492529Y97667D03*
X483675D03*
X487925Y95111D03*
X479331Y102495D03*
X479065Y142862D03*
X486206Y143762D03*
X480106Y148717D03*
X476725Y226320D03*
X493272Y230117D03*
X484427Y230556D03*
X488682Y227824D03*
X479686Y228646D03*
X483412Y242078D03*
X478643Y232971D03*
X489288Y238714D03*
X473032Y110784D03*
X468032D03*
X477592Y125107D03*
X462523Y124283D03*
X467589Y124879D03*
X472611Y124663D03*
X473955Y138838D03*
X460930Y161306D03*
X475293Y244571D03*
X472673Y249108D03*
X464054Y248371D03*
X429919Y141247D03*
X437386Y143740D03*
X434766Y148277D03*
X450436Y143518D03*
X458181Y157370D03*
X422473Y22627D03*
X422450Y30483D03*
X422378Y26534D03*
X414145Y27486D03*
X426147Y147540D03*
X414626Y176665D03*
Y168665D03*
X414739Y186778D03*
X414658Y208864D03*
X405912Y172665D03*
X405849Y178560D03*
X399984Y192490D03*
X406029Y200864D03*
X395942Y192300D03*
X406052Y207037D03*
X403419Y221642D03*
X410299Y219379D03*
X410927Y228631D03*
X387852Y256303D03*
X387611Y265896D03*
X382524Y265701D03*
X392627Y266114D03*
X384159Y281716D03*
X390100Y281982D03*
X410789Y22627D03*
X396680Y37543D03*
X408680Y37530D03*
X400714Y45448D03*
X404686D03*
X397731Y100625D03*
X406393Y103621D03*
X383612Y33768D03*
X388612Y31168D03*
X387948Y27288D03*
X380196Y98551D03*
X390750Y97475D03*
X387588Y177616D03*
X390842Y168697D03*
X388169Y172190D03*
X391930Y191941D03*
X371915Y92874D03*
X363007Y95236D03*
X365073Y258880D03*
X339287Y238714D03*
X333411Y242078D03*
X332635Y256394D03*
X347058Y399918D03*
X345050Y454334D03*
X358636Y90615D03*
X353324Y90650D03*
X362957Y99961D03*
X353074Y95236D03*
X348351Y319372D03*
X348806Y315427D03*
X351132Y322202D03*
X349120Y336100D03*
X351136Y372334D03*
X350486Y377173D03*
X347591Y391533D03*
X349311Y385644D03*
X354486Y385123D03*
X353894Y406060D03*
X350163Y412106D03*
X353320Y454214D03*
X353367Y459330D03*
X330905Y15806D03*
Y19806D03*
Y27806D03*
X333674Y97667D03*
X342528D03*
X337924Y95111D03*
X329330Y102495D03*
X336205Y143762D03*
X343271Y230117D03*
X338681Y227824D03*
X334426Y230556D03*
X312263Y324518D03*
X301943Y328867D03*
X299000Y377912D03*
Y386500D03*
X299088Y397912D03*
X322847Y19806D03*
X322113Y26187D03*
X316751Y86012D03*
Y94374D03*
X318031Y110784D03*
X323031D03*
X327591Y125107D03*
X322610Y124663D03*
X317588Y124879D03*
X329064Y142862D03*
X330105Y148717D03*
X323954Y138838D03*
X326724Y226320D03*
X329685Y228646D03*
X328642Y232971D03*
X322672Y249108D03*
X325292Y244571D03*
X314053Y248371D03*
X318508Y324322D03*
X315944Y332584D03*
X316067Y347937D03*
X321416Y348015D03*
X312256Y37543D03*
X305610Y55513D03*
X301835Y68581D03*
X301848Y80581D03*
X305978Y88801D03*
X312844Y94279D03*
X308895Y94351D03*
X308338Y85731D03*
X311892Y86046D03*
X304031Y103621D03*
X300435Y143518D03*
X310929Y161306D03*
X308180Y157370D03*
X303550Y172665D03*
X303487Y178560D03*
X312264Y176665D03*
Y168665D03*
Y196665D03*
Y192665D03*
X312377Y186778D03*
X312296Y204864D03*
Y208864D03*
X303756Y212455D03*
X303690Y207037D03*
X301057Y221642D03*
X307937Y219379D03*
X308565Y228631D03*
X288480Y168697D03*
X285226Y177616D03*
X289568Y191941D03*
X285490Y256303D03*
X290265Y266114D03*
X285249Y265896D03*
X287738Y281982D03*
X286940Y315039D03*
X297719Y339559D03*
X291396Y350223D03*
X292520Y384410D03*
X292358Y393858D03*
X298000Y391496D03*
X295699Y382047D03*
X296000Y403500D03*
X298000Y409000D03*
X294000Y398583D03*
X278827Y444841D03*
X282230Y458572D03*
X265011Y453881D03*
X280220Y448493D03*
X274866Y446606D03*
X275873Y463479D03*
X276344Y467367D03*
X289797Y36735D03*
X284666Y34068D03*
X290113Y23188D03*
X289631Y28281D03*
X293930Y76587D03*
Y72615D03*
X295369Y100625D03*
X288388Y97475D03*
X287385Y143740D03*
X284765Y148277D03*
X285807Y172190D03*
X276146Y147540D03*
X279918Y141247D03*
X280162Y265701D03*
X281797Y281716D03*
X277575Y395084D03*
X274425Y381500D03*
X274949Y442606D03*
X278784Y435158D03*
X278529Y440489D03*
X250962Y90650D03*
X256274Y90615D03*
X260595Y99961D03*
X260645Y95236D03*
X250712D03*
X262711Y258880D03*
X257993Y307994D03*
X256475Y422088D03*
X252695Y442956D03*
X254512Y438323D03*
X261965Y458455D03*
X250336Y456386D03*
X254678Y445873D03*
X262526Y451108D03*
X249125Y465874D03*
X277834Y98551D03*
X269553Y92874D03*
X222930Y244571D03*
X233417Y253198D03*
X230842Y313888D03*
X233258Y359186D03*
X228267Y396718D03*
X221375Y455024D03*
X220349Y465622D03*
X240166Y97667D03*
X235562Y95111D03*
X233843Y143762D03*
X240909Y230117D03*
X236319Y227824D03*
X236925Y238714D03*
X234986Y336161D03*
X236264Y342494D03*
X231312Y97667D03*
X226968Y102495D03*
X220669Y110784D03*
X225229Y125107D03*
X220248Y124663D03*
X226702Y142862D03*
X227743Y148717D03*
X221592Y138838D03*
X224362Y226320D03*
X232064Y230556D03*
X227323Y228646D03*
X231049Y242078D03*
X226280Y232971D03*
X220310Y249108D03*
X203248Y55513D03*
X199473Y68581D03*
X199486Y80581D03*
X214389Y86012D03*
X203616Y88801D03*
X214389Y94374D03*
X206533Y94351D03*
X210482Y94279D03*
X209530Y86046D03*
X205976Y85731D03*
X201669Y103621D03*
X215669Y110784D03*
X210160Y124283D03*
X215226Y124879D03*
X205818Y157370D03*
X208567Y161306D03*
X209902Y176665D03*
Y168665D03*
Y196665D03*
Y192665D03*
X210015Y186778D03*
X209934Y204864D03*
Y208864D03*
X205575Y219379D03*
X206203Y228631D03*
X211691Y248371D03*
X204675Y382109D03*
X201125Y178560D03*
X186118Y168697D03*
X201188Y172665D03*
X187206Y191941D03*
X195260Y192490D03*
X200535Y190185D03*
X201394Y212455D03*
X201328Y207037D03*
X198695Y221642D03*
X183128Y256303D03*
X187903Y266114D03*
X185376Y281982D03*
X179435Y281716D03*
X170215Y311671D03*
X191568Y76587D03*
Y72615D03*
X193007Y100625D03*
X186026Y97475D03*
X193586Y141247D03*
X198073Y143518D03*
X175472Y98551D03*
X173784Y147540D03*
X177556Y141247D03*
X185023Y143740D03*
X182403Y148277D03*
X182864Y177616D03*
X183445Y172190D03*
X177800Y265701D03*
X182887Y265896D03*
X147520Y463600D03*
X167191Y92874D03*
X153912Y90615D03*
X158283Y95236D03*
X158233Y99961D03*
X160349Y258880D03*
X164496Y309405D03*
X129702Y230556D03*
X133957Y227824D03*
X124961Y228646D03*
X128687Y242078D03*
X123918Y232971D03*
X134044Y246874D03*
X120568Y244571D03*
X127911Y256394D03*
X126131Y359511D03*
X125753Y365856D03*
X137804Y97667D03*
X148600Y90650D03*
X148350Y95236D03*
X138547Y230117D03*
X134563Y238714D03*
X138664Y241699D03*
X148061Y378600D03*
Y382600D03*
X117886Y124663D03*
X112864Y124879D03*
X107798Y124283D03*
X119230Y138838D03*
X106205Y161306D03*
X107540Y176665D03*
Y168665D03*
Y196665D03*
Y192665D03*
X107653Y186778D03*
X107572Y204864D03*
Y208864D03*
X103213Y219379D03*
X117948Y249108D03*
X109329Y248371D03*
X128950Y97667D03*
X133200Y95111D03*
X124606Y102495D03*
X122867Y125107D03*
X124340Y142862D03*
X131481Y143762D03*
X125381Y148717D03*
X122000Y226320D03*
X95711Y143518D03*
X103456Y157370D03*
X98826Y172665D03*
X98763Y178560D03*
X92898Y192490D03*
X98173Y190185D03*
X98966Y207037D03*
X99032Y212455D03*
X96333Y221642D03*
X103841Y228631D03*
X100120Y377898D03*
X98255Y374510D03*
X100066Y381976D03*
X118307Y110784D03*
X113307D03*
X73110Y98551D03*
X77804Y95879D03*
X75194Y141247D03*
X71422Y147540D03*
X82661Y143740D03*
X80041Y148277D03*
X80502Y177616D03*
X81083Y172190D03*
X83756Y168697D03*
X84844Y191941D03*
X80766Y256303D03*
X75438Y265701D03*
X85541Y266114D03*
X80525Y265896D03*
X83014Y281982D03*
X77073Y281716D03*
X57987Y258880D03*
X27340Y230556D03*
X36185Y230117D03*
X31595Y227824D03*
X32201Y238714D03*
X23844Y239299D03*
X21556Y232971D03*
X26325Y262078D03*
X25549Y256394D03*
X31682Y266874D03*
X29116Y281129D03*
X37117Y279991D03*
X25549Y276394D03*
X26629Y295619D03*
X45988Y90512D03*
X51550Y90615D03*
X48476Y180812D03*
X34845Y291756D03*
X64829Y92874D03*
X55871Y99961D03*
X55921Y95236D03*
X7036Y272371D03*
X8335Y280663D03*
X14807Y282181D03*
X15586Y269108D03*
X15499Y288542D03*
X32350Y63562D03*
Y59562D03*
X28442Y55340D03*
X32350Y67562D03*
X26588Y97667D03*
X35442D03*
X22439Y102495D03*
X26565Y177448D03*
X32507Y180517D03*
X7271Y70981D03*
X11011Y79720D03*
X8786Y88425D03*
X14264Y94236D03*
X10292D03*
X12786Y87903D03*
X18000Y90000D03*
X8000Y102500D03*
X18298Y102141D03*
X10131Y115473D03*
X15143Y115581D03*
X14996Y133034D03*
X11442Y132719D03*
X19855Y133000D03*
X9082Y135789D03*
X19855Y141362D03*
X11999Y141415D03*
X15948Y141267D03*
X16909Y153263D03*
X12247Y166341D03*
X17313Y166937D03*
X21909Y153263D03*
X22335Y166721D03*
X16709Y175943D03*
X19638Y226320D03*
X22599Y228646D03*
X18206Y244571D03*
X15586Y249108D03*
X13715Y259381D03*
X8970Y254871D03*
X18206Y264571D03*
X1756894Y472020D03*
X1756954Y477318D03*
X1768575Y475560D03*
X1764906Y474382D03*
X1777061Y475560D03*
X1790061Y474513D03*
X40009Y481467D03*
X45643Y472905D03*
X49643D03*
X1787674Y303130D03*
X1455013Y43128D03*
X201305Y200864D03*
X445949Y141247D03*
X295948D03*
X945018Y276051D03*
X903035Y141247D03*
X650673D03*
X548311D03*
X74700Y842890D03*
X69049Y847718D03*
X53549Y843118D03*
X72149Y827318D03*
X68649Y827218D03*
X86289Y822088D03*
X65549Y850718D03*
X278400Y890839D03*
X269700Y853100D03*
X275400Y864400D03*
X279261Y926339D03*
X275400Y899400D03*
X68778Y873821D03*
X23603Y1449735D03*
X54843Y1501625D03*
X48089Y1501387D03*
X26231Y1554167D03*
X22381Y1554152D03*
X33189Y1501373D03*
X39095Y1501361D03*
X60303Y1534436D03*
X6951Y1538547D03*
X47621Y1343672D03*
X15889Y1494254D03*
X10089D03*
X60277Y1528395D03*
X60227Y1514751D03*
X18879Y1534334D03*
X6489Y1501334D03*
X55862Y1541791D03*
X10367Y1553080D03*
X65478Y1541980D03*
X19735Y1530499D03*
X19745Y1508846D03*
X12599Y1438143D03*
X16304Y1468196D03*
X58443Y1272257D03*
X47074Y1555923D03*
X64747Y1555890D03*
X40951Y1555932D03*
X93496Y1547768D03*
X863116Y200864D03*
X556030D03*
X406118Y212455D03*
X760754Y200864D03*
X303667D03*
X60747Y1555890D03*
X1124075Y192665D03*
Y196665D03*
X379928Y949774D03*
X76332Y953421D03*
X70059Y1071656D03*
Y1079656D03*
X62109Y1091656D03*
X363893Y946863D03*
X80593Y946082D03*
X69263Y1053152D03*
X69373Y1063389D03*
X270100Y946500D03*
X397252Y962861D03*
X396671Y968287D03*
X393998Y971780D03*
X370214Y967812D03*
Y963812D03*
Y971812D03*
X378928Y967812D03*
X159836Y988813D03*
X151836Y997860D03*
X159836D03*
X155836D03*
X147836Y988813D03*
X139836D03*
X151836D03*
X143836D03*
X139836Y997860D03*
X147836D03*
X143836D03*
X135836D03*
Y988813D03*
X131836D03*
X123836D03*
X127836D03*
X124079Y1009354D03*
X119836Y997860D03*
X131836D03*
X127836D03*
X123836D03*
X120579Y1009354D03*
X111836Y988813D03*
X119836D03*
X115836D03*
X107836D03*
X103836Y997860D03*
X111836D03*
X111275Y1008262D03*
X114770Y1009354D03*
X107836Y997860D03*
X115836D03*
X103836Y988813D03*
X100200Y988800D03*
X95836Y988813D03*
X99836Y997860D03*
X95836D03*
X461285Y1193471D03*
Y1197471D03*
X451304Y1293045D03*
X437991Y1286544D03*
X434424Y1286274D03*
X430527Y1289198D03*
X440906D03*
X411174Y1282776D03*
X425582Y1291743D03*
X413526Y1288938D03*
X419977Y1288843D03*
X413640Y1292856D03*
X404324Y1271889D03*
X397695Y1287071D03*
X404324Y1275889D03*
X399716Y1295198D03*
X407767Y1292198D03*
X403678Y1295426D03*
X365748Y1134325D03*
X366133Y1162817D03*
Y1170767D03*
X368661Y1182649D03*
X366429Y1185238D03*
X366222Y1180235D03*
X368917Y1195419D03*
X362402Y1201039D03*
X366402Y1200969D03*
X369839Y1218940D03*
X366521Y1208993D03*
X372501Y1123695D03*
X361621Y1134729D03*
X352545Y1142666D03*
X360877Y1157404D03*
X357947Y1159455D03*
X352931Y1167768D03*
X357950D03*
X357057Y1179542D03*
X361792Y1187310D03*
X348432Y1187215D03*
X348125Y1180175D03*
X358368Y1201043D03*
X354398D03*
X350402D03*
X346387Y1199256D03*
X349276Y1217228D03*
X351940Y1219895D03*
X355215Y1223170D03*
X339251Y1138130D03*
X340500Y1147500D03*
X342009Y1176100D03*
X335190Y1173065D03*
X349700Y1148000D03*
X456213Y1286776D03*
X454120Y1269498D03*
X341266Y1171956D03*
X336755Y1143489D03*
X419619Y1539978D03*
X421454Y1544625D03*
X422539Y1534361D03*
X426701Y1541947D03*
X418151Y1552470D03*
X417461Y1569584D03*
X404500Y1452500D03*
X408964Y1531149D03*
X399373Y1555855D03*
X405496Y1561024D03*
X400396D03*
X410596D03*
X401461Y1569560D03*
X397461D03*
X382017Y1559700D03*
X395296Y1561024D03*
X391740Y1550729D03*
Y1555829D03*
X381900Y1544800D03*
X391740Y1545629D03*
Y1540529D03*
X395380Y1485778D03*
X395199Y1482223D03*
X395112Y1395690D03*
X398340Y1399779D03*
X389700Y1536900D03*
X898869Y351114D03*
X804536Y441486D03*
X473658Y475509D03*
X482193Y476784D03*
Y472784D03*
Y468784D03*
X459461Y473805D03*
X459414Y468689D03*
X459757Y463520D03*
X453544Y461961D03*
X451144Y472809D03*
Y468809D03*
X1054876Y536382D03*
X998332Y578986D03*
X1001825Y581659D03*
X997857Y596729D03*
X1001857Y605443D03*
X997857D03*
X992906Y578405D03*
X985903Y579475D03*
X985357Y585507D03*
X989950D03*
X981857Y605637D03*
X986688Y596089D03*
X991907Y596782D03*
X981857Y597232D03*
X985401Y590145D03*
X989995Y590190D03*
X993857Y605443D03*
X989857D03*
X973843Y500086D03*
X964012Y546830D03*
X978032Y590801D03*
X978581Y582747D03*
X977857Y597130D03*
X973857Y605443D03*
X958124Y492354D03*
X957977Y500202D03*
X949823Y495982D03*
X959600Y496486D03*
X949823Y499982D03*
X948905Y534909D03*
X950667Y616905D03*
X954535Y610548D03*
X948427Y611091D03*
X948532Y541135D03*
X936653Y526836D03*
X944351Y534211D03*
X939992Y536726D03*
X948621Y552726D03*
X948598Y546553D03*
X939992Y544726D03*
Y548726D03*
Y540726D03*
Y552726D03*
X931627Y561578D03*
Y565578D03*
X944296Y611071D03*
X913998Y597103D03*
X915712Y613792D03*
X920961Y550075D03*
X923642Y561578D03*
X923453Y569578D03*
X923599Y581578D03*
X909362Y555614D03*
X898156Y554812D03*
X908846Y560124D03*
X904393Y570176D03*
X908517D03*
X898815D03*
X909024Y578394D03*
X898232Y588320D03*
X902635Y588305D03*
X909024Y574394D03*
X898207Y599891D03*
X910789Y598726D03*
X896431Y534093D03*
X885931D03*
X886549Y553963D03*
X887417Y566713D03*
X892023Y570176D03*
X882949Y557363D03*
X890959Y579788D03*
X891673Y600049D03*
X895933Y609696D03*
Y618143D03*
X887949Y608863D03*
X894449Y606363D03*
X874649Y545296D03*
X878382Y554942D03*
X876949Y571419D03*
X867093Y558703D03*
Y562703D03*
Y566703D03*
X875290Y578703D03*
X881131Y577349D03*
X881476Y588202D03*
X867093Y578703D03*
X861468Y491303D03*
X867093Y570703D03*
Y582828D03*
X796000Y553101D03*
X775746Y539315D03*
X781429Y545017D03*
X777708Y553287D03*
X749402Y559665D03*
Y566752D03*
X741602Y559665D03*
Y566752D03*
X749402Y573839D03*
Y588012D03*
Y580925D03*
X741452Y579978D03*
X741602Y573839D03*
X749402Y595099D03*
Y523799D03*
Y516713D03*
Y509626D03*
X741602Y516713D03*
X749402Y537973D03*
Y530886D03*
X738062Y537973D03*
X740542Y525483D03*
X740463Y532756D03*
X731984Y514608D03*
X731906Y522134D03*
X723491Y537973D03*
X732549Y529136D03*
X732388Y535677D03*
X731291Y559665D03*
X731672Y565574D03*
X731319Y574338D03*
X711463Y546712D03*
X702448Y542712D03*
Y546712D03*
X682586Y530000D03*
X660366Y511673D03*
X652042Y487711D03*
X652566Y495886D03*
X647915Y516841D03*
X651166Y510565D03*
X642255Y518760D03*
Y511673D03*
Y525847D03*
X634455Y488799D03*
Y495886D03*
Y511673D03*
Y518760D03*
Y525847D03*
Y532933D03*
X598462Y504684D03*
X597789Y536382D03*
X539111Y681459D03*
X535387Y712617D03*
X532628Y720776D03*
X526276Y721339D03*
X508237Y723585D03*
X503311Y715652D03*
X500705Y705524D03*
X468558Y491669D03*
Y503669D03*
Y507669D03*
Y499669D03*
Y512669D03*
Y516609D03*
X464199Y510184D03*
X443094Y491251D03*
X459929Y491669D03*
X460537Y501905D03*
X459952Y496842D03*
X459645Y509486D03*
X432700Y516277D03*
X393823Y487382D03*
X388593Y664232D03*
X386350Y693559D03*
X391478Y690675D03*
X373971Y489036D03*
X373504Y517954D03*
X376881Y518564D03*
X932388Y330517D03*
X1077602Y314060D03*
X1082297Y340770D03*
X1085615Y339815D03*
X1082787Y348501D03*
X1061325Y339509D03*
X1060679Y360151D03*
Y364276D03*
X1062234Y378600D03*
Y382600D03*
X1061693Y463600D03*
X1045966Y346808D03*
X1050777Y450750D03*
X1030220Y313554D03*
X1041783Y321114D03*
X1031377Y333671D03*
X1043106Y340230D03*
X1042948Y333696D03*
X1031259Y350427D03*
X1046674Y340031D03*
X1013354Y323362D03*
X1021451Y322879D03*
X1026032Y322906D03*
X1013327Y327453D03*
X1013318Y333190D03*
X1022845Y340944D03*
X1013313Y339909D03*
X1020406Y350772D03*
X1015195Y428305D03*
X1041496Y300276D03*
X998667Y322239D03*
X1004544Y318050D03*
X1004933Y314535D03*
X1003181Y323057D03*
X1001105Y318006D03*
X997921Y333654D03*
X1009770Y344486D03*
X997020Y345354D03*
X1003076Y332496D03*
X1000420Y348954D03*
Y353954D03*
X996024Y352132D03*
X997992Y290755D03*
X1002580Y309619D03*
X1010499Y309062D03*
X1004635Y300276D03*
X1008635D03*
X993992Y290755D03*
X989992D03*
X993132Y310942D03*
X983956Y346652D03*
X989630Y343862D03*
X983717Y341665D03*
X993026Y353813D03*
X981719Y352217D03*
X988631Y349496D03*
X992045Y366559D03*
X984045D03*
X988045D03*
X986373Y370467D03*
X991392Y409230D03*
X979932Y437508D03*
X981843Y464818D03*
X977150Y335472D03*
X968348Y402369D03*
X975932Y437508D03*
X971932D03*
X971826Y430187D03*
X962769Y458466D03*
X969109Y449352D03*
X962816Y442919D03*
X977327Y462371D03*
X949974Y291554D03*
X950953Y317947D03*
X960376Y392807D03*
X956863Y451466D03*
X962769Y451419D03*
X950315Y464851D03*
X955816Y464919D03*
X963816Y464419D03*
X977150Y328472D03*
X947733Y319680D03*
X934128Y355168D03*
X934464Y358618D03*
X934047Y369160D03*
X936175Y364823D03*
X931072Y386992D03*
X941872Y440942D03*
X933424Y458455D03*
X933161Y451442D03*
X941505Y463442D03*
X933404Y463462D03*
X933412Y468942D03*
X913057Y311046D03*
X920142Y308501D03*
X930727Y302571D03*
X923732Y304585D03*
X927309Y357267D03*
X921389D03*
X915395D03*
X923311Y349959D03*
X915395Y363212D03*
X927309Y363239D03*
Y369210D03*
X921468D03*
X915395D03*
X929943Y372600D03*
X921343Y376888D03*
X916330Y377748D03*
X929947Y376821D03*
X927072Y386992D03*
X919072D03*
X923072D03*
X915072D03*
X927766Y456442D03*
X921973Y469328D03*
X927401Y469059D03*
X916593Y469140D03*
X911072Y386992D03*
X897736Y383125D03*
X910779Y471380D03*
X910236Y465272D03*
X910040Y353532D03*
X905000Y362158D03*
X906161Y367191D03*
X913288Y372752D03*
X910646Y376084D03*
X906344Y372524D03*
X886059Y284644D03*
X885918Y289500D03*
X885989Y309368D03*
Y305368D03*
Y317368D03*
X885953Y325368D03*
X885989Y313368D03*
X885953Y321368D03*
Y329368D03*
Y333368D03*
X898533Y334498D03*
X896592Y358369D03*
Y354369D03*
X888812Y357372D03*
X883552Y357276D03*
X896592Y362369D03*
Y366369D03*
Y370369D03*
Y374369D03*
X884736Y383125D03*
X893736D03*
X888736D03*
X891251Y387484D03*
X890553Y392038D03*
X876622Y293721D03*
X869924Y305368D03*
X877977Y309368D03*
X869924Y313368D03*
X877977D03*
Y325368D03*
Y317368D03*
Y321368D03*
X869924D03*
Y328722D03*
X870413Y342791D03*
X869924Y333722D03*
X877977Y333368D03*
Y329368D03*
X873885Y340892D03*
X874005Y344917D03*
X872736Y383125D03*
X876736D03*
X877909Y391731D03*
X880736Y383125D03*
X882925Y391099D03*
X872736Y391754D03*
X867586Y393000D03*
Y385000D03*
X868586Y398500D03*
X855017Y411969D03*
X862020Y410899D03*
X850733Y461382D03*
X850748Y465382D03*
X863430Y309368D03*
Y316970D03*
X863114Y324505D03*
X863040Y330140D03*
X854086Y374500D03*
X858586D03*
X863086D03*
X854086Y385000D03*
X861235Y394000D03*
X854086Y392999D03*
X864086Y384000D03*
X857973Y404867D03*
X862522Y400229D03*
X862566Y404867D03*
X857928Y400184D03*
X843992Y290755D03*
X839992D03*
X847992D03*
X848879Y360849D03*
X845435Y356172D03*
X849591Y411388D03*
X846098Y408715D03*
X842515Y461382D03*
X850732Y469382D03*
X842916Y467009D03*
X823529Y467189D03*
X825792Y305225D03*
X822477Y309368D03*
X825971Y345101D03*
X822626Y348066D03*
X805952Y301675D03*
X817456Y305368D03*
Y313368D03*
X809490Y305368D03*
X801097Y325858D03*
X817100Y319600D03*
X809490Y325368D03*
Y317368D03*
Y321368D03*
X786461Y293028D03*
X800155Y337368D03*
X800029Y333368D03*
X799937Y347340D03*
X797141Y350368D03*
X795445Y356950D03*
X778985Y442498D03*
X778881Y446510D03*
X763898Y342319D03*
X754805Y339559D03*
X759624Y353961D03*
X766344Y409924D03*
X759543Y445787D03*
X760407Y324494D03*
X741161Y381500D03*
X723404Y379657D03*
X731511Y390500D03*
X721900Y384500D03*
X712692Y356779D03*
X689486Y339583D03*
X678461Y455981D03*
X687055Y376456D03*
X660366Y467539D03*
Y389154D03*
X661761Y382109D03*
X642255Y389154D03*
X649074D03*
X642255Y396240D03*
X643534Y404911D03*
X647604Y396240D03*
X642488Y412571D03*
X652381Y414823D03*
X651689Y422864D03*
X643675Y426299D03*
X651759Y429832D03*
X651364Y436447D03*
X653399Y447953D03*
X643986Y445847D03*
X642255Y467539D03*
X652566D03*
X634455Y389154D03*
Y396240D03*
Y403327D03*
Y410413D03*
Y417500D03*
Y424587D03*
Y431673D03*
Y438760D03*
Y445847D03*
Y467539D03*
X593690Y450750D03*
X604606Y463600D03*
X605147Y378600D03*
Y382600D03*
X551536Y359223D03*
Y354723D03*
Y350223D03*
Y345723D03*
Y377223D03*
Y372723D03*
Y368223D03*
Y363723D03*
X541706Y381723D03*
X551536D03*
X553563Y384987D03*
X552905Y430829D03*
X533189Y390723D03*
X531953Y385749D03*
X532659Y359557D03*
X526388Y351301D03*
X528812Y369164D03*
X533115Y371856D03*
X530144Y376062D03*
X531953Y380749D03*
X520845Y434508D03*
X516845D03*
X512845D03*
X492817Y357111D03*
X491843Y351089D03*
X491053Y365423D03*
X481724Y391589D03*
Y387089D03*
X491289Y391589D03*
X490885Y382570D03*
X488438Y425464D03*
X482532Y418464D03*
X490985Y412342D03*
X488438Y418417D03*
X481485Y439900D03*
Y431917D03*
X489485Y431417D03*
X482484Y444517D03*
X497424Y354559D03*
X496023Y362913D03*
X497048Y369450D03*
X495750Y377531D03*
X506500Y379687D03*
X495203Y386890D03*
X446179Y447101D03*
X472913Y369089D03*
Y373589D03*
Y382589D03*
Y378089D03*
X470796Y394592D03*
X426647Y452987D03*
X421267Y452799D03*
X414910Y448931D03*
X418754Y468607D03*
X415433Y459170D03*
X424876Y471334D03*
X432440Y440101D03*
X438098Y442114D03*
X437835Y435101D03*
X432075Y452718D03*
X438086Y452601D03*
X438078Y447121D03*
X433673Y461607D03*
X397315Y471560D03*
X405301Y467560D03*
X415129Y325181D03*
X422988Y323627D03*
X421231Y338523D03*
Y331255D03*
X426830Y359026D03*
X416574Y357528D03*
X421413Y359053D03*
X421231Y345776D03*
X413432Y346797D03*
X416318Y367903D03*
X424479Y367859D03*
X415453Y455039D03*
X410086Y336795D03*
X410688Y344736D03*
X400728Y353152D03*
X411007Y356743D03*
X394237Y370899D03*
X394944Y398949D03*
X389237Y371070D03*
X385237Y370976D03*
X384173Y379028D03*
X381237Y371076D03*
X392444Y401949D03*
X393837Y466409D03*
X393662Y470382D03*
X385293Y466409D03*
X376099Y458309D03*
Y454309D03*
X367564Y461034D03*
X376099Y462309D03*
X366443Y472189D03*
X373264Y370010D03*
X377237Y371060D03*
X373264Y379429D03*
X378875Y379088D03*
X370486Y377173D03*
X366486Y385123D03*
X370160Y391569D03*
X376992Y395248D03*
X368587Y409016D03*
X364551Y409032D03*
X368587Y401066D03*
X850738Y477382D03*
X861468Y483303D03*
Y487303D03*
X850832Y473382D03*
X875907Y486256D03*
X869454Y479303D03*
X869954Y487303D03*
X882954Y486256D03*
X882907Y480350D03*
X891454Y486303D03*
X910759Y475511D03*
X928999Y477948D03*
X634455Y474626D03*
X652155Y479104D03*
X642516Y480828D03*
X642255Y474626D03*
X651308Y472772D03*
X842779Y473076D03*
X850909Y482382D03*
X393652D03*
X393746Y478382D03*
X393646Y474382D03*
X385634Y472020D03*
X385694Y477318D03*
X397315Y479560D03*
Y475560D03*
X405801D03*
X418801Y474513D03*
X411754D03*
X634455Y481713D03*
X522200Y677613D03*
X524206Y354119D03*
X885556Y543664D03*
X899407Y560019D03*
X1022604Y290262D03*
X499528Y657843D03*
X481742Y657477D03*
X496070Y665976D03*
X949579Y330517D03*
X909417Y323302D03*
X949813Y336817D03*
X912085Y332335D03*
X932622Y336817D03*
X926801Y323302D03*
X923902Y332411D03*
X485303Y681841D03*
X425062Y883981D03*
X404468Y864407D03*
X396306Y864409D03*
X406770Y869767D03*
X405466Y881299D03*
X397431Y870654D03*
X401108Y878487D03*
X392584Y875845D03*
X391614Y930676D03*
X475588Y1043055D03*
X470610Y1033783D03*
X471755Y1038665D03*
X470978Y1046591D03*
X495236Y1129094D03*
X528500Y1106365D03*
X525525Y1110092D03*
X514566Y1000766D03*
X514690Y996766D03*
Y1004766D03*
X514843Y1030766D03*
X519500Y1028377D03*
X498585Y1016266D03*
X506566Y1012266D03*
X496372Y1106298D03*
X493397Y1110092D03*
X498435Y1008766D03*
X506566Y996766D03*
Y1008766D03*
X498524Y997590D03*
X480711Y999941D03*
X477857Y1004375D03*
X485678Y1039880D03*
X485633Y1036155D03*
X467345Y996480D03*
X459360Y1004680D03*
X464385Y1038534D03*
X459700Y1035716D03*
X477765Y1093432D03*
X462913Y1106365D03*
X459938Y1110092D03*
X459360Y1012325D03*
X443591Y1019766D03*
X451140Y1021793D03*
X447091Y1019766D03*
X450875Y1028416D03*
X443091Y1034266D03*
X452091Y1039880D03*
X459700Y1032266D03*
X443091Y1026266D03*
X429677Y1106955D03*
X427810Y1110092D03*
X409231Y1118801D03*
X464795Y1000647D03*
X488041Y1020440D03*
X432838Y1128821D03*
X429348Y1129092D03*
X498727Y1128759D03*
X417305Y1359169D03*
X418430Y1394237D03*
X414280Y1362561D03*
X419045Y1398874D03*
X395959Y1352153D03*
X468850Y545586D03*
X447279Y637031D03*
X447921Y630789D03*
X453552Y631779D03*
X456469Y638302D03*
X446987Y643360D03*
X443144Y628667D03*
X441162Y638313D03*
X423963Y625778D03*
X590957Y1180691D03*
Y1155491D03*
Y1142891D03*
Y1168091D03*
X587467Y1142891D03*
Y1155491D03*
Y1168091D03*
Y1180691D03*
X578298Y1215195D03*
X584024Y1209607D03*
X569135Y1214372D03*
X564890Y1218169D03*
X569882Y1223749D03*
X569520Y1139891D03*
X566020D03*
X560211D03*
Y1134764D03*
X566058D03*
X566020Y1152491D03*
X560211D03*
X569520D03*
X560211Y1147364D03*
X566058D03*
X566020Y1165091D03*
X560211D03*
X569520D03*
X560211Y1172564D03*
X566058D03*
X560211Y1159964D03*
X566058D03*
X560211Y1177691D03*
X566020D03*
X569520D03*
X566058Y1185164D03*
X560211D03*
X563673Y1204932D03*
X575620Y1207737D03*
X592885Y1229402D03*
X593519Y1224472D03*
X586502Y1227300D03*
X583520Y1230407D03*
X594183Y1220068D03*
X592634Y1234921D03*
X541245Y578986D03*
X535819Y578405D03*
X529601Y596089D03*
X540770Y596729D03*
X534820Y596782D03*
X524770Y597232D03*
X536770Y605443D03*
X520945Y590801D03*
X521494Y582747D03*
X524770Y605637D03*
X520770Y597130D03*
X516770Y605443D03*
X520770D03*
X511278Y633473D03*
X515267Y627908D03*
X523616Y625013D03*
X521778Y642184D03*
X501224Y492050D03*
X492736Y495982D03*
X502493Y495917D03*
X500890Y500202D03*
X497448Y610548D03*
X506278Y628078D03*
X499258Y633716D03*
X504265Y633736D03*
X492736Y491982D03*
X491445Y541135D03*
X491818Y534909D03*
X491511Y546553D03*
X491534Y552726D03*
X493580Y616905D03*
X493392Y622285D03*
X487209Y611071D03*
X493778Y633724D03*
X493661Y627713D03*
X512943Y443071D03*
X520823Y442603D03*
X518240Y459371D03*
X517310Y470045D03*
X522756Y461818D03*
X503682Y448419D03*
X500729Y469905D03*
X496729Y470419D03*
X504729Y469905D03*
X496729Y461919D03*
X504729Y461419D03*
X497095Y481467D03*
X501649Y482165D03*
X616923Y988813D03*
X608923D03*
X612923Y997860D03*
X607993Y1036920D03*
X610780Y1051037D03*
X617634Y1049283D03*
X617894Y1043955D03*
X612955Y1062941D03*
X600923Y988813D03*
X592923D03*
X604923D03*
X596923D03*
X599113Y1012354D03*
Y1024954D03*
X606434Y1041904D03*
X603682Y1053457D03*
X584923Y988813D03*
X576923D03*
X580923D03*
X588923D03*
X572923D03*
X577704Y1029427D03*
Y1016827D03*
X587880Y1034834D03*
X587467Y1105091D03*
Y1117691D03*
X564923Y988813D03*
X560923D03*
X556923D03*
X568923D03*
X567484Y1024003D03*
X571857Y1016827D03*
Y1029427D03*
X560211Y1109564D03*
X566058D03*
X560211Y1122164D03*
X566058D03*
X552923Y988813D03*
X551485Y1006648D03*
X548852Y1018307D03*
X556493Y1118351D03*
X591872Y1518071D03*
X806148Y1383715D03*
Y1375208D03*
X816648Y1380758D03*
X810148Y1374884D03*
X810204Y1401661D03*
X804654Y1404769D03*
X967936Y1207823D03*
X970761Y1216607D03*
X978169Y1221268D03*
X958690Y1210419D03*
X963263Y1219469D03*
X962855Y1214182D03*
X956509Y1220112D03*
X961146Y1225259D03*
X939298Y1207654D03*
X903959Y1207823D03*
X906784Y1216607D03*
X913784Y1221057D03*
X909077Y1232724D03*
X894713Y1210419D03*
X898878Y1214182D03*
X899286Y1219469D03*
X892532Y1220112D03*
X897169Y1225259D03*
X886926Y1298712D03*
X889729Y1295516D03*
X887342Y1314990D03*
X875321Y1207654D03*
X762671Y1619367D03*
X756358Y1613767D03*
X732268Y1618260D03*
X732825Y1604100D03*
X777059Y1608982D03*
X768361Y1610083D03*
X744924Y1617709D03*
X741705Y1622015D03*
X736067Y1611892D03*
X749704Y1608631D03*
X737892Y1602340D03*
X749786Y1590517D03*
X738775Y1597866D03*
X747140Y1581335D03*
X784046Y1600438D03*
X781110Y1595254D03*
X759802Y1590864D03*
X763542Y1590186D03*
X755035Y1443524D03*
X760398Y1440276D03*
X613738Y1546507D03*
X621727Y1556800D03*
X591487Y1501687D03*
X591481Y1509313D03*
X595809Y1532133D03*
Y1546214D03*
X591809Y1542407D03*
X581803Y1493687D03*
X578859Y1497758D03*
X588859Y1490895D03*
X590826Y1495688D03*
X588507Y1514141D03*
X582027Y1502800D03*
X577931Y1505687D03*
X581803Y1509687D03*
X575809Y1532912D03*
X587809Y1528389D03*
X583809Y1533025D03*
X579809Y1528163D03*
X587809Y1545854D03*
X583809Y1541607D03*
X577571Y1544013D03*
X570796Y1530309D03*
X567324Y1528151D03*
X565400Y1535100D03*
X563968Y1541445D03*
X557584Y1543411D03*
X568279Y1538438D03*
X572507Y1541375D03*
X1267333Y1531334D03*
X1262891Y1527334D03*
X1267183Y1539334D03*
X1262891Y1535334D03*
X1254275Y1531334D03*
X1249894Y1527805D03*
X1254275Y1539334D03*
X1250434Y1535334D03*
X906309Y1226647D03*
X910633Y1222799D03*
X793548Y1397690D03*
X1049770Y1229402D03*
X1040606Y1230407D03*
X1049720Y1234921D03*
X1043588Y1227300D03*
X891107Y1314305D03*
X1046075Y1350650D03*
X729600Y1625165D03*
X771383Y1616917D03*
X1007850Y1368835D03*
X749439Y1458777D03*
X931159Y1379427D03*
X740530Y1524113D03*
X931159Y1383227D03*
Y1406027D03*
Y1402227D03*
X931137Y1375878D03*
X931199Y1371951D03*
X931159Y1387027D03*
Y1390827D03*
Y1394627D03*
Y1398427D03*
X1023358Y1363921D03*
X1013991Y1360842D03*
X781124Y1583553D03*
X768812Y1453306D03*
X1069642Y1445541D03*
X1068861Y1451311D03*
X939559Y1402227D03*
X980166Y1373622D03*
X998600Y1369200D03*
X988784Y1361974D03*
X1019391Y1377061D03*
X1008387Y1380797D03*
X985448Y1398271D03*
X998600Y1373400D03*
X948235Y1406262D03*
X944235D03*
X939559Y1398427D03*
X927193Y1361547D03*
X952561Y1383465D03*
X980203Y1377559D03*
X980139Y1381496D03*
Y1393308D03*
X980047Y1397245D03*
X920255Y1383264D03*
X952716Y1387402D03*
X952395Y1395276D03*
X952514Y1391339D03*
X904177Y1359955D03*
X999283Y1377400D03*
X997401Y1381200D03*
X920360Y1387039D03*
X998643Y1398271D03*
X778045Y1619395D03*
X738325Y1634485D03*
X743331Y1627871D03*
X778358Y1627418D03*
X1253904Y1519645D03*
X1049204Y1337377D03*
X755187Y1580821D03*
X698936Y678462D03*
X648211Y614400D03*
X605011Y615600D03*
X604979Y607588D03*
X703669Y665140D03*
X705390Y655789D03*
X706070Y638125D03*
X704364Y618288D03*
X700164Y636842D03*
X614176Y562003D03*
X614461Y555234D03*
X669546Y560500D03*
X680586Y568000D03*
X884887Y1026762D03*
X890887D03*
X897717Y1019915D03*
X895394Y1026985D03*
X887862Y1088067D03*
X894004Y1081231D03*
X884906Y1102760D03*
X884890Y1098724D03*
X878887Y1026762D03*
X866887Y1023208D03*
X863956Y1020763D03*
X825335Y1137129D03*
X819026Y1128137D03*
X823220Y1162817D03*
Y1170767D03*
X818879Y1187310D03*
X823309Y1180235D03*
X823516Y1185238D03*
X823487Y1193019D03*
X819487D03*
X819489Y1201039D03*
X823489Y1200969D03*
X826612Y1219254D03*
X823608Y1208993D03*
X809632Y1142666D03*
X794716Y1186071D03*
X817964Y1157404D03*
X815034Y1159455D03*
X810018Y1167768D03*
X815037D03*
X814160Y1178240D03*
X814170Y1185205D03*
X805212Y1180175D03*
X805519Y1187215D03*
X815487Y1193019D03*
X811487D03*
X815455Y1201043D03*
X811485D03*
X796338Y1138130D03*
X797160Y1146609D03*
X799020Y1175975D03*
X809393Y1187252D03*
X794533Y1195766D03*
X799631Y1025440D03*
X803673D03*
X798542Y1188345D03*
X795631Y1025440D03*
X806787Y1148000D03*
X849996Y1091073D03*
X850023Y1095179D03*
X793842Y1143384D03*
X798353Y1172011D03*
X1017297Y1147364D03*
X1023144D03*
X1017297Y1165091D03*
X1023106D03*
X1017297Y1172564D03*
Y1159964D03*
X1023144D03*
X1017297Y1177691D03*
X1023139Y1184856D03*
X1017297Y1185164D03*
X1021976Y1218169D03*
X1017297Y1114691D03*
Y1122164D03*
X1023144D03*
X1023106Y1127291D03*
X1017297Y1139891D03*
X1023106D03*
X1017297Y1127291D03*
Y1134764D03*
X1023144D03*
X1017297Y1152491D03*
X1023106D03*
X995317Y1137378D03*
X980726Y1092664D03*
X995009Y1131223D03*
X991763Y1140378D03*
Y1128378D03*
Y1134378D03*
X988389Y1302558D03*
X979001Y1288925D03*
X984817Y1303297D03*
X980726Y1080659D03*
Y1088659D03*
X965716Y1091346D03*
X966366Y1081764D03*
X972776Y1093659D03*
X972255Y1083484D03*
X972776Y1088659D03*
X965671Y1095940D03*
X972776Y1100659D03*
X978727Y1284908D03*
X974985Y1290950D03*
X948259Y1295965D03*
X961033Y1091391D03*
X957981Y1081231D03*
X951839Y1088067D03*
X948883Y1102760D03*
X948867Y1098724D03*
X955032Y1095407D03*
X961033Y1095984D03*
X940848Y1310181D03*
X943891Y1306608D03*
X944207Y1320739D03*
X947308Y1325035D03*
X916749Y1080659D03*
Y1088659D03*
Y1092664D03*
X901739Y1091346D03*
X902389Y1081764D03*
X908799Y1093659D03*
Y1088659D03*
X908278Y1083484D03*
X901694Y1095940D03*
X908799Y1100659D03*
X910788Y1299456D03*
X897056Y1091391D03*
Y1095984D03*
X949970Y1321749D03*
X901366Y1078069D03*
X989513Y1097683D03*
X986645Y1108465D03*
X990501Y1320756D03*
X1045300Y872352D03*
X1004577Y853679D03*
X988820Y858903D03*
X956239Y829577D03*
X955712Y833988D03*
X961175Y838525D03*
X1164732Y802269D03*
X1173697Y791911D03*
X1160516Y800900D03*
X1169266Y800799D03*
X1145910Y794217D03*
X1044553Y1105091D03*
X1048043Y1117691D03*
Y1142891D03*
Y1155491D03*
Y1180691D03*
X1071548Y555234D03*
X1071263Y562003D03*
X1137673Y568000D03*
X1126633Y560500D03*
X1157451Y618288D03*
X1157251Y636842D03*
X1161451Y618288D03*
X1163157Y638125D03*
X1160756Y665140D03*
X1160275Y656321D03*
X1164275D03*
X1105298Y614400D03*
X1090747Y1617415D03*
X1102904Y1566668D03*
X1093778Y1599574D03*
X1093713Y1585583D03*
X1092527Y1579422D03*
X1100233Y1588000D03*
X1107620Y1606752D03*
X1091529Y1528718D03*
X1083483Y1523433D03*
X1101767Y1544567D03*
X1084000Y1529600D03*
X1095800Y1552200D03*
X1091525Y1546300D03*
X1098617Y1546183D03*
X1105474Y1638426D03*
X1086904Y1599004D03*
X1096780Y1526700D03*
X1091569Y1561300D03*
X1100476Y1579318D03*
X1083900Y1593206D03*
X1090469Y1588435D03*
X1105973Y1593206D03*
X1088021Y1606949D03*
X1098904Y1602138D03*
X1101946Y1614709D03*
X1090093Y1628297D03*
X1096941Y1627905D03*
X1105474Y1629450D03*
X1097474Y1637753D03*
X1089474Y1638213D03*
X1375459Y1197471D03*
Y1193471D03*
X1318287Y1295381D03*
Y1291381D03*
X1275788Y1124088D03*
X1282421Y1137129D03*
X1275050Y1157404D03*
X1272120Y1159455D03*
X1280306Y1162817D03*
Y1170767D03*
X1275965Y1187232D03*
X1280602Y1185238D03*
X1280395Y1180235D03*
X1276573Y1193019D03*
X1280573D03*
X1272573D03*
X1272541Y1201043D03*
X1276575Y1201039D03*
X1280575Y1200969D03*
X1284198Y1218754D03*
X1280694Y1208993D03*
X1266718Y1142666D03*
X1267104Y1167768D03*
X1272123D03*
X1271246Y1178240D03*
X1271256Y1185205D03*
X1262605Y1187215D03*
X1262298Y1180175D03*
X1268573Y1193019D03*
X1264573D03*
X1268571Y1201043D03*
X1263449Y1217228D03*
X1266113Y1219895D03*
X1269388Y1223170D03*
X1253424Y1138130D03*
X1254200Y1146600D03*
X1256218Y1175987D03*
X1249363Y1166065D03*
X1263873Y1148000D03*
X1249363Y1173065D03*
X1251802Y1186071D03*
X1346270Y1297498D03*
X1351670D03*
X1340870D03*
X1357070D03*
X1308276Y1276446D03*
X1335470Y1297498D03*
X1330070D03*
X1307167Y1245696D03*
X1303900Y1288000D03*
X1260800Y1191096D03*
X1255439Y1172008D03*
X1250928Y1142828D03*
X1307996Y487382D03*
X1288144Y489036D03*
X1308010Y466409D03*
X1290272Y458309D03*
Y462309D03*
X1299466Y466409D03*
X1281737Y461034D03*
X1280616Y472189D03*
X1261623Y447486D03*
X1259223Y454334D03*
X1267540Y459330D03*
X1267493Y454214D03*
X1259223Y458334D03*
X1223431Y393924D03*
Y389912D03*
Y385912D03*
Y409924D03*
Y405924D03*
Y401924D03*
X1209872Y382047D03*
X1212173Y391496D03*
X1213173Y386500D03*
X1206673Y410394D03*
Y403307D03*
X1213261Y397912D03*
X1210173Y403500D03*
X1212173Y409000D03*
X1212680Y445908D03*
X1216630Y445787D03*
X1206531Y393858D03*
X1208173Y398583D03*
X1192702Y440489D03*
X1192957Y435158D03*
X1193000Y444841D03*
X1192686Y449961D03*
X1198689Y465492D03*
X1179184Y410394D03*
Y403307D03*
X1178083Y442856D03*
X1179184Y446595D03*
X1171445Y422088D03*
X1168902Y431029D03*
X1166868Y442956D03*
X1169173Y427017D03*
X1168851Y449873D03*
X1142440Y400718D03*
Y408718D03*
Y404718D03*
Y412718D03*
X1198689Y486752D03*
Y479665D03*
X1206489D03*
Y486752D03*
Y472579D03*
X1299867Y477318D03*
X1299807Y472020D03*
X1307919Y478382D03*
X1307825Y482382D03*
X1407265Y989465D03*
X1416618Y992307D03*
X1389192Y992568D03*
X1420740Y996766D03*
X1428864D03*
X1412698Y997590D03*
X1394885Y999941D03*
X1428740Y1000766D03*
X1392031Y1004375D03*
X1435669Y1005366D03*
X1412609Y1008766D03*
X1420740D03*
X1440869Y1010256D03*
X1420740Y1012266D03*
X1412759Y1016266D03*
X1428740D03*
X1357765Y1019766D03*
X1361265D03*
X1428823Y1020266D03*
X1402215Y1020440D03*
X1365314Y1021793D03*
X1357265Y1026266D03*
X1435197Y1028372D03*
X1365049Y1028416D03*
X1373874Y1032266D03*
X1333974Y1033483D03*
X1384784Y1033783D03*
X1357265Y1034266D03*
X1373874Y1035716D03*
X1399807Y1036155D03*
X1378559Y1038534D03*
X1385929Y1038665D03*
X1399852Y1039779D03*
X1366265Y1039880D03*
X1322773Y1040599D03*
X1389762Y1043055D03*
X1385152Y1046591D03*
X1392086Y1092743D03*
X1344241Y1106298D03*
X1410546D03*
X1377087Y1106365D03*
X1442674D03*
X1341984Y1110092D03*
X1374112D03*
X1407571D03*
X1439699D03*
X1347300Y1128332D03*
X1343725Y1128738D03*
X1413177Y1128894D03*
X1409425Y1129238D03*
X1480193Y1177691D03*
X1474384D03*
X1480231Y1185164D03*
X1474384D03*
X1483693Y1177691D03*
X1505130Y1180691D03*
X1480231Y1134764D03*
X1474384D03*
X1501640Y1142891D03*
X1480231Y1147364D03*
X1474384D03*
X1505130Y1142891D03*
X1483693Y1139891D03*
X1480193D03*
X1474384D03*
X1501640Y1155491D03*
X1480231Y1159964D03*
X1474384D03*
X1505130Y1155491D03*
X1483693Y1152491D03*
X1480193D03*
X1474384D03*
X1480231Y1172564D03*
X1474384D03*
X1505130Y1168091D03*
X1483693Y1165091D03*
X1480193D03*
X1474384D03*
X1501640Y1168091D03*
Y1180691D03*
X1489793Y1207737D03*
X1498197Y1209607D03*
X1492471Y1215195D03*
X1484055Y1223749D03*
X1477846Y1204932D03*
X1483308Y1214372D03*
X1479063Y1218169D03*
X1425652Y1297411D03*
X1500675Y1227300D03*
X1507058Y1229402D03*
X1508356Y1220068D03*
X1507692Y1224472D03*
X1506807Y1234921D03*
X1497693Y1230407D03*
X1385992Y1285466D03*
X1404019Y1285290D03*
X1415903Y1282590D03*
X1390492Y1285466D03*
X1762041Y1631511D03*
X1768422Y1632245D03*
X1773820Y1631238D03*
X1765040Y1599511D03*
X1759947Y1599029D03*
X1750685Y1621654D03*
X1640581Y1551907D03*
X1600008Y1488492D03*
X1601500Y1514500D03*
X1608500Y1506000D03*
Y1515000D03*
X1613790Y1531334D03*
X1609348Y1527334D03*
X1613790Y1523334D03*
X1604000Y1519000D03*
X1600732Y1539334D03*
X1609348Y1535334D03*
X1591775Y1473090D03*
X1596038Y1492000D03*
X1591925Y1512075D03*
X1591333Y1501980D03*
X1590748Y1523377D03*
X1766313Y1580198D03*
X1761072Y1590719D03*
X1758390Y1577905D03*
X1421964Y1502813D03*
X1596836Y1446488D03*
X1778104Y1470289D03*
X1420877Y1494706D03*
X1605430Y1468023D03*
X1596790Y1442557D03*
X1600333Y1440504D03*
X1407255Y1571732D03*
X1803885Y1435046D03*
X1778227Y1438099D03*
X1812202Y1432624D03*
X1423930Y1520364D03*
X1429587Y1527450D03*
X1432913Y1568679D03*
X1407747Y1549054D03*
X1433405Y1546001D03*
X1441145Y1540415D03*
X1440153Y1563093D03*
X1408536Y1536570D03*
X1806428Y1444543D03*
X1809342Y1476733D03*
X1430374Y1492474D03*
X1408044Y1559306D03*
X1786091Y1443715D03*
X1601968Y1453442D03*
X1597457Y1460662D03*
X1772188Y1428369D03*
X1787745Y1437765D03*
X1783178Y1437550D03*
X1795374Y1444543D03*
X1600333Y1449068D03*
X1598574Y1543373D03*
X1443769Y1562173D03*
X1482535Y1024254D03*
X1475062Y1008300D03*
Y1002453D03*
X1513286Y1024954D03*
X1491877Y1029427D03*
X1486030D03*
X1513286Y1012354D03*
X1491877Y1016827D03*
X1486030D03*
X1501640Y1117691D03*
X1480231Y1122164D03*
X1474384D03*
X1501640Y1105091D03*
X1480231Y1109564D03*
X1474384D03*
X1532067Y1041832D03*
X1531947Y1046212D03*
X1531546Y1062769D03*
X1531096Y988813D03*
X1527096Y997860D03*
X1521939Y1040818D03*
X1522099Y1035521D03*
X1524953Y1051037D03*
X1468869Y1018469D03*
X1471374Y1118654D03*
X1456966Y998507D03*
X1458892Y1007522D03*
X1465658Y1006648D03*
X1465846Y1023900D03*
X1463025Y1018307D03*
X1459267Y1013678D03*
X1456280Y1023405D03*
X1459683Y1028377D03*
X1490235Y1004816D03*
X1487266Y1002046D03*
X1526810Y1025090D03*
X1522904Y1021256D03*
X1779404Y826570D03*
X1791041Y818795D03*
X1500638Y873839D03*
X1692379Y622912D03*
X1693000Y626912D03*
X1611873Y795127D03*
X1630327Y774627D03*
X1628027Y801427D03*
X1606709Y819165D03*
X1629927Y787327D03*
X1635283Y728117D03*
X1613117Y828117D03*
X1606190Y803774D03*
X1500353Y859855D03*
X1504938Y859711D03*
X1802000Y892447D03*
X1780016Y874400D03*
X1746884Y884649D03*
X1750915Y902055D03*
X1749267Y918413D03*
X1746897Y879199D03*
X1741800Y917900D03*
X1775904Y924546D03*
X1778047Y916120D03*
X1644552Y871353D03*
X1518452Y873780D03*
X1819900Y906900D03*
X1512712Y867418D03*
X1547644Y903060D03*
X1548080Y910757D03*
X1525022Y909558D03*
X1504208Y909740D03*
X1502158Y899479D03*
X1494954Y895264D03*
X1635176Y886761D03*
X1644718Y909263D03*
X1505337Y921240D03*
X1509274Y921226D03*
X1614538Y618288D03*
X1618538D03*
X1620244Y638125D03*
X1617843Y665140D03*
X1621362Y656321D03*
X1617362D03*
X1613110Y678462D03*
X1614338Y636842D03*
X1594760Y568000D03*
X1583720Y560500D03*
X1571755Y577937D03*
X1565323Y577716D03*
X1579760Y595500D03*
X1574540Y602205D03*
Y595118D03*
X1580354Y616317D03*
X1575001Y612592D03*
X1574720Y618400D03*
X1547910Y602197D03*
X1562385Y598400D03*
Y602400D03*
Y594400D03*
X1548374Y595108D03*
X1562385Y614400D03*
Y606400D03*
X1528350Y562003D03*
X1519185Y615600D03*
X1519153Y607588D03*
X1528635Y555234D03*
X1548616Y931602D03*
X1572141Y662981D03*
X1568872Y686971D03*
X1575192Y707592D03*
X1620100Y738300D03*
X1620500Y723200D03*
X1616683Y744517D03*
X1620600Y705900D03*
X1809696Y1091832D03*
X1816756Y1089145D03*
X1816235Y1083970D03*
X1810346Y1082250D03*
X1809651Y1096426D03*
X1816756Y1101145D03*
X1810310Y1104819D03*
X1815865Y1133356D03*
X1805013Y1091877D03*
X1801961Y1081717D03*
X1795819Y1088553D03*
X1792847Y1099210D03*
X1799012Y1095893D03*
X1805013Y1096470D03*
X1800813Y1103246D03*
X1792863D03*
X1739508Y1137129D03*
X1732137Y1157404D03*
X1729207Y1159455D03*
X1737393Y1162817D03*
Y1170767D03*
X1729210Y1167768D03*
X1728333Y1178240D03*
X1733052Y1187310D03*
X1737689Y1185238D03*
X1737482Y1180235D03*
X1733660Y1193019D03*
X1729660D03*
X1737660D03*
X1733662Y1201039D03*
X1729628Y1201043D03*
X1737662Y1200969D03*
X1740785Y1219254D03*
X1737781Y1208993D03*
X1723805Y1142666D03*
X1724191Y1167768D03*
X1713239Y1176038D03*
X1728343Y1185205D03*
X1719692Y1187215D03*
X1719385Y1180175D03*
X1725660Y1193019D03*
X1721660D03*
X1725658Y1201043D03*
X1720536Y1217228D03*
X1723200Y1219895D03*
X1710511Y1138130D03*
X1711333Y1146609D03*
X1720960Y1148000D03*
X1708889Y1189221D03*
X1712715Y1188500D03*
X1764744Y1097879D03*
Y1101930D03*
X1812296Y1075688D03*
X1708015Y1142700D03*
X1712526Y1171950D03*
X1812130Y1205349D03*
X1814741Y1217093D03*
X1806835Y1214668D03*
X1800489Y1220598D03*
X1807243Y1219955D03*
X1802670Y1210905D03*
X1805126Y1225745D03*
X1783278Y1208140D03*
G54D59*
X978614Y1210568D03*
Y1214838D03*
X914637Y1210568D03*
Y1214838D03*
X1822594Y1211054D03*
Y1215324D03*
G54D50*
X180610Y1136909D03*
Y1148129D03*
Y1144389D03*
X169389Y1121948D03*
X176870D03*
X180610D03*
X176870Y1125688D03*
Y1129429D03*
X180610Y1140649D03*
Y1125688D03*
Y1129429D03*
Y1133169D03*
X158169Y1121948D03*
X154429D03*
X150689D03*
X161909D03*
X158169Y1125688D03*
X154429D03*
X146948Y1121948D03*
X143208D03*
X188090Y1114468D03*
Y1125688D03*
Y1129429D03*
Y1133169D03*
Y1136909D03*
Y1140649D03*
Y1144389D03*
Y1118208D03*
Y1121948D03*
X158169Y1114468D03*
X154429D03*
X150689D03*
X165649D03*
X161909D03*
X146948D03*
X143208D03*
X257283Y1108858D03*
X234842Y1090157D03*
X320866Y1221062D03*
X313385Y1209842D03*
X320866Y1213582D03*
X324606Y1221062D03*
X313385Y1217322D03*
X320866Y1236023D03*
Y1224803D03*
Y1232283D03*
X313385D03*
X317125Y1228543D03*
Y1224803D03*
X313385Y1236023D03*
X324606Y1232283D03*
Y1236023D03*
Y1224803D03*
X328347Y1239762D03*
Y1247243D03*
X320866Y1250984D03*
Y1243503D03*
X313385Y1250984D03*
X317125Y1247243D03*
Y1243503D03*
X324606D03*
Y1250984D03*
X313385Y1247243D03*
X320866D03*
X317125Y1250984D03*
X313385Y1243503D03*
X324606Y1247243D03*
X317125Y1258465D03*
X313385Y1254724D03*
X317125D03*
X322736Y1155610D03*
X318996Y1144389D03*
X315255D03*
X318996Y1155610D03*
X315255Y1151869D03*
X318996D03*
Y1148129D03*
X326476D03*
Y1155610D03*
X322736Y1144389D03*
Y1151870D03*
X326476Y1144389D03*
X315255Y1148129D03*
X326476Y1151870D03*
X315255Y1155610D03*
X322736Y1170570D03*
Y1166830D03*
X315255Y1159350D03*
X318996D03*
X315255Y1166830D03*
X318996Y1170570D03*
Y1166830D03*
X326476D03*
Y1170570D03*
X322736Y1159350D03*
X326476D03*
X315255Y1170570D03*
Y1181791D03*
Y1189271D03*
X318996D03*
Y1185531D03*
Y1181791D03*
Y1178051D03*
X315255Y1174310D03*
X318996D03*
X326476Y1178051D03*
Y1185531D03*
X322736Y1178051D03*
Y1185531D03*
Y1174310D03*
Y1181791D03*
Y1189271D03*
X326476Y1174310D03*
X315255Y1178051D03*
X326476Y1181791D03*
X315255Y1185531D03*
X326476Y1189271D03*
X328347Y1198621D03*
Y1206102D03*
X322736Y1193011D03*
X320866Y1202362D03*
X318996Y1193011D03*
X317125Y1206102D03*
X313385D03*
X317125Y1198621D03*
X326416Y1193011D03*
X324606Y1202362D03*
X320866Y1198621D03*
X313385Y1202362D03*
X324606Y1198621D03*
X317125Y1202362D03*
X320866Y1206102D03*
X324606D03*
X315255Y1193011D03*
X328347Y1221062D03*
Y1213582D03*
X320866Y1217322D03*
Y1209842D03*
X313385Y1221062D03*
X317125D03*
X313385Y1213582D03*
X317125D03*
X324606Y1209842D03*
Y1217322D03*
X317125D03*
Y1209842D03*
X324606Y1213582D03*
X317125Y1116338D03*
X324606Y1112598D03*
Y1120078D03*
X328347Y1116339D03*
Y1123819D03*
X320866Y1112598D03*
Y1120078D03*
X317125Y1123818D03*
X328347Y1131300D03*
X320866Y1127558D03*
X322736Y1140649D03*
X318996D03*
X313384Y1131299D03*
X317125D03*
X324606Y1127558D03*
X326476Y1140649D03*
X315255D03*
X322736Y1148129D03*
X320866Y1086417D03*
Y1078936D03*
X313384Y1090157D03*
X317125D03*
X317126Y1086417D03*
X317125Y1082677D03*
X313386Y1078936D03*
X320866Y1093897D03*
X313385D03*
X324606Y1086417D03*
Y1093897D03*
Y1105117D03*
Y1097637D03*
X328347Y1101378D03*
Y1108859D03*
X320866Y1105117D03*
Y1097637D03*
X313385Y1108858D03*
X317125D03*
X317126Y1105117D03*
X317125Y1101377D03*
X313385Y1097637D03*
X317125Y1071455D03*
X320866Y1075196D03*
X313386D03*
X328347Y1082677D03*
Y1090158D03*
X309645Y1247243D03*
Y1243503D03*
X317125Y1239763D03*
X294685Y1247243D03*
X298425Y1250984D03*
X302165Y1247243D03*
X294685Y1243503D03*
X302165D03*
X305905Y1239763D03*
X302165D03*
X313385D03*
X305905Y1250984D03*
X294685D03*
X298425Y1247243D03*
X309645Y1250984D03*
X298425Y1243503D03*
X305905D03*
Y1247243D03*
X302165Y1250984D03*
X309645Y1258465D03*
X294685D03*
X302165D03*
X298425Y1254724D03*
X305905D03*
X294685D03*
X309645D03*
X302165D03*
X311515Y1193011D03*
X305905Y1206102D03*
X302165Y1213582D03*
X294685Y1209842D03*
X298425D03*
X302165Y1206102D03*
X298425Y1221062D03*
X302165D03*
X298425Y1217322D03*
X309645D03*
Y1209842D03*
X305905Y1213582D03*
X309645D03*
Y1206102D03*
Y1221062D03*
X298425Y1236023D03*
Y1232283D03*
X294685Y1228543D03*
X302165D03*
X294685Y1224803D03*
Y1221062D03*
X302165Y1224803D03*
X305905Y1221062D03*
X298425Y1239763D03*
X305905Y1232283D03*
X309645Y1228543D03*
Y1224803D03*
X305905Y1236023D03*
X309645Y1239763D03*
X294685Y1127558D03*
X302165Y1123818D03*
X313385D03*
X309645D03*
X311515Y1140649D03*
X296555Y1151869D03*
X304035Y1155610D03*
Y1148129D03*
X300295Y1155610D03*
Y1151869D03*
Y1148129D03*
Y1144389D03*
X296555D03*
X311515D03*
X307775Y1148129D03*
X311515Y1151869D03*
X307775Y1155610D03*
X304035Y1144389D03*
Y1151869D03*
X307775Y1144389D03*
Y1151869D03*
X296555Y1155610D03*
X311515Y1148129D03*
Y1155610D03*
X307775Y1159350D03*
X296555D03*
X300295D03*
X296555Y1166830D03*
X304035Y1170570D03*
X300295D03*
Y1166830D03*
X311515D03*
X307775Y1170570D03*
X311515Y1159350D03*
X304035Y1166830D03*
Y1159350D03*
X307775Y1166830D03*
X296555Y1170570D03*
X311515D03*
X300295Y1181791D03*
Y1178051D03*
Y1174310D03*
X296555D03*
X304035Y1185531D03*
Y1178051D03*
X311515Y1174310D03*
X307775Y1178051D03*
X311515Y1181791D03*
X307775Y1185531D03*
X311515Y1189271D03*
X304035Y1174310D03*
Y1181791D03*
Y1189271D03*
X307775Y1174310D03*
Y1181791D03*
Y1189271D03*
X311515Y1178051D03*
Y1185531D03*
X294685Y1194881D03*
Y1202362D03*
X304035Y1193011D03*
X302165Y1198621D03*
X298425Y1202362D03*
Y1194881D03*
X307775Y1193011D03*
X305905Y1198621D03*
X309645Y1202362D03*
X302165Y1101377D03*
X298425Y1097637D03*
X302165Y1105117D03*
X305904Y1108857D03*
X309645Y1105117D03*
Y1101377D03*
X309644Y1108858D03*
X305905Y1097637D03*
X302165Y1116338D03*
X298425Y1108858D03*
X302165D03*
X298425Y1112598D03*
X313385Y1116338D03*
X309645Y1112598D03*
Y1116338D03*
Y1120078D03*
X305905Y1116338D03*
X298425Y1120078D03*
X309645Y1127558D03*
Y1131299D03*
X307775Y1140649D03*
X304035D03*
X305905Y1131299D03*
Y1123818D03*
X300295Y1140649D03*
X298425Y1135039D03*
X294685D03*
X302165Y1131299D03*
X298425Y1127558D03*
X298424Y1090157D03*
X294684Y1082677D03*
X302164D03*
X298426Y1078936D03*
X294684Y1090157D03*
X294685Y1086417D03*
X302164Y1090157D03*
X302165Y1086417D03*
X298425Y1093897D03*
X305904Y1090157D03*
X309644Y1082677D03*
X305906Y1078936D03*
X309645Y1086417D03*
X309644Y1090157D03*
X305905Y1093897D03*
X294684Y1071455D03*
X309645D03*
X302165D03*
X298425Y1075196D03*
X305906D03*
X279724Y1239763D03*
X283464Y1250984D03*
X287204Y1247243D03*
Y1243503D03*
X279724Y1247243D03*
X287204Y1239763D03*
X294685D03*
X290944Y1250984D03*
Y1247243D03*
Y1243503D03*
X279724Y1258465D03*
X287204D03*
X283464Y1254724D03*
X290944D03*
X294685Y1217322D03*
X281594Y1211712D03*
X285334Y1207972D03*
Y1215452D03*
Y1211712D03*
X281594Y1215452D03*
X279724Y1224803D03*
X283464Y1239763D03*
X290944Y1232283D03*
Y1236023D03*
Y1239763D03*
X283464Y1232283D03*
X287204Y1228543D03*
X283464Y1236023D03*
X287204Y1224803D03*
X281594Y1140649D03*
Y1136909D03*
X285334Y1140649D03*
Y1136909D03*
X281594Y1148129D03*
Y1155610D03*
Y1151869D03*
X285334D03*
X289074D03*
Y1155610D03*
Y1144389D03*
X292814Y1151869D03*
Y1144389D03*
X285334Y1155610D03*
X281594Y1144389D03*
X285334Y1148129D03*
Y1144389D03*
X289074Y1148129D03*
X292815D03*
Y1155610D03*
X281594Y1159350D03*
X289074Y1166830D03*
Y1170570D03*
Y1159350D03*
X281594Y1170570D03*
Y1166830D03*
X292814Y1159350D03*
Y1166830D03*
X285334Y1170570D03*
Y1166830D03*
Y1159350D03*
X292815Y1170570D03*
X292814Y1181791D03*
X285334Y1185531D03*
X289074Y1174310D03*
Y1178051D03*
Y1185531D03*
X281594Y1189271D03*
Y1185531D03*
X285334Y1181791D03*
X281594Y1178051D03*
Y1174310D03*
X292814D03*
X285334D03*
Y1189271D03*
X281594Y1181791D03*
X285334Y1178051D03*
X289074Y1181791D03*
X281594Y1196751D03*
Y1204232D03*
Y1193011D03*
X285334D03*
Y1196751D03*
Y1200491D03*
Y1204232D03*
X281594Y1200491D03*
X287204Y1090157D03*
X290944Y1078936D03*
X279724Y1082677D03*
X287204D03*
Y1086417D03*
X279724D03*
X283464Y1078936D03*
Y1090157D03*
X290943D03*
X290944Y1075196D03*
Y1093897D03*
X283464D03*
X287204Y1101377D03*
X283464Y1097637D03*
X287204Y1105117D03*
X290944Y1097637D03*
X294684Y1101377D03*
X294685Y1105117D03*
X294684Y1120078D03*
Y1112598D03*
X285334Y1118208D03*
X281594D03*
X285334Y1114468D03*
X281594D03*
X279723Y1071455D03*
X287203D03*
X283464Y1075196D03*
X272244Y1224803D03*
X268503Y1236023D03*
Y1232283D03*
X272244Y1228543D03*
X264763Y1224803D03*
X268503Y1239763D03*
X275984D03*
X272244Y1243503D03*
Y1247243D03*
X264763Y1239763D03*
Y1247243D03*
X268503Y1250984D03*
X264763Y1243503D03*
X272244Y1239763D03*
X275984Y1250984D03*
X279724Y1243503D03*
X264763Y1258465D03*
X272244D03*
X268503Y1254724D03*
X275984D03*
X266633Y1181791D03*
X270373Y1189271D03*
X277854Y1178051D03*
Y1189271D03*
Y1185531D03*
X270373Y1174310D03*
X277854D03*
X266633Y1185531D03*
Y1178051D03*
X270373Y1181791D03*
X274114Y1189271D03*
Y1185531D03*
Y1178051D03*
Y1204232D03*
Y1196751D03*
X270393Y1196732D03*
X270373Y1204232D03*
X266633D03*
X270373Y1200491D03*
X266633Y1196751D03*
X270373Y1193011D03*
X277854D03*
X266633D03*
Y1200491D03*
X274114D03*
Y1193011D03*
X277854Y1200491D03*
Y1196751D03*
Y1204232D03*
X274114Y1207972D03*
X270373Y1211712D03*
X266633Y1207972D03*
Y1211712D03*
X264763Y1221062D03*
X270373Y1207972D03*
X277854Y1211712D03*
X274114Y1215452D03*
X277854D03*
X266633D03*
X274114Y1211712D03*
X277854Y1207972D03*
X275984Y1232283D03*
Y1236023D03*
X268503Y1093897D03*
Y1097637D03*
X272244Y1101377D03*
Y1105117D03*
X279724Y1101377D03*
X275984Y1097637D03*
X279724Y1105117D03*
X274114Y1118208D03*
Y1121948D03*
X270373Y1118208D03*
X266633Y1121948D03*
X270373D03*
X277854Y1118208D03*
Y1121948D03*
X270373Y1114468D03*
X274114D03*
X277854D03*
Y1129429D03*
X274114Y1125688D03*
X270373Y1136909D03*
X266633Y1133169D03*
X270373D03*
X266633Y1140649D03*
X270373Y1125688D03*
Y1129429D03*
X266633Y1125688D03*
X270373Y1140649D03*
X277854Y1136909D03*
Y1133169D03*
Y1140649D03*
Y1125688D03*
X266633Y1136909D03*
Y1129429D03*
X274114D03*
Y1136909D03*
Y1140649D03*
Y1155610D03*
Y1151869D03*
Y1148129D03*
X266633D03*
X270373Y1144389D03*
Y1148129D03*
Y1151869D03*
X277854Y1144389D03*
Y1148129D03*
Y1151870D03*
X270373Y1155610D03*
X277854D03*
X266633Y1151869D03*
Y1144389D03*
X274114D03*
Y1166830D03*
Y1159350D03*
Y1170570D03*
X277854Y1159350D03*
Y1166830D03*
Y1170570D03*
X266633D03*
X270373D03*
X266633Y1159350D03*
X270373D03*
Y1166830D03*
X266633D03*
X277854Y1181791D03*
X274114D03*
Y1174310D03*
X266633Y1189271D03*
X270373Y1178051D03*
Y1185531D03*
X264762Y1071455D03*
X272243D03*
X268503Y1075196D03*
X279724Y1090157D03*
X275984Y1075196D03*
Y1093897D03*
Y1078936D03*
X272244Y1082677D03*
X275984Y1090157D03*
X272244Y1086417D03*
X264763Y1082677D03*
X268503Y1078936D03*
Y1090157D03*
X264763Y1086417D03*
X272244Y1090157D03*
X249803Y1243503D03*
X253543Y1250984D03*
Y1254724D03*
X249803Y1247243D03*
X246062Y1254724D03*
X253543Y1239763D03*
X249803D03*
X257283Y1243503D03*
Y1247243D03*
X261023Y1250984D03*
Y1239763D03*
X249803Y1258465D03*
X257283D03*
X261023Y1254724D03*
X249803Y1228543D03*
X257283D03*
X249803Y1224803D03*
X246062Y1232283D03*
Y1236023D03*
X253543D03*
X246062Y1239763D03*
X264763Y1228543D03*
X257283Y1239763D03*
Y1224803D03*
X261023Y1236023D03*
X253543Y1232283D03*
X261023D03*
X251673Y1144389D03*
X247933D03*
X255413D03*
X262893Y1166830D03*
X251673Y1170570D03*
X255413Y1166830D03*
X247933D03*
X251673Y1159350D03*
X259153D03*
Y1170570D03*
X262893D03*
Y1159350D03*
X247933Y1181791D03*
X251673D03*
X255413D03*
X247933Y1189271D03*
X251673D03*
X255413D03*
X262893D03*
Y1174310D03*
X259153Y1181791D03*
X262893D03*
X259153Y1189271D03*
X255413Y1174310D03*
X247933D03*
Y1185531D03*
X255413D03*
X251673D03*
X259153D03*
X262893D03*
X251673Y1178051D03*
X247933D03*
X255413D03*
X259153D03*
X262893D03*
X247933Y1204232D03*
X255413D03*
X251673D03*
X247933Y1196751D03*
X251673D03*
X255413D03*
X259153Y1204232D03*
X262893D03*
X259153Y1196751D03*
X262893D03*
X251673Y1193011D03*
X255413D03*
X247933D03*
X262893D03*
X259153D03*
Y1200491D03*
X262893D03*
X251673D03*
X247933D03*
X255413D03*
X247933Y1207972D03*
X251673D03*
X255413Y1211712D03*
Y1207972D03*
X249803Y1221062D03*
X246062D03*
X253543D03*
X262893Y1207972D03*
X259153D03*
X262893Y1211712D03*
X259153D03*
X261023Y1221062D03*
X257283D03*
X255413Y1215452D03*
X262893D03*
X247932Y1215451D03*
X259153Y1215452D03*
X251673D03*
X247932Y1211711D03*
X251673D03*
X249803Y1105117D03*
Y1101377D03*
X246062Y1097637D03*
X253543Y1093897D03*
X257283Y1101377D03*
X253543Y1097637D03*
X257283Y1105117D03*
X261023Y1093897D03*
Y1097637D03*
X264763Y1101377D03*
Y1105117D03*
X255413Y1121948D03*
X251673D03*
X247933D03*
X262893D03*
X259153D03*
X262893Y1118208D03*
X259153Y1114468D03*
X262893D03*
X255413Y1118208D03*
Y1114468D03*
X247933D03*
X259153Y1118208D03*
X251673Y1114468D03*
X247933Y1118208D03*
X251673D03*
X247933Y1133169D03*
X251673D03*
X255413D03*
X247933Y1140649D03*
X251673D03*
X255413D03*
X247933Y1125688D03*
X251673D03*
X255413D03*
X259153Y1133169D03*
X262893D03*
Y1140649D03*
X259153Y1125688D03*
X262893D03*
X259153Y1140649D03*
X255413Y1136909D03*
X251673D03*
X247933D03*
X259153D03*
X262893D03*
X247933Y1129429D03*
X259153D03*
X262893D03*
X255413D03*
X251673D03*
X259153Y1148129D03*
X262893D03*
Y1155610D03*
X247933Y1148129D03*
X251673D03*
X255413D03*
X247933Y1155610D03*
X255413D03*
X259153Y1151869D03*
X262893D03*
X247933D03*
X255413D03*
X251673D03*
X262893Y1144389D03*
X259153D03*
X253543Y1090157D03*
X246062D03*
X249803Y1082677D03*
X246062Y1078936D03*
X249803Y1090157D03*
Y1086417D03*
X253543Y1078936D03*
X246062Y1093897D03*
X257283Y1090157D03*
X264763D03*
X257283Y1082677D03*
Y1086417D03*
X261023Y1090157D03*
Y1078936D03*
X253543Y1075196D03*
X261023D03*
X249802Y1071455D03*
X257282D03*
X246062Y1075196D03*
X238582Y1254724D03*
X234842Y1258465D03*
X242322D03*
X236712Y1200491D03*
X244192D03*
X240452Y1207972D03*
Y1211712D03*
X242322Y1221062D03*
X244192Y1211712D03*
Y1207972D03*
X236712D03*
Y1211712D03*
X238582Y1232283D03*
X234842Y1228543D03*
Y1224803D03*
X238582Y1236023D03*
Y1239763D03*
X242322Y1228543D03*
Y1224803D03*
X234842Y1239763D03*
X238582Y1250984D03*
X234842Y1243503D03*
Y1247243D03*
X242322Y1243503D03*
Y1239763D03*
Y1247243D03*
X246062Y1250984D03*
X242322Y1105117D03*
X234842Y1101377D03*
X238582Y1097637D03*
Y1093897D03*
X242322Y1101377D03*
X234842Y1105117D03*
X236712Y1121948D03*
X240452D03*
X244192D03*
X240452Y1114468D03*
X244192D03*
X236712Y1118208D03*
X244192D03*
X236712Y1114468D03*
X240452Y1118208D03*
X236712Y1133464D03*
X240452Y1133169D03*
X236712Y1140649D03*
X240452D03*
X236712Y1125688D03*
X240452D03*
X244192Y1133169D03*
Y1140649D03*
Y1125688D03*
X240452Y1136909D03*
X236712D03*
X244192D03*
Y1129429D03*
X240452D03*
X236712D03*
Y1148129D03*
X240452D03*
X244192D03*
X240452Y1155610D03*
Y1151869D03*
X236712D03*
X244192D03*
X240452Y1144389D03*
X236712D03*
X244192D03*
X240452Y1166830D03*
X236712Y1170570D03*
Y1159350D03*
X244192Y1170570D03*
Y1159350D03*
X240452Y1181791D03*
X236712D03*
Y1189271D03*
X240452D03*
X244192Y1181791D03*
Y1189271D03*
X240452Y1174310D03*
Y1185531D03*
X236712D03*
X244192D03*
X240452Y1178051D03*
X236712D03*
X244192D03*
X240452Y1204232D03*
X236712D03*
Y1196751D03*
X240452D03*
X244192Y1204232D03*
Y1196751D03*
X240452Y1193011D03*
X236712D03*
X244192D03*
X240452Y1200491D03*
X234841Y1071454D03*
X242321Y1071455D03*
X238582Y1075196D03*
Y1078936D03*
Y1090157D03*
X242322Y1082677D03*
Y1086417D03*
X234842Y1082677D03*
Y1086417D03*
X242322Y1090157D03*
X218011Y1114468D03*
X225492Y1133169D03*
Y1140649D03*
Y1125688D03*
X218011Y1140649D03*
X221751D03*
X218011Y1125688D03*
X221751D03*
Y1133169D03*
X218011D03*
X229330Y1132677D03*
X229232Y1140649D03*
Y1125688D03*
X225492Y1136909D03*
X221751D03*
X218011D03*
X229232D03*
Y1129429D03*
X218011D03*
X221751D03*
X225492D03*
Y1148129D03*
X221751D03*
X218011D03*
X229232D03*
X221751Y1155610D03*
X229232D03*
X225492Y1144389D03*
X221751D03*
X218011D03*
X229232D03*
Y1151870D03*
X221752D03*
X218011D03*
X225492D03*
Y1170570D03*
Y1159350D03*
X218011Y1170570D03*
X221752Y1166830D03*
X218011Y1159350D03*
X229232Y1166830D03*
X225492Y1181791D03*
Y1189271D03*
X221751Y1181791D03*
X218011D03*
X221751Y1189271D03*
X218011D03*
X229232Y1181791D03*
Y1189271D03*
X221751Y1174310D03*
X229232D03*
X225492Y1185531D03*
X218011D03*
X221751D03*
X229232D03*
X225492Y1178051D03*
X221751D03*
X218011D03*
X229232D03*
X218011Y1204232D03*
X229232Y1196751D03*
Y1204232D03*
X225492Y1196751D03*
Y1204232D03*
X221751D03*
Y1196751D03*
X218011D03*
Y1193011D03*
X221751D03*
X225492D03*
X229232D03*
X218011Y1200491D03*
X221751D03*
X225492D03*
X229232D03*
X225492Y1207972D03*
X218011Y1211712D03*
X221751Y1207972D03*
X218011D03*
X229232D03*
Y1211712D03*
Y1215452D03*
X225492Y1211712D03*
X221752D03*
X227362Y1086417D03*
Y1082677D03*
Y1090157D03*
X223622D03*
X219881Y1086417D03*
Y1082677D03*
Y1090157D03*
X223622Y1078936D03*
Y1093897D03*
X231102Y1090157D03*
Y1078936D03*
Y1093897D03*
Y1097637D03*
X227362Y1101377D03*
Y1105117D03*
X219881Y1101377D03*
Y1105117D03*
X223622Y1097637D03*
X225492Y1118208D03*
Y1121948D03*
X218011Y1118208D03*
X221751D03*
X218011Y1121948D03*
X221751D03*
X229232D03*
Y1118208D03*
Y1114468D03*
X225492D03*
X221752D03*
X219880Y1071455D03*
X227361D03*
X223622Y1075196D03*
X231102D03*
X214271Y1215452D03*
X199311Y1129429D03*
X206791D03*
X203051Y1148129D03*
X199311D03*
X206791D03*
X214271D03*
X210531D03*
X199311Y1155610D03*
X206791D03*
X214271D03*
X206791Y1144389D03*
X203051D03*
X199311D03*
X214271D03*
X210531D03*
X214271Y1151870D03*
X210531D03*
X206791D03*
X203051D03*
X199311D03*
X206791Y1166830D03*
X203051Y1159350D03*
X199311Y1166830D03*
X203051Y1170570D03*
X214271Y1166830D03*
X210531Y1159350D03*
Y1170570D03*
X206791Y1181791D03*
X203051D03*
X199311D03*
X206791Y1189271D03*
X203051D03*
X199311D03*
X214271Y1181791D03*
X210531D03*
X214271Y1189271D03*
X210531D03*
X199311Y1174310D03*
X206791D03*
X214271D03*
X203051Y1185531D03*
X199311D03*
X206791D03*
X214271D03*
X210531D03*
X206791Y1178051D03*
X203051D03*
X199311D03*
X214271D03*
X210531D03*
X206791Y1196751D03*
X203051D03*
X199311D03*
Y1204232D03*
X203051D03*
X206791D03*
X214271Y1196751D03*
X210531D03*
Y1204232D03*
X214271D03*
Y1193011D03*
X210531D03*
X199311D03*
X203051D03*
X206791D03*
X214271Y1200491D03*
X210531D03*
X199311D03*
X206791D03*
X203051D03*
X206791Y1207972D03*
X203051D03*
X210531D03*
X214271D03*
Y1211712D03*
X204921Y1101377D03*
X208661Y1097637D03*
X201181D03*
X204921Y1105117D03*
X212401Y1101377D03*
Y1105117D03*
X216141Y1097637D03*
X199311Y1118208D03*
Y1121948D03*
X206791Y1118208D03*
X203051D03*
Y1121948D03*
X206791D03*
X210531Y1118208D03*
X214271Y1114468D03*
X210531Y1121948D03*
X214271Y1118208D03*
Y1121948D03*
X203051Y1114468D03*
X199311D03*
X206791D03*
X210531D03*
X199311Y1140649D03*
X203051D03*
X206791D03*
X199311Y1125688D03*
X203051D03*
X206791D03*
Y1133169D03*
X203051D03*
X199311D03*
X210531D03*
Y1140649D03*
X214271D03*
Y1125688D03*
X210531D03*
X214271Y1133169D03*
X206791Y1136909D03*
X203051D03*
X199311D03*
X214271D03*
X210531D03*
X214271Y1129429D03*
X210531D03*
X203051D03*
X201181Y1075196D03*
X208661D03*
X216141D03*
X204920Y1071455D03*
X212400D03*
X208661Y1078936D03*
X204921Y1090157D03*
X201181Y1093897D03*
X208661D03*
X216141Y1090157D03*
X212401Y1086417D03*
Y1082677D03*
X216141Y1078936D03*
X212401Y1090157D03*
X216141Y1093897D03*
X208661Y1090157D03*
X201181D03*
X204921Y1086417D03*
Y1082677D03*
X201181Y1078936D03*
X195570Y1121948D03*
Y1114468D03*
Y1133169D03*
Y1129429D03*
Y1125688D03*
Y1136909D03*
Y1140649D03*
Y1151869D03*
Y1144389D03*
Y1159350D03*
Y1170570D03*
Y1189271D03*
Y1185531D03*
Y1178051D03*
Y1200491D03*
Y1196751D03*
Y1193011D03*
Y1204232D03*
X197440Y1086417D03*
Y1082677D03*
Y1090157D03*
Y1101377D03*
Y1105117D03*
X195570Y1118208D03*
X197439Y1071455D03*
X261023Y1108858D03*
X281594Y1207972D03*
X197440Y1108858D03*
X204921D03*
X270374Y1215452D03*
X201181Y1108858D03*
X272244Y1221062D03*
X279724Y1228543D03*
X290944Y1120078D03*
X320866Y1254724D03*
X290944Y1116338D03*
X328347Y1228543D03*
X324606Y1078936D03*
X290944Y1112598D03*
X253543Y1108858D03*
X249803D03*
X238582Y1221062D03*
X234842D03*
X290944Y1217322D03*
Y1213582D03*
Y1209842D03*
Y1206102D03*
Y1202362D03*
Y1198621D03*
Y1194881D03*
X294685Y1108858D03*
X290944D03*
X287204D03*
X283464D03*
X279724D03*
X275984D03*
X242322D03*
X231102Y1221062D03*
X246062Y1108858D03*
X290944Y1135039D03*
Y1131299D03*
Y1127558D03*
Y1123818D03*
X268503Y1221062D03*
X275984D03*
X238582Y1108858D03*
X234842D03*
X279724Y1221062D03*
X283464D03*
X287204D03*
X231102Y1108858D03*
X290944Y1221062D03*
X227362Y1108858D03*
X223622D03*
X219881D03*
X264763D03*
X268503D03*
X272244D03*
X208661D03*
X723720Y1148129D03*
X719980D03*
Y1155610D03*
Y1151869D03*
X723720D03*
Y1144389D03*
X719980D03*
Y1166830D03*
Y1159350D03*
X723720D03*
Y1166830D03*
X719980Y1170570D03*
X723720D03*
X716240Y1148129D03*
X712500D03*
X708760D03*
X705020D03*
X712500Y1155610D03*
X705020D03*
X716240Y1151869D03*
X708760D03*
X712500D03*
X705020D03*
X712500Y1144389D03*
X705020D03*
X708760D03*
X716240D03*
Y1170570D03*
Y1159350D03*
X708760D03*
X705020Y1166830D03*
X712500D03*
X708760Y1170570D03*
X697539Y1148129D03*
X701279D03*
X693799D03*
X697539Y1155610D03*
X701279Y1151869D03*
X697539D03*
X693799D03*
X701279Y1144389D03*
X697539D03*
X693799D03*
X697539Y1166830D03*
X693799Y1170570D03*
Y1159350D03*
X701279D03*
Y1170570D03*
X678839Y1151870D03*
X675098D03*
X671358D03*
X682579D03*
Y1170570D03*
Y1159350D03*
X675098Y1170570D03*
X678839Y1166830D03*
X671358D03*
X675098Y1159350D03*
X686319Y1166830D03*
Y1148129D03*
X682579D03*
X678838D03*
X675098D03*
X671358D03*
X686319Y1155610D03*
X671358D03*
X678838D03*
X682579Y1144389D03*
X671358D03*
X678838D03*
X675098D03*
X686319D03*
Y1151870D03*
X667618Y1148129D03*
X660138D03*
X656398D03*
X663878D03*
X656398Y1155610D03*
X663878D03*
X667618Y1144389D03*
X663878D03*
X660138D03*
X656398D03*
X667618Y1151870D03*
X663878D03*
X660138D03*
X656398D03*
X663878Y1166830D03*
X660138Y1159350D03*
X656398Y1166830D03*
X660138Y1170570D03*
X667618Y1159350D03*
Y1170570D03*
X641437Y1211712D03*
Y1215452D03*
X648917D03*
X645177D03*
Y1136909D03*
X648917Y1140649D03*
X641437Y1136909D03*
X637697Y1155610D03*
Y1151870D03*
X645177Y1144389D03*
X637697D03*
Y1148129D03*
X645177Y1151870D03*
X648917Y1155610D03*
Y1148129D03*
X652657Y1151869D03*
Y1144389D03*
X641437D03*
Y1151870D03*
X645177Y1155610D03*
Y1148129D03*
Y1170570D03*
X637697Y1166830D03*
X645177Y1159350D03*
X637697D03*
Y1170570D03*
X648917Y1166830D03*
X652657Y1159350D03*
Y1170570D03*
X641437D03*
X645177Y1166830D03*
X641437Y1159350D03*
X645177Y1185531D03*
X637697Y1178051D03*
Y1174310D03*
X645177Y1178051D03*
X637697Y1181791D03*
X648917D03*
Y1174310D03*
X641437Y1185531D03*
Y1178051D03*
X645177Y1181791D03*
Y1174310D03*
Y1193011D03*
Y1196751D03*
Y1200491D03*
X641437D03*
Y1204232D03*
X645177D03*
X648917D03*
Y1196751D03*
Y1200491D03*
X641437Y1193011D03*
Y1196751D03*
X648917Y1193011D03*
X645177Y1211712D03*
X648917D03*
Y1207972D03*
X645177D03*
X641437D03*
X637697Y1136909D03*
X645177Y1140649D03*
X641437D03*
X637697D03*
X622736Y1174310D03*
X630216D03*
Y1178051D03*
X622736Y1178050D03*
X633957Y1174310D03*
Y1178051D03*
Y1181791D03*
Y1140649D03*
Y1136909D03*
X630216Y1140649D03*
X626476D03*
X622736D03*
X630216Y1136909D03*
X626476D03*
X630216Y1144389D03*
X626476D03*
X630216Y1148129D03*
Y1155610D03*
Y1151870D03*
X633957D03*
Y1148129D03*
Y1144389D03*
X626476Y1148129D03*
X622736Y1144389D03*
Y1148129D03*
X626476Y1151870D03*
X622736Y1155610D03*
Y1166830D03*
Y1170570D03*
X630216Y1159350D03*
Y1166830D03*
Y1170570D03*
X633957D03*
Y1166830D03*
Y1159350D03*
X626476D03*
X607776Y1136909D03*
X615256Y1140649D03*
X611516D03*
X607776D03*
X618996D03*
Y1144389D03*
Y1148129D03*
Y1151870D03*
Y1155610D03*
X607776Y1144389D03*
X615256Y1151869D03*
X611516D03*
X607776Y1148129D03*
Y1151870D03*
X615256Y1155610D03*
X611516D03*
X607776D03*
Y1159350D03*
X615256Y1166830D03*
X611516D03*
X607775D03*
X611516Y1170570D03*
X607775D03*
X618996Y1159350D03*
Y1174310D03*
Y1178051D03*
X607775Y1174310D03*
Y1178051D03*
X611516Y1174310D03*
X615256D03*
X604034D03*
X600295Y1140649D03*
X604035D03*
X600295Y1136909D03*
X604035D03*
X600295Y1144389D03*
Y1151870D03*
X604035Y1144389D03*
Y1151870D03*
Y1148129D03*
X600295D03*
Y1159350D03*
X604036Y1166830D03*
X604035Y1159350D03*
X635827Y1213582D03*
Y1209842D03*
Y1206102D03*
Y1202362D03*
Y1198621D03*
X624606Y1183661D03*
X598424Y1206103D03*
X602165Y1243503D03*
X613386Y1183661D03*
Y1239763D03*
X609646Y1243503D03*
Y1239763D03*
Y1247243D03*
X613386Y1254724D03*
Y1250984D03*
Y1198621D03*
X609646Y1191141D03*
X613386D03*
Y1221062D03*
X609646D03*
Y1213582D03*
X613386D03*
X617126Y1187401D03*
Y1202362D03*
X620866Y1206102D03*
X617126D03*
Y1194881D03*
Y1198621D03*
X620866D03*
X617126Y1191141D03*
X620866D03*
X617126Y1213582D03*
Y1209842D03*
X620866Y1213582D03*
X628346Y1187401D03*
X624606Y1191141D03*
X632086Y1202362D03*
X628346D03*
X624606Y1206102D03*
Y1198621D03*
X632086Y1194881D03*
X628346D03*
X624606Y1213582D03*
X632086Y1209842D03*
X628346D03*
X617126Y1217322D03*
X602165Y1250984D03*
X617126Y1183661D03*
X620866D03*
X609646D03*
X613386Y1206102D03*
X605905Y1224803D03*
Y1232283D03*
Y1236023D03*
Y1243503D03*
Y1254724D03*
Y1250984D03*
X609646Y1224803D03*
Y1228543D03*
X613386Y1232283D03*
Y1236023D03*
X605905Y1183661D03*
X602165D03*
Y1187401D03*
X605905D03*
X602165Y1202362D03*
X605905D03*
X602165Y1194881D03*
X605905D03*
Y1217322D03*
X602165D03*
X605905Y1209842D03*
X602165D03*
Y1224803D03*
Y1236023D03*
Y1232283D03*
X609646Y1206102D03*
Y1198621D03*
X598424Y1213583D03*
Y1228542D03*
X598423Y1239762D03*
X598424Y1221063D03*
X598423Y1247242D03*
X598424Y1198622D03*
Y1191142D03*
X609646Y1258465D03*
X645177Y1114468D03*
X641437D03*
X622736Y1077066D03*
X626476Y1084547D03*
X622736Y1092027D03*
X626476Y1080807D03*
X622736Y1095767D03*
X626476Y1103247D03*
X622736Y1118208D03*
X626476Y1114468D03*
X622736Y1110728D03*
X630216Y1114468D03*
X622736Y1073326D03*
X607776Y1095767D03*
X615256D03*
X618996Y1103247D03*
X611516D03*
X618996Y1099507D03*
X611516D03*
X618996Y1118208D03*
Y1121948D03*
X611516Y1118208D03*
X607776D03*
X611516Y1110728D03*
X618996D03*
X607776D03*
X611516Y1125688D03*
X607776D03*
X615256Y1073326D03*
X607776D03*
X618996Y1084547D03*
Y1080807D03*
X615256Y1077066D03*
X611516Y1080807D03*
Y1084547D03*
X607776Y1092027D03*
X615256D03*
X600295Y1088287D03*
X604035D03*
X600295Y1099507D03*
X604035D03*
X600295Y1106988D03*
X604035D03*
Y1121948D03*
X600295D03*
Y1114468D03*
X604035D03*
X1098523Y1215452D03*
X1102263D03*
X662008Y1101377D03*
X665748Y1093897D03*
X658268D03*
X744291Y1101377D03*
X740551Y1097637D03*
X688189D03*
X759251Y1082677D03*
X766731Y1090157D03*
X718110Y1108858D03*
X695669Y1093897D03*
X669488Y1090157D03*
Y1086417D03*
X665748Y1078936D03*
X669488Y1082677D03*
X751772Y1086417D03*
X748030Y1090157D03*
X751771D03*
X744291Y1082677D03*
X748031Y1078936D03*
X751771Y1082677D03*
X783503Y1193011D03*
X776083D03*
X779823D03*
X772342D03*
X783563Y1140649D03*
Y1155610D03*
Y1148129D03*
X776083D03*
Y1151869D03*
X772342D03*
X776083Y1155610D03*
X772342Y1144389D03*
X768602Y1151869D03*
Y1144389D03*
X776083D03*
X779823Y1155610D03*
Y1148129D03*
X772342D03*
Y1155610D03*
X783563Y1151870D03*
X779823D03*
Y1144389D03*
X783563D03*
X768602Y1155610D03*
Y1148129D03*
X783563Y1170570D03*
Y1166830D03*
X776083D03*
Y1170570D03*
X772342Y1166830D03*
X768602Y1159350D03*
X776083D03*
X772342D03*
X768602Y1166830D03*
X779823D03*
Y1170570D03*
Y1159350D03*
X772342Y1170570D03*
X768602D03*
X783563Y1159350D03*
X776083Y1174310D03*
X772342D03*
X776083Y1178051D03*
Y1181791D03*
Y1185531D03*
X772342Y1181791D03*
X779823Y1185531D03*
Y1178051D03*
X783563Y1185531D03*
Y1178051D03*
X768602Y1181791D03*
Y1174310D03*
X783563Y1189271D03*
X768602Y1185531D03*
X772342Y1178051D03*
X779823Y1189271D03*
X772342Y1185531D03*
X783563Y1174310D03*
X779823D03*
X783563Y1181791D03*
X768602Y1178051D03*
X779823Y1181791D03*
X776083Y1140649D03*
X779823D03*
X744291Y1090157D03*
Y1086417D03*
X753642Y1170570D03*
Y1181791D03*
Y1174310D03*
X757382D03*
Y1178051D03*
Y1181791D03*
X764862Y1185531D03*
Y1178051D03*
X761122D03*
Y1185531D03*
X764862Y1174310D03*
X761122Y1181791D03*
X764862D03*
X761122Y1174310D03*
X759252Y1191141D03*
X755512Y1194881D03*
X757382Y1140649D03*
X761122D03*
X764862D03*
Y1155610D03*
Y1148129D03*
X753642Y1144389D03*
X757382D03*
Y1148129D03*
Y1151869D03*
Y1155610D03*
X761122Y1148129D03*
Y1155610D03*
X753642Y1151869D03*
X761122Y1144389D03*
Y1151869D03*
X753642Y1155610D03*
X764862Y1151869D03*
Y1144389D03*
Y1159350D03*
Y1170570D03*
X757382Y1166830D03*
Y1170570D03*
X761122D03*
X753642Y1166830D03*
X757382Y1159350D03*
X753642D03*
X740551Y1078936D03*
Y1090157D03*
X738681Y1155610D03*
Y1148129D03*
X749901Y1144389D03*
Y1151869D03*
X742421Y1155610D03*
X746161Y1148129D03*
X738681Y1144389D03*
X742421Y1148129D03*
Y1144389D03*
X749902Y1155610D03*
Y1148129D03*
X738681Y1166830D03*
X746161Y1170570D03*
Y1166830D03*
X738681Y1159350D03*
X749901Y1166830D03*
Y1159350D03*
X738681Y1170570D03*
X746161Y1159350D03*
X742421D03*
Y1166830D03*
Y1170570D03*
X749902D03*
X749901Y1181791D03*
Y1174310D03*
X738681D03*
Y1178051D03*
X742421Y1181791D03*
X738681Y1185531D03*
Y1189271D03*
X746161Y1185531D03*
Y1178051D03*
Y1174310D03*
X742421Y1185531D03*
Y1189271D03*
Y1174310D03*
X738681Y1181791D03*
X746161D03*
X742421Y1178051D03*
X738681Y1204232D03*
X751772Y1194881D03*
X748031D03*
X738681Y1193011D03*
Y1196751D03*
X742421Y1193011D03*
Y1196751D03*
Y1200491D03*
X738681D03*
X742421Y1204232D03*
X738681Y1211712D03*
X742421D03*
Y1215452D03*
Y1207972D03*
X738681Y1215452D03*
Y1118208D03*
X742421D03*
X738681Y1114468D03*
X742421D03*
X738681Y1136909D03*
Y1140649D03*
X742421D03*
Y1136909D03*
X746161Y1144389D03*
Y1155610D03*
Y1151869D03*
X742421D03*
X738681D03*
X727460Y1181791D03*
X719980Y1185531D03*
X723720D03*
X731201Y1189271D03*
Y1185531D03*
Y1178051D03*
X719980Y1204232D03*
X727460D03*
X727480Y1196732D03*
X731201Y1196751D03*
Y1204232D03*
X734941Y1193011D03*
X727460D03*
X723720Y1196751D03*
X719980D03*
X727460Y1200491D03*
X723720Y1204232D03*
X719980Y1200491D03*
X723720D03*
X731201D03*
Y1193011D03*
X734941Y1200491D03*
Y1204232D03*
Y1196751D03*
Y1211712D03*
X727460Y1207972D03*
X723720Y1211712D03*
Y1207972D03*
X719980Y1211712D03*
Y1207972D03*
X727460Y1211712D03*
X731201Y1207972D03*
Y1215452D03*
X734941D03*
X723720D03*
X719980D03*
X731201Y1211712D03*
X734941Y1207972D03*
Y1121948D03*
Y1118208D03*
X727460Y1121948D03*
X719980D03*
X723720D03*
X727460Y1118208D03*
X731201Y1121948D03*
Y1118208D03*
Y1114468D03*
X734941D03*
X727460D03*
X719980Y1118208D03*
Y1114468D03*
X734941Y1129429D03*
Y1125688D03*
Y1140649D03*
Y1133169D03*
Y1136909D03*
X723720Y1125688D03*
X719980D03*
X727460Y1129429D03*
Y1125688D03*
Y1133169D03*
X723720D03*
X719980D03*
X727460Y1136909D03*
X731201Y1125688D03*
X719980Y1129429D03*
X723720D03*
X731201D03*
Y1136909D03*
X734941Y1151870D03*
Y1148129D03*
Y1144389D03*
X727460Y1185531D03*
X734941Y1181791D03*
Y1185531D03*
Y1189271D03*
Y1178051D03*
X727460Y1189271D03*
X723720Y1181791D03*
X719980D03*
X723720Y1189271D03*
X719980D03*
X731201Y1181791D03*
X751771Y1101377D03*
X716240Y1215452D03*
X708760D03*
X712500D03*
X705019Y1215451D03*
Y1211711D03*
X708760D03*
X705020Y1114468D03*
X712500D03*
X716240D03*
X705020Y1118208D03*
X712500D03*
X708760D03*
X716240Y1125688D03*
Y1133169D03*
X712500Y1125688D03*
X708760D03*
X705020D03*
X712500Y1133169D03*
X708760D03*
X705020D03*
Y1129429D03*
X708760D03*
X712500D03*
X716240D03*
Y1189271D03*
Y1181791D03*
X712500Y1189271D03*
X708760D03*
X705020D03*
X712500Y1181791D03*
X708760D03*
X705020D03*
X716240Y1185531D03*
X708760D03*
X712500D03*
X705020D03*
X716240Y1196751D03*
Y1204232D03*
X712500Y1196751D03*
X708760D03*
X705020D03*
X708760Y1204232D03*
X712500D03*
X705020D03*
X712500Y1200491D03*
X705020D03*
X708760D03*
X716240D03*
Y1211712D03*
Y1207972D03*
X712500D03*
Y1211712D03*
X708760Y1207972D03*
X705020D03*
X716240Y1121948D03*
X705020D03*
X708760D03*
X712500D03*
X708760Y1114468D03*
X716240Y1118208D03*
X748031Y1093897D03*
Y1097637D03*
X693799Y1121948D03*
X697539D03*
X701279D03*
X693799Y1114468D03*
Y1118208D03*
X701279Y1114468D03*
X697539Y1118208D03*
Y1114468D03*
X701279Y1118208D03*
X693799Y1133464D03*
X697539Y1133169D03*
X686417Y1132677D03*
X693799Y1125688D03*
X697539D03*
X701279D03*
Y1133169D03*
Y1129429D03*
X697539D03*
X693799D03*
Y1181791D03*
Y1189271D03*
X697539D03*
X701279D03*
Y1181791D03*
X697539D03*
X701279Y1185531D03*
X697539D03*
X693799D03*
X697539Y1204232D03*
X693799D03*
Y1196751D03*
X697539D03*
X701279D03*
Y1204232D03*
Y1200491D03*
X697539D03*
X693799D03*
Y1207972D03*
X697539D03*
Y1211712D03*
X701279Y1207972D03*
Y1211712D03*
X693799D03*
X740551Y1093897D03*
X751772Y1105117D03*
X675098Y1181791D03*
X671358D03*
X678838Y1189271D03*
X675098D03*
X671358D03*
X686319Y1181791D03*
Y1189271D03*
X682579Y1181791D03*
Y1189271D03*
X678838Y1181791D03*
X686319Y1185531D03*
X682579D03*
X675098D03*
X671358D03*
X678838D03*
X682579Y1196751D03*
Y1204232D03*
X678838D03*
Y1196751D03*
X675098D03*
X671358D03*
Y1204232D03*
X675098D03*
X686319Y1196751D03*
Y1204232D03*
Y1200491D03*
X675098D03*
X671358D03*
X678838D03*
X682579D03*
Y1207972D03*
X675098Y1211712D03*
X678838Y1207972D03*
X675098D03*
X671358D03*
X686319D03*
Y1211712D03*
Y1215452D03*
X682579Y1211712D03*
X678839D03*
Y1215452D03*
X671358Y1211712D03*
Y1215452D03*
X675098D03*
X682579Y1118208D03*
Y1121948D03*
X671358Y1114468D03*
Y1118208D03*
X675098D03*
X678838D03*
X675098Y1121948D03*
X678838D03*
X671358D03*
X686319D03*
Y1118208D03*
Y1114468D03*
X682579D03*
X678839D03*
X675098D03*
X682579Y1133169D03*
Y1125688D03*
X675098D03*
X671358D03*
X678838D03*
Y1133169D03*
X675098D03*
X671358D03*
X686319Y1125688D03*
Y1129429D03*
X675098D03*
X671358D03*
X678838D03*
X682579D03*
X744291Y1105117D03*
X663878Y1181791D03*
X660138D03*
X656398D03*
X663878Y1189271D03*
X660138D03*
X656398D03*
X667618Y1181791D03*
Y1189271D03*
Y1185531D03*
X660138D03*
X656398D03*
X663878D03*
Y1196751D03*
X660138D03*
X656398D03*
Y1204232D03*
X660138D03*
X663878D03*
X667618Y1196751D03*
Y1204232D03*
Y1200491D03*
X656398D03*
X663878D03*
X660138D03*
X663878Y1207972D03*
X660138D03*
X656398D03*
X667618D03*
Y1211712D03*
X663878D03*
X656398D03*
X660138Y1215452D03*
X656398D03*
X663878D03*
X667618D03*
X660138Y1211712D03*
X656398Y1118208D03*
Y1121948D03*
X663878Y1118208D03*
X660138D03*
Y1121948D03*
X663878D03*
X667618Y1118208D03*
Y1121948D03*
X660138Y1114468D03*
X656398D03*
X663878D03*
X667618D03*
X656398Y1125688D03*
X660138D03*
X663878D03*
Y1133169D03*
X660138D03*
X656398D03*
X667618D03*
Y1125688D03*
Y1129429D03*
X660138D03*
X656398D03*
X663878D03*
X652657Y1118208D03*
Y1121948D03*
Y1114468D03*
Y1133169D03*
Y1129429D03*
Y1125688D03*
X755512Y1075196D03*
X762993D03*
X759251Y1090157D03*
X762991D03*
X680709D03*
X676968Y1105117D03*
X684449Y1101377D03*
Y1105117D03*
X688189Y1093897D03*
X759252Y1086417D03*
X729331Y1101377D03*
X748031Y1120078D03*
X676968Y1090157D03*
X785434Y1198621D03*
X755511Y1090157D03*
X725590Y1097637D03*
X703149Y1108858D03*
X665748Y1090157D03*
X738681Y1207972D03*
X699409Y1105117D03*
X688189Y1108858D03*
X710630D03*
X748031Y1135039D03*
X684449Y1108858D03*
X744291D03*
X740551D03*
X691929D03*
X748031Y1131299D03*
Y1127558D03*
X721850Y1108858D03*
X654527D03*
X658268D03*
X662008D03*
X665748D03*
X669488D03*
X673228D03*
X676968D03*
X680709D03*
X772342Y1189271D03*
X727461Y1215452D03*
X695669Y1108858D03*
X721850Y1101377D03*
X762992Y1116338D03*
X766732Y1120078D03*
X770472Y1097637D03*
X748031Y1116338D03*
X736811Y1108858D03*
X766732Y1086417D03*
X706889Y1071455D03*
X721849D03*
X759252D03*
X721850Y1105117D03*
X777953Y1093897D03*
X774212Y1101377D03*
X777953Y1105117D03*
X691929Y1101377D03*
X762992Y1131299D03*
X766732D03*
X774213Y1105117D03*
X762991Y1108857D03*
X766731Y1108858D03*
X777953Y1075196D03*
X766732Y1116338D03*
Y1123818D03*
X762992D03*
X654527Y1082677D03*
Y1086417D03*
Y1090157D03*
X770472Y1093897D03*
X654527Y1105117D03*
Y1101377D03*
X781693Y1093897D03*
Y1097637D03*
X777953D03*
X774212Y1090157D03*
X781693Y1105117D03*
X777953Y1078936D03*
X766732Y1135039D03*
Y1112598D03*
X781693Y1078936D03*
X680709Y1075196D03*
Y1093897D03*
X762992Y1097637D03*
X770473Y1078936D03*
X688189D03*
X774213Y1086417D03*
X762992Y1093897D03*
X759252Y1105117D03*
X684449Y1090157D03*
X688189D03*
X762993Y1078936D03*
X766732Y1105117D03*
X774212Y1082677D03*
X725590Y1093897D03*
X684449Y1082677D03*
X755512Y1097637D03*
X770473Y1075196D03*
X684449Y1086417D03*
X688189Y1075196D03*
X673228D03*
X759252Y1101377D03*
X766732D03*
X766731Y1082677D03*
X755513Y1078936D03*
X770471Y1090157D03*
X781693Y1086417D03*
X777953D03*
X755512Y1093897D03*
X781693Y1112598D03*
X770472Y1123818D03*
X676968Y1101377D03*
X680709Y1097637D03*
X658268Y1075196D03*
X777953Y1120078D03*
X665748Y1075196D03*
X781693Y1120078D03*
X766732Y1127558D03*
X774212Y1123818D03*
X740551Y1075196D03*
X662008Y1105117D03*
X729331D03*
X733071Y1093897D03*
X658268Y1090157D03*
X662008Y1082677D03*
Y1086417D03*
Y1090157D03*
X736811Y1105117D03*
X733071Y1097637D03*
X736811Y1101377D03*
X721850Y1082677D03*
X729331Y1086417D03*
Y1082677D03*
X736811Y1086417D03*
X725590Y1075196D03*
X706890Y1101377D03*
Y1105117D03*
X714370D03*
Y1101377D03*
X710630Y1097637D03*
Y1093897D03*
X718110Y1097637D03*
Y1093897D03*
X710630Y1078936D03*
X706890Y1082677D03*
Y1086417D03*
Y1090157D03*
X718110Y1078936D03*
X714370Y1082677D03*
Y1086417D03*
Y1090157D03*
X710630D03*
X718110D03*
X673228D03*
Y1078936D03*
X680709D03*
X699409Y1101377D03*
X676968Y1082677D03*
X703149Y1093897D03*
Y1097637D03*
X691929Y1082677D03*
Y1086417D03*
X695669Y1090157D03*
X699409D03*
Y1086417D03*
X691929Y1090157D03*
X695669Y1078936D03*
X703149D03*
X699409Y1082677D03*
X703149Y1090157D03*
X695669Y1075196D03*
X676968Y1086417D03*
X703149Y1075196D03*
X695669Y1097637D03*
X691929Y1105117D03*
X718110Y1075196D03*
X710630D03*
X733071D03*
X736811Y1090157D03*
Y1082677D03*
X733071Y1090157D03*
Y1078936D03*
X729331Y1090157D03*
X725590D03*
X721850D03*
X725590Y1078936D03*
X721850Y1086417D03*
X673228Y1097637D03*
Y1093897D03*
X658268Y1097637D03*
X669488Y1101377D03*
Y1105117D03*
X748031Y1075196D03*
X665748Y1097637D03*
X733071Y1108858D03*
X781693Y1217322D03*
X777953D03*
X781693Y1209842D03*
X777953D03*
X774212Y1213582D03*
X770472D03*
X781693Y1202362D03*
X777953D03*
X774212Y1206102D03*
X770472D03*
X766732Y1217322D03*
X755512D03*
X759252Y1213582D03*
X762992D03*
X766732D03*
Y1209842D03*
X755512D03*
X766732Y1206102D03*
X762992D03*
X759252D03*
X755512Y1202362D03*
X766732D03*
Y1198621D03*
X762992D03*
X759252D03*
X751772Y1217322D03*
Y1209842D03*
Y1202362D03*
X755512Y1108858D03*
X759252D03*
X755512Y1127558D03*
X759252Y1131299D03*
X755512Y1135039D03*
X748031Y1213582D03*
Y1209842D03*
Y1206102D03*
Y1202362D03*
Y1198621D03*
X751772Y1108858D03*
X759252Y1116338D03*
X755512Y1120078D03*
X759252Y1123818D03*
X751772Y1127558D03*
Y1135039D03*
X751771Y1112598D03*
Y1120078D03*
X781693Y1127558D03*
X777953D03*
X774212Y1131299D03*
X770471D03*
X777953Y1135039D03*
X781693D03*
X770472Y1108858D03*
X774212D03*
X770472Y1116338D03*
X774212D03*
X777953Y1112598D03*
X658268Y1078936D03*
X699408Y1071455D03*
X714370Y1108858D03*
X706890D03*
X676967Y1071455D03*
X785434Y1090158D03*
Y1082677D03*
X766732Y1071455D03*
X774212D03*
X751771D03*
X684448D03*
X785434Y1213582D03*
Y1206102D03*
X669487Y1071455D03*
X785434Y1131300D03*
X691928Y1071454D03*
X729330Y1071455D03*
X785434Y1116339D03*
Y1123819D03*
Y1108859D03*
X736810Y1071455D03*
X785434Y1101378D03*
X744290Y1071455D03*
X662007D03*
X714369D03*
X654526D03*
X748031Y1123818D03*
X725590Y1108858D03*
X729331D03*
X748031D03*
Y1112598D03*
X699409Y1108858D03*
X1072342Y1077066D03*
Y1095767D03*
Y1092027D03*
X1064862D03*
X1068602Y1084547D03*
Y1080807D03*
X1057381Y1088287D03*
X1061121D03*
X1068602Y1099507D03*
X1057381Y1106988D03*
X1061121D03*
X1057381Y1099507D03*
X1068602Y1103247D03*
X1064862Y1095767D03*
X1061121Y1099507D03*
X1068602Y1110728D03*
X1064862D03*
Y1073326D03*
X1079822Y1118208D03*
Y1110728D03*
X1083562Y1114468D03*
X1087302D03*
X1079822Y1092027D03*
X1083562Y1084547D03*
X1079822Y1077066D03*
X1083562Y1080807D03*
X1079822Y1095767D03*
X1083562Y1103247D03*
X1076082Y1084547D03*
Y1080807D03*
Y1103247D03*
Y1099507D03*
Y1121948D03*
Y1118208D03*
Y1110728D03*
X1098523Y1140649D03*
X1094783D03*
X1098523Y1144389D03*
X1094783D03*
X1102263D03*
X1091043Y1140649D03*
X1079822Y1144389D03*
X1091043D03*
X1083562D03*
X1087302D03*
X1079822Y1136909D03*
Y1140649D03*
X1083562D03*
X1087302D03*
X1064862Y1121948D03*
X1061121Y1118208D03*
Y1121948D03*
X1076082Y1133169D03*
Y1140649D03*
Y1136909D03*
X1072342D03*
X1064862Y1129429D03*
X1068602D03*
X1072342D03*
X1061121Y1125688D03*
X1064862D03*
X1068602D03*
X1057381Y1118208D03*
Y1121948D03*
X1094783Y1151870D03*
X1083562D03*
X1091043D03*
X1087302D03*
X1061121Y1140649D03*
X1064862D03*
X1061121Y1136909D03*
X1076082Y1151870D03*
X1072342Y1151869D03*
X1064862Y1144389D03*
X1057381Y1133169D03*
Y1136909D03*
X1094783Y1159350D03*
X1087302D03*
X1083562D03*
X1091043D03*
X1064862Y1155610D03*
X1061121Y1151870D03*
X1076082Y1159350D03*
X1061121D03*
X1064862D03*
X1057381Y1151870D03*
Y1148129D03*
X1094783Y1170570D03*
X1087302D03*
X1079822D03*
X1091043D03*
X1064861D03*
X1068602D03*
X1102263Y1178051D03*
Y1185531D03*
X1098523Y1193011D03*
X1102263D03*
X1077952Y1191141D03*
X1074212D03*
X1070472D03*
X1066732D03*
X1081692D03*
X1055510Y1191142D03*
X1092913Y1191141D03*
X1064861Y1178051D03*
X1094783Y1181791D03*
Y1178051D03*
X1087302D03*
X1091043Y1181791D03*
Y1178051D03*
X1076082D03*
X1106003Y1125688D03*
Y1133169D03*
Y1129429D03*
Y1121948D03*
Y1118208D03*
Y1114468D03*
X1104132Y1071455D03*
X1104133Y1086417D03*
Y1090157D03*
Y1082677D03*
Y1101377D03*
Y1105117D03*
Y1108858D03*
X1205117Y1213582D03*
Y1209842D03*
X1137795Y1108858D03*
X1205117Y1123818D03*
X1190157Y1108858D03*
X1205117Y1198621D03*
X1178936Y1221062D03*
X1182676D03*
X1190157D03*
X1152755Y1108858D03*
X1205117Y1202362D03*
X1240589Y1193011D03*
X1240649Y1140649D03*
Y1148129D03*
Y1155610D03*
Y1151870D03*
Y1144389D03*
Y1166830D03*
Y1170570D03*
Y1159350D03*
Y1178051D03*
Y1185531D03*
Y1174310D03*
Y1181791D03*
Y1189271D03*
X1236909Y1178051D03*
Y1185531D03*
X1229428Y1181791D03*
Y1189271D03*
X1233169D03*
Y1185531D03*
Y1181791D03*
Y1178051D03*
X1229428Y1174310D03*
X1233169D03*
X1225688D03*
Y1181791D03*
Y1189271D03*
X1236909Y1181791D03*
X1225688Y1185531D03*
X1236909Y1189271D03*
X1229428Y1178051D03*
Y1185531D03*
X1236909Y1174310D03*
X1225688Y1178051D03*
X1233169Y1193011D03*
X1236909D03*
X1229428D03*
X1236909Y1140649D03*
X1233169D03*
X1225688D03*
X1229428D03*
X1236909Y1148129D03*
Y1155610D03*
X1233169Y1144389D03*
X1225688D03*
Y1151869D03*
X1229428Y1144389D03*
X1233169Y1155610D03*
X1229428Y1151869D03*
X1233169D03*
Y1148129D03*
X1236909Y1151870D03*
X1225688Y1148129D03*
X1229428D03*
X1225688Y1155610D03*
X1236909Y1144389D03*
X1229428Y1155610D03*
X1236909Y1170570D03*
Y1166830D03*
X1225688D03*
X1229428Y1159350D03*
X1233169D03*
X1225688D03*
X1229428Y1166830D03*
X1233169Y1170570D03*
Y1166830D03*
X1229428Y1170570D03*
X1225688D03*
X1236909Y1159350D03*
X1210728Y1181791D03*
X1206987D03*
X1210728Y1189271D03*
X1218208Y1185531D03*
Y1178051D03*
X1214468Y1189271D03*
X1221948Y1178051D03*
Y1185531D03*
X1206987Y1174310D03*
Y1189271D03*
X1214468Y1185531D03*
Y1181791D03*
Y1178051D03*
Y1174310D03*
X1210728D03*
X1218208Y1189271D03*
Y1174310D03*
X1221948Y1181791D03*
Y1174310D03*
X1218208Y1181791D03*
X1221948Y1189271D03*
X1208858Y1194881D03*
X1218208Y1193011D03*
X1221948Y1140649D03*
X1206988D03*
X1221948Y1155610D03*
X1210728Y1151869D03*
X1206987D03*
X1218208Y1155610D03*
Y1148129D03*
X1214468Y1155610D03*
Y1151869D03*
Y1148129D03*
Y1144389D03*
X1206987D03*
X1210728D03*
X1221948Y1148129D03*
X1218208Y1144389D03*
Y1151869D03*
X1206988Y1155610D03*
Y1148129D03*
X1210728Y1155610D03*
X1221948Y1151869D03*
Y1144389D03*
X1206987Y1159350D03*
X1210728D03*
X1214468D03*
X1210728Y1166830D03*
X1206987D03*
X1218208Y1170570D03*
X1214468D03*
Y1166830D03*
X1221948Y1170570D03*
Y1159350D03*
X1218208Y1166830D03*
Y1159350D03*
X1221948Y1166830D03*
X1210728Y1170570D03*
X1206988D03*
X1218208Y1140649D03*
X1214468D03*
X1192027Y1211712D03*
X1195767D03*
X1192027Y1215452D03*
X1199507Y1211712D03*
Y1215452D03*
Y1207972D03*
X1195767Y1215452D03*
X1192027Y1207972D03*
Y1166830D03*
Y1170570D03*
Y1181791D03*
X1199507Y1185531D03*
X1203247Y1174310D03*
Y1178051D03*
Y1185531D03*
X1192027Y1178051D03*
Y1189271D03*
X1195767D03*
X1192027Y1185531D03*
X1195767D03*
X1199507Y1181791D03*
X1195767Y1178051D03*
Y1174310D03*
X1203247Y1189271D03*
X1199507D03*
Y1174310D03*
X1195767Y1181791D03*
X1192027Y1174310D03*
X1199507Y1178051D03*
X1203247Y1181791D03*
X1195767Y1204232D03*
X1199507Y1193011D03*
X1203247D03*
X1195767Y1196751D03*
Y1193011D03*
X1192027D03*
X1199507Y1196751D03*
Y1200491D03*
Y1204232D03*
X1195767Y1200491D03*
X1192027Y1204232D03*
Y1200491D03*
Y1196751D03*
Y1136909D03*
X1195767Y1140649D03*
X1192027Y1133169D03*
Y1140649D03*
X1195767Y1136909D03*
X1192027Y1125688D03*
Y1129429D03*
X1199507Y1140649D03*
Y1136909D03*
X1203247Y1140649D03*
X1195767Y1148129D03*
X1192027Y1144389D03*
X1195767Y1155610D03*
X1192027Y1148129D03*
X1195767Y1151869D03*
X1199507D03*
X1203247D03*
Y1155610D03*
Y1144389D03*
X1192027Y1151870D03*
X1199507Y1155610D03*
X1192027D03*
X1203247Y1148129D03*
X1195767Y1144389D03*
X1199507Y1148129D03*
Y1144389D03*
X1195767Y1170570D03*
Y1159350D03*
X1203247Y1166830D03*
Y1170570D03*
Y1159350D03*
X1195767Y1166830D03*
X1199507Y1170570D03*
Y1166830D03*
Y1159350D03*
X1192027D03*
Y1118208D03*
Y1121948D03*
X1199507Y1118208D03*
X1195767D03*
Y1114468D03*
X1192027D03*
X1199507D03*
X1188287Y1181791D03*
Y1174310D03*
X1177066Y1189271D03*
X1180806D03*
X1184546Y1178051D03*
X1177066Y1174310D03*
X1184546Y1185531D03*
X1177066Y1181791D03*
X1180806D03*
X1184546Y1189271D03*
Y1174310D03*
X1177066Y1185531D03*
Y1178051D03*
X1180806Y1185531D03*
Y1178051D03*
X1184546Y1181791D03*
X1188287Y1185531D03*
Y1189271D03*
Y1178051D03*
X1184546Y1204232D03*
X1177066D03*
X1180806D03*
X1184546Y1200491D03*
X1177066Y1196751D03*
X1180806D03*
X1184546Y1193011D03*
X1188287Y1204232D03*
Y1196751D03*
X1184566Y1196732D03*
X1180806Y1200491D03*
X1177066D03*
X1188287D03*
X1177066Y1193011D03*
X1180806D03*
X1188287D03*
Y1207972D03*
X1184546Y1211712D03*
X1177066Y1207972D03*
Y1211712D03*
X1180806Y1207972D03*
Y1211712D03*
X1184546Y1207972D03*
X1188287Y1215452D03*
X1180806D03*
X1177066D03*
X1188287Y1211712D03*
Y1125688D03*
X1184546Y1136909D03*
X1177066Y1133169D03*
X1180806D03*
X1184546D03*
X1177066Y1140649D03*
X1180806D03*
X1184546Y1125688D03*
Y1129429D03*
X1177066Y1125688D03*
X1180806D03*
X1184546Y1140649D03*
X1180806Y1129429D03*
X1177066D03*
X1188287D03*
X1180806Y1136909D03*
X1177066D03*
X1188287D03*
Y1140649D03*
Y1155610D03*
Y1151869D03*
Y1148129D03*
X1177066D03*
X1180806D03*
X1184546Y1144389D03*
Y1148129D03*
Y1151869D03*
X1177066Y1155610D03*
X1184546D03*
X1180806Y1151869D03*
X1177066D03*
Y1144389D03*
X1180806D03*
X1188287D03*
X1177066Y1166830D03*
X1188287D03*
Y1159350D03*
Y1170570D03*
X1180806D03*
X1184546D03*
X1177066D03*
X1184546Y1166830D03*
X1180806D03*
X1177066Y1159350D03*
X1180806D03*
X1184546D03*
X1188287Y1118208D03*
Y1121948D03*
X1184546Y1118208D03*
X1180806Y1121948D03*
X1177066D03*
X1184546D03*
X1188287Y1114468D03*
X1177066D03*
Y1118208D03*
X1184546Y1114468D03*
X1158365Y1211712D03*
Y1207972D03*
X1173326D03*
Y1211712D03*
X1162106Y1207972D03*
X1165846D03*
X1173326Y1215452D03*
X1165846D03*
X1169586D03*
X1162105Y1215451D03*
Y1211711D03*
X1165846D03*
X1173326Y1189271D03*
X1158365Y1181791D03*
X1162106D03*
X1165846D03*
X1169586D03*
X1158365Y1189271D03*
X1162106D03*
X1165846D03*
X1169586D03*
X1173326Y1181791D03*
X1169586Y1174310D03*
X1162106D03*
X1158365Y1185531D03*
X1162106D03*
X1169586D03*
X1165846D03*
X1173326D03*
X1165846Y1178051D03*
X1158365D03*
X1162106D03*
X1169586D03*
X1173326D03*
X1162106Y1204232D03*
X1158365D03*
X1169586D03*
X1165846D03*
X1158365Y1196751D03*
X1162106D03*
X1165846D03*
X1169586D03*
X1173326Y1204232D03*
Y1196751D03*
Y1200491D03*
X1165846D03*
X1162106D03*
X1158365D03*
X1169586D03*
X1165846Y1193011D03*
X1169586D03*
X1158365D03*
X1162106D03*
X1173326D03*
X1169586Y1211712D03*
Y1207972D03*
X1162106Y1133169D03*
X1165846D03*
X1169586D03*
X1158365Y1140649D03*
X1162106D03*
X1165846D03*
X1169586D03*
X1158365Y1125688D03*
X1162106D03*
X1165846D03*
X1169586D03*
X1173326Y1133169D03*
Y1125688D03*
Y1140649D03*
X1158365Y1133169D03*
X1169586Y1129429D03*
X1165846D03*
X1162106D03*
X1158365D03*
X1173326D03*
Y1136909D03*
X1169586D03*
X1165846D03*
X1158365D03*
X1162106D03*
X1173326Y1148129D03*
X1158365D03*
X1162106D03*
X1165846D03*
X1169586D03*
X1162106Y1155610D03*
X1169586D03*
X1173326Y1151869D03*
X1158365D03*
X1162106D03*
X1169586D03*
X1165846D03*
X1173326Y1144389D03*
X1165846D03*
X1158365D03*
X1162106D03*
X1169586D03*
X1158365Y1170570D03*
X1165846D03*
X1169586Y1166830D03*
X1158365Y1159350D03*
X1162106Y1166830D03*
X1165846Y1159350D03*
X1173326D03*
Y1170570D03*
X1169586Y1121948D03*
X1165846D03*
X1162106D03*
X1158365D03*
X1173326D03*
X1162106Y1114468D03*
X1169586D03*
X1162106Y1118208D03*
X1173326Y1114468D03*
X1158365Y1118208D03*
X1173326D03*
X1165846Y1114468D03*
X1158365D03*
X1169586Y1118208D03*
X1165846D03*
X1150885Y1196751D03*
X1154625Y1204232D03*
X1150885D03*
X1154625Y1196751D03*
X1143405D03*
Y1204232D03*
Y1200491D03*
X1154625D03*
X1150885D03*
Y1193011D03*
X1154625D03*
X1143405D03*
X1150885Y1207972D03*
X1154625D03*
Y1211712D03*
X1143405Y1207972D03*
Y1211712D03*
Y1215452D03*
X1150885Y1211712D03*
X1143405Y1148129D03*
X1150885D03*
X1154625D03*
X1143405Y1155610D03*
X1154625D03*
X1143405Y1144389D03*
X1150885Y1151869D03*
X1154625D03*
Y1144389D03*
X1150885D03*
X1143405Y1151870D03*
X1154625Y1166830D03*
X1150885Y1170570D03*
X1143405Y1166830D03*
X1150885Y1159350D03*
X1143405Y1181791D03*
X1154625D03*
X1150885D03*
Y1189271D03*
X1154625D03*
X1143405D03*
Y1174310D03*
X1154625D03*
X1143405Y1178051D03*
Y1185531D03*
X1154625D03*
X1150885D03*
X1154625Y1178051D03*
X1150885D03*
Y1121948D03*
X1143405D03*
Y1118208D03*
Y1114468D03*
X1154625Y1121948D03*
Y1118208D03*
X1150885D03*
X1154625Y1114468D03*
X1150885D03*
X1154625Y1125688D03*
X1150885Y1133464D03*
X1154625Y1133169D03*
X1143503Y1132677D03*
X1143405Y1140649D03*
Y1125688D03*
X1150885Y1140649D03*
X1154625D03*
X1150885Y1125688D03*
X1154625Y1129429D03*
X1150885D03*
X1143405D03*
Y1136909D03*
X1154625D03*
X1150885D03*
X1135924Y1181791D03*
X1132184D03*
X1128444D03*
X1135924Y1189271D03*
X1132184D03*
X1128444D03*
Y1174310D03*
X1135924D03*
X1139665Y1178051D03*
X1135924D03*
X1132184D03*
X1128444D03*
X1139665Y1185531D03*
X1132184D03*
X1128444D03*
X1135924D03*
X1139665Y1196751D03*
Y1204232D03*
X1135924D03*
Y1196751D03*
X1132184D03*
X1128444D03*
Y1204232D03*
X1132184D03*
Y1200491D03*
X1128444D03*
X1135924D03*
X1139665D03*
X1128444Y1193011D03*
X1132184D03*
X1135924D03*
X1139665D03*
Y1207972D03*
X1132184Y1211712D03*
X1135924Y1207972D03*
X1132184D03*
X1128444D03*
X1139665Y1211712D03*
X1135925D03*
X1128444Y1215452D03*
Y1211712D03*
X1139665Y1125688D03*
X1128444Y1140649D03*
X1132184D03*
X1135924D03*
X1132184Y1125688D03*
X1128444D03*
X1135924D03*
Y1133169D03*
X1132184D03*
X1128444D03*
X1132184Y1129429D03*
X1128444D03*
X1135924D03*
X1139665D03*
Y1136909D03*
X1135924D03*
X1132184D03*
X1128444D03*
X1135924Y1148129D03*
X1132184D03*
X1128444D03*
X1139665D03*
X1128444Y1155610D03*
X1135924D03*
X1128444Y1144389D03*
X1135924D03*
X1132184D03*
X1139665D03*
X1135925Y1151870D03*
X1132184D03*
X1128444D03*
X1139665D03*
Y1170570D03*
Y1159350D03*
X1132184Y1170570D03*
X1135925Y1166830D03*
X1128444D03*
X1132184Y1159350D03*
X1139665Y1181791D03*
Y1189271D03*
Y1121948D03*
X1128444Y1118208D03*
X1132184D03*
X1135924D03*
X1132184Y1121948D03*
X1135924D03*
X1128444D03*
X1139665Y1118208D03*
Y1114468D03*
X1135925D03*
X1139665Y1133169D03*
Y1140649D03*
X1124704Y1204232D03*
Y1196751D03*
X1120964Y1204232D03*
X1117224D03*
X1113484D03*
Y1196751D03*
X1117224D03*
X1120964D03*
X1117224Y1200491D03*
X1120964D03*
X1113484D03*
X1124704D03*
X1120964Y1193011D03*
X1117224D03*
X1113484D03*
X1124704D03*
X1113484Y1207972D03*
X1117224D03*
X1120964D03*
X1124704Y1211712D03*
Y1207972D03*
Y1215452D03*
X1120964D03*
Y1211712D03*
X1113484D03*
X1117224D03*
X1113484Y1155610D03*
X1120964D03*
X1124704Y1144389D03*
X1113484D03*
X1117224D03*
X1120964D03*
X1113484Y1151870D03*
X1117224D03*
X1120964D03*
X1124704D03*
X1117224Y1170570D03*
X1113484Y1166830D03*
X1117224Y1159350D03*
X1120964Y1166830D03*
X1124704Y1170570D03*
Y1159350D03*
X1113484Y1189271D03*
X1117224D03*
X1120964D03*
X1113484Y1181791D03*
X1117224D03*
X1120964D03*
X1124704Y1189271D03*
Y1181791D03*
X1120964Y1174310D03*
X1113484D03*
Y1178051D03*
X1117224D03*
X1120964D03*
X1124704D03*
X1120964Y1185531D03*
X1113484D03*
X1117224D03*
X1124704D03*
X1117224Y1121948D03*
Y1118208D03*
X1120964D03*
X1113484Y1121948D03*
Y1118208D03*
X1124704Y1121948D03*
Y1118208D03*
X1120964Y1121948D03*
X1117224Y1114468D03*
X1113484D03*
X1120964D03*
X1124704D03*
Y1125688D03*
Y1140649D03*
Y1133169D03*
X1113484D03*
X1117224D03*
X1120964D03*
Y1125688D03*
X1117224D03*
X1113484D03*
X1120964Y1140649D03*
X1117224D03*
X1113484D03*
X1120964Y1129429D03*
X1113484D03*
X1117224D03*
X1124704D03*
Y1136909D03*
X1113484D03*
X1117224D03*
X1120964D03*
Y1148129D03*
X1113484D03*
X1117224D03*
X1124704D03*
X1242520Y1090158D03*
X1130314Y1108858D03*
X1160235D03*
X1175196D03*
X1171455Y1071455D03*
X1119093D03*
X1205117Y1127558D03*
X1186416Y1071455D03*
X1208857D03*
X1195767Y1207972D03*
X1163976Y1221062D03*
X1182676Y1108858D03*
X1156495Y1221062D03*
X1205117Y1206102D03*
X1184547Y1215452D03*
X1163976Y1108858D03*
X1167716Y1221062D03*
X1201377Y1108858D03*
X1178935Y1071455D03*
X1197637Y1108858D03*
Y1221062D03*
X1171456D03*
X1152755Y1232283D03*
Y1236023D03*
X1156495Y1228543D03*
Y1224803D03*
X1149015Y1228543D03*
Y1224803D03*
Y1247243D03*
Y1243503D03*
Y1239763D03*
X1152755D03*
X1156495D03*
Y1243503D03*
Y1247243D03*
X1163976Y1228543D03*
Y1224803D03*
X1171456Y1228543D03*
Y1224803D03*
X1167716Y1232283D03*
X1175196D03*
Y1236023D03*
X1167716D03*
X1160235Y1232283D03*
Y1236023D03*
X1175196Y1254724D03*
X1163976Y1239763D03*
Y1243503D03*
Y1247243D03*
X1167716Y1239763D03*
Y1250984D03*
Y1254724D03*
X1171456Y1247243D03*
Y1243503D03*
X1175196Y1239763D03*
Y1250984D03*
X1171456Y1239763D03*
X1160235D03*
Y1250984D03*
Y1254724D03*
X1178936Y1228543D03*
Y1224803D03*
X1182676Y1232283D03*
Y1236023D03*
X1190157Y1232283D03*
Y1236023D03*
X1186417Y1228543D03*
Y1224803D03*
X1178936Y1247243D03*
X1182676Y1250984D03*
Y1254724D03*
X1190157D03*
Y1250984D03*
X1186417Y1247243D03*
X1178936Y1239763D03*
X1186417D03*
X1182676D03*
X1178936Y1243503D03*
X1186417D03*
X1190157Y1239763D03*
X1197637Y1232283D03*
X1201377Y1228543D03*
X1197637Y1236023D03*
X1201377Y1224803D03*
X1205117Y1232283D03*
Y1236023D03*
X1193897Y1228543D03*
Y1224803D03*
X1205117Y1243503D03*
Y1247243D03*
X1197637Y1250984D03*
Y1254724D03*
X1201377Y1247243D03*
X1205117Y1250984D03*
Y1254724D03*
X1197637Y1239763D03*
X1201377D03*
Y1243503D03*
X1205117Y1239763D03*
X1193897Y1247243D03*
Y1239763D03*
Y1243503D03*
X1216338Y1224803D03*
Y1228543D03*
X1212598Y1232283D03*
Y1236023D03*
X1223818Y1228543D03*
X1220078Y1232283D03*
Y1236023D03*
X1208858Y1224803D03*
Y1228543D03*
X1220078Y1243503D03*
Y1247243D03*
X1223818Y1250984D03*
Y1254724D03*
X1216338D03*
Y1250984D03*
X1212598Y1247243D03*
Y1243503D03*
Y1250984D03*
Y1254724D03*
X1216338Y1247243D03*
Y1243503D03*
X1220078Y1250984D03*
Y1254724D03*
X1223818Y1247243D03*
Y1243503D03*
X1212598Y1239763D03*
X1216338D03*
X1220078D03*
X1223818D03*
X1208858Y1250984D03*
Y1254724D03*
Y1247243D03*
Y1243503D03*
Y1239763D03*
X1238779Y1224803D03*
X1235039D03*
X1231298D03*
Y1228543D03*
X1227558Y1236023D03*
Y1232283D03*
X1238779D03*
X1235039D03*
Y1236023D03*
X1238779D03*
Y1247243D03*
X1235039D03*
X1231298Y1250984D03*
Y1254724D03*
X1227558Y1247243D03*
Y1243503D03*
Y1250984D03*
Y1254724D03*
X1238779Y1250984D03*
X1235039D03*
X1231298Y1247243D03*
Y1243503D03*
X1235039D03*
X1238779D03*
X1227558Y1239763D03*
X1231298D03*
X1235039Y1254724D03*
X1223818Y1206102D03*
X1220078D03*
X1216338D03*
X1212598Y1202362D03*
X1223818D03*
Y1198621D03*
X1220078D03*
X1216338D03*
X1208858Y1202362D03*
X1223818Y1217322D03*
X1220078Y1221062D03*
X1216338D03*
X1212598D03*
Y1217322D03*
X1216338Y1213582D03*
X1220078D03*
X1223818D03*
Y1209842D03*
X1212598D03*
X1208858Y1221062D03*
Y1217322D03*
Y1209842D03*
X1238779Y1198621D03*
X1231298Y1202362D03*
X1227558D03*
X1235039Y1206102D03*
X1238779D03*
Y1202362D03*
X1235039D03*
X1231298Y1206102D03*
X1227558D03*
X1238779Y1213582D03*
X1235039D03*
X1238779Y1221062D03*
X1235039D03*
X1231298Y1217322D03*
X1227558D03*
Y1209842D03*
X1231298D03*
X1238779Y1217322D03*
X1235039D03*
X1231298Y1221062D03*
X1238779Y1209842D03*
X1235039D03*
X1231298Y1213582D03*
X1227558D03*
X1115354Y1075196D03*
X1122834D03*
X1115354Y1090157D03*
Y1078936D03*
X1119094Y1082677D03*
Y1086417D03*
Y1090157D03*
X1122834D03*
X1126574D03*
Y1086417D03*
Y1082677D03*
X1122834Y1078936D03*
Y1093897D03*
X1115354D03*
X1122834Y1097637D03*
X1115354D03*
X1119094Y1101377D03*
X1126574D03*
X1130314Y1075196D03*
X1137795D03*
X1130314Y1090157D03*
Y1078936D03*
X1134054Y1082677D03*
Y1086417D03*
Y1090157D03*
X1137795D03*
Y1078936D03*
X1141535Y1082677D03*
Y1086417D03*
Y1090157D03*
X1130314Y1097637D03*
Y1093897D03*
X1137795D03*
Y1097637D03*
X1134054Y1101377D03*
X1141535D03*
X1152755Y1075196D03*
X1145275D03*
X1149015Y1082677D03*
Y1086417D03*
X1152755Y1090157D03*
X1156495D03*
Y1086417D03*
X1149015Y1090157D03*
X1152755Y1078936D03*
X1156495Y1082677D03*
X1145275Y1090157D03*
Y1078936D03*
X1149015Y1101377D03*
X1152755Y1093897D03*
Y1097637D03*
X1156495Y1101377D03*
X1145275Y1093897D03*
Y1097637D03*
X1167716Y1075196D03*
X1175196D03*
X1160235D03*
X1167716Y1078936D03*
X1163976Y1082677D03*
Y1086417D03*
Y1090157D03*
X1175196Y1078936D03*
X1171456Y1082677D03*
Y1086417D03*
Y1090157D03*
X1167716D03*
X1175196D03*
X1160235Y1078936D03*
Y1090157D03*
X1163976Y1101377D03*
X1171456D03*
X1167716Y1097637D03*
Y1093897D03*
X1175196Y1097637D03*
Y1093897D03*
X1160235D03*
Y1097637D03*
X1182676Y1075196D03*
X1190157D03*
X1178936Y1090157D03*
X1182676Y1078936D03*
X1178936Y1082677D03*
Y1086417D03*
X1182676Y1090157D03*
X1186417D03*
Y1086417D03*
Y1082677D03*
X1190157Y1078936D03*
Y1090157D03*
X1178936Y1101377D03*
X1186417D03*
X1182676Y1097637D03*
Y1093897D03*
X1190157D03*
Y1097637D03*
X1197637Y1075196D03*
X1205117D03*
X1197637Y1078936D03*
Y1090157D03*
X1201377D03*
Y1086417D03*
Y1082677D03*
X1205117Y1078936D03*
X1205116Y1090157D03*
X1193897Y1082677D03*
Y1086417D03*
Y1090157D03*
X1197637Y1097637D03*
X1201377Y1101377D03*
X1197637Y1093897D03*
X1205117D03*
Y1097637D03*
X1193897Y1101377D03*
X1212598Y1075196D03*
X1220079D03*
Y1078936D03*
X1212599D03*
X1223817Y1082677D03*
X1216337D03*
X1216338Y1086417D03*
X1223818D03*
X1212597Y1090157D03*
X1216337D03*
X1220077D03*
X1223817D03*
X1208857Y1082677D03*
X1208858Y1086417D03*
X1208857Y1090157D03*
X1212598Y1093897D03*
X1220078D03*
X1212598Y1097637D03*
X1220078D03*
X1223818Y1101377D03*
X1216338D03*
X1208857D03*
X1227559Y1075196D03*
X1235039D03*
Y1078936D03*
X1227559D03*
X1231298Y1082677D03*
X1238779Y1086417D03*
X1235039D03*
X1231299D03*
X1227557Y1090157D03*
X1231298D03*
X1238779Y1078936D03*
X1227558Y1093897D03*
Y1097637D03*
X1231298Y1101377D03*
X1235039Y1093897D03*
X1238779D03*
Y1097637D03*
X1235039D03*
X1119094Y1105117D03*
X1126574D03*
X1134054D03*
X1141535D03*
X1149015D03*
X1156495D03*
X1163976D03*
X1171456D03*
X1178936D03*
X1186417D03*
X1201377D03*
X1193897D03*
X1216338D03*
X1223818D03*
X1208858D03*
X1231299D03*
X1212598Y1108858D03*
X1216338D03*
Y1116338D03*
X1212598Y1120078D03*
X1216338Y1123818D03*
X1208857Y1112598D03*
Y1120078D03*
X1220077Y1108857D03*
X1223817Y1108858D03*
X1223818Y1116338D03*
X1220078D03*
X1223818Y1112598D03*
Y1123818D03*
X1220078D03*
X1223818Y1120078D03*
X1212598Y1127558D03*
X1216338Y1131299D03*
X1208858Y1127558D03*
X1223818D03*
Y1131299D03*
X1220078D03*
X1235039Y1105117D03*
X1238779D03*
X1227558Y1108858D03*
X1231298D03*
X1227558Y1116338D03*
X1231298D03*
X1235039Y1112598D03*
X1238779D03*
X1227558Y1123818D03*
X1231298D03*
X1235039Y1120078D03*
X1238779D03*
Y1127558D03*
X1235039D03*
X1231298Y1131299D03*
X1227557D03*
X1223818Y1135039D03*
X1212598D03*
X1149015Y1221062D03*
X1126574Y1108858D03*
X1193897Y1221062D03*
X1186417Y1108858D03*
X1201377Y1221062D03*
X1208858Y1108858D03*
X1205117Y1221062D03*
X1216338Y1071455D03*
X1201376D03*
X1193896D03*
X1156494D03*
X1141534D03*
X1134053D03*
X1242520Y1228543D03*
Y1239762D03*
Y1247243D03*
Y1221062D03*
Y1198621D03*
Y1206102D03*
Y1213582D03*
X1231298Y1258465D03*
X1223818D03*
X1216338D03*
X1193897D03*
X1201377D03*
X1208858D03*
X1178936D03*
X1186417D03*
X1171456D03*
X1126573Y1071455D03*
X1242520Y1101378D03*
X1231298Y1071455D03*
X1223818D03*
X1242520Y1082677D03*
Y1108859D03*
Y1116339D03*
Y1123819D03*
Y1131300D03*
X1149014Y1071454D03*
X1163975Y1071455D03*
X1152755Y1221062D03*
X1122834Y1108858D03*
X1149015D03*
X1178936D03*
X1205117Y1120078D03*
X1145275Y1108858D03*
Y1221062D03*
X1115354Y1108858D03*
X1134054D03*
X1119094D03*
X1205117Y1131299D03*
X1160235Y1221062D03*
X1193897Y1108858D03*
X1205117Y1217322D03*
Y1108858D03*
Y1116338D03*
X1141535Y1108858D03*
X1175196Y1221062D03*
X1156495Y1108858D03*
X1186417Y1221062D03*
X1167716Y1108858D03*
X1171456D03*
X1637893Y1170570D03*
X1634153D03*
X1637893Y1166830D03*
Y1159350D03*
X1634153D03*
Y1140649D03*
X1637893D03*
X1630413D03*
Y1136909D03*
X1637893D03*
X1634153D03*
X1630413Y1148129D03*
X1634153D03*
X1637893D03*
X1634153Y1155610D03*
X1630413Y1151869D03*
X1637893D03*
X1634153D03*
Y1144389D03*
X1630413D03*
X1637893D03*
X1634153Y1166830D03*
X1630413Y1159350D03*
Y1170570D03*
X1615452Y1140649D03*
X1619193D03*
X1622933D03*
X1626673D03*
Y1136909D03*
X1622933D03*
X1615452D03*
X1619193D03*
X1615452Y1148129D03*
X1619193D03*
X1622933D03*
X1626673D03*
X1619193Y1155610D03*
X1626673D03*
X1615452Y1151869D03*
X1619193D03*
X1626673D03*
X1622933D03*
Y1144389D03*
X1615452D03*
X1619193D03*
X1626673D03*
X1615452Y1170570D03*
X1622933D03*
X1626673Y1166830D03*
X1615452Y1159350D03*
X1619193Y1166830D03*
X1622933Y1159350D03*
X1600492Y1136909D03*
X1596752D03*
X1611712D03*
X1607972D03*
X1600492Y1148129D03*
X1596752D03*
X1607972D03*
X1611712D03*
X1600492Y1155610D03*
X1611712D03*
X1600492Y1144389D03*
X1596752D03*
X1611712Y1151869D03*
X1607972D03*
X1611712Y1144389D03*
X1607972D03*
X1600492Y1151870D03*
X1596752D03*
Y1170570D03*
Y1159350D03*
X1611712Y1166830D03*
X1607972Y1170570D03*
X1600492Y1166830D03*
X1607972Y1159350D03*
Y1133464D03*
X1596752Y1140649D03*
X1600492D03*
X1607972D03*
X1611712D03*
X1581791D03*
X1585531D03*
X1589271D03*
X1593011D03*
Y1136909D03*
X1589271D03*
X1585531D03*
X1581791D03*
X1593011Y1148129D03*
X1589271D03*
X1585531D03*
X1581791D03*
X1593011Y1155610D03*
X1585531D03*
Y1144389D03*
X1581791D03*
X1593011D03*
X1589271D03*
X1593012Y1151870D03*
X1589271D03*
X1585531D03*
X1581791D03*
X1589271Y1170570D03*
X1593012Y1166830D03*
X1585531D03*
X1581791Y1159350D03*
X1589271D03*
X1581791Y1170570D03*
X1570571Y1140649D03*
X1574311D03*
X1578051D03*
X1566830Y1136909D03*
X1578051D03*
X1574311D03*
X1570571D03*
X1566830Y1140649D03*
X1574311Y1148129D03*
X1570571D03*
X1578051D03*
X1570571Y1155610D03*
X1566830Y1151869D03*
X1578051Y1155610D03*
X1566830Y1144389D03*
X1578051D03*
X1574311D03*
X1570571D03*
X1578051Y1151870D03*
X1574311D03*
X1570571D03*
X1566830Y1159350D03*
X1578051Y1166830D03*
X1574311Y1159350D03*
X1570571Y1166830D03*
X1566830Y1170570D03*
X1574311D03*
X1559350Y1193011D03*
Y1196751D03*
Y1200491D03*
X1555610D03*
Y1204232D03*
X1559350D03*
X1563090D03*
Y1196751D03*
Y1200491D03*
X1555610Y1193011D03*
Y1196751D03*
X1563090Y1193011D03*
X1555610Y1211712D03*
X1559350D03*
X1563090D03*
Y1207972D03*
X1559350D03*
X1555610D03*
X1563090Y1215452D03*
X1559350D03*
X1548130Y1140649D03*
X1559350Y1136909D03*
X1551870D03*
X1548130D03*
X1559350Y1140649D03*
X1555610D03*
X1551870D03*
X1563090D03*
Y1136909D03*
X1555610D03*
X1551870Y1155610D03*
Y1151870D03*
X1559350Y1144389D03*
X1551870D03*
Y1148129D03*
X1559350Y1151870D03*
X1563090Y1155610D03*
Y1148129D03*
X1555610Y1144389D03*
X1548130Y1151870D03*
Y1148129D03*
Y1144389D03*
X1559350Y1155610D03*
X1555610Y1151870D03*
X1559350Y1148129D03*
Y1170570D03*
X1551870Y1166830D03*
X1559350Y1159350D03*
X1551870D03*
X1548130Y1170570D03*
X1551870D03*
X1563090Y1166830D03*
X1548130D03*
Y1159350D03*
X1555610Y1170570D03*
X1559350Y1166830D03*
X1555610Y1159350D03*
X1559350Y1185531D03*
X1551870Y1178051D03*
Y1174310D03*
X1559350Y1178051D03*
X1551870Y1181791D03*
X1563090D03*
Y1174310D03*
X1548130D03*
Y1178051D03*
Y1181791D03*
X1555610Y1185531D03*
X1559350Y1174310D03*
Y1181791D03*
X1555610Y1178051D03*
X1544389Y1140649D03*
X1540649D03*
X1536909D03*
X1533169D03*
X1544389Y1136909D03*
X1540649D03*
X1544389Y1144389D03*
X1540649D03*
X1533169D03*
Y1148129D03*
Y1151870D03*
Y1155610D03*
X1544389Y1148129D03*
Y1155610D03*
Y1151870D03*
X1536909Y1148129D03*
X1540649Y1151870D03*
Y1148129D03*
X1536909Y1144389D03*
Y1155610D03*
X1533169Y1159350D03*
X1536909Y1166830D03*
Y1170570D03*
X1544389Y1159350D03*
Y1166830D03*
Y1170570D03*
X1540649Y1159350D03*
Y1170570D03*
X1544389Y1174310D03*
Y1178051D03*
X1540649Y1174310D03*
X1521949Y1136909D03*
X1529429Y1140649D03*
X1525689D03*
X1521949D03*
X1518208D03*
Y1136909D03*
X1521949Y1144389D03*
X1518208D03*
X1529429Y1151869D03*
X1525689D03*
X1521949Y1148129D03*
Y1151870D03*
X1518208D03*
X1529429Y1155610D03*
X1525689D03*
X1521949D03*
X1518208Y1148129D03*
Y1155610D03*
X1521949Y1159350D03*
X1518208D03*
X1529429Y1166830D03*
X1525689D03*
X1521948D03*
X1525689Y1170570D03*
X1521948D03*
X1518209Y1166830D03*
X1521948Y1174310D03*
X1518207D03*
X1527559Y1179921D03*
X1514468Y1140649D03*
Y1136909D03*
Y1144389D03*
Y1151870D03*
Y1148129D03*
Y1155610D03*
Y1159350D03*
Y1166829D03*
Y1174309D03*
X1512597Y1198622D03*
X1516338Y1187401D03*
Y1194881D03*
Y1202362D03*
Y1209842D03*
Y1217322D03*
X1531299Y1187401D03*
X1520078D03*
X1535039Y1191141D03*
X1531299D03*
X1535039Y1198621D03*
X1531299D03*
Y1194881D03*
Y1206102D03*
X1535039D03*
X1531299Y1202362D03*
X1527559Y1191141D03*
X1523819D03*
X1527559Y1198621D03*
X1523819D03*
Y1206102D03*
X1527559D03*
X1520078Y1194881D03*
Y1202362D03*
X1531299Y1217322D03*
X1535039Y1213582D03*
X1531299Y1209842D03*
Y1213582D03*
X1527559D03*
X1523819D03*
X1520078Y1209842D03*
Y1217322D03*
X1538779Y1198621D03*
Y1206102D03*
Y1191141D03*
Y1213582D03*
X1542519Y1194881D03*
X1546259D03*
X1542519Y1202362D03*
X1546259D03*
X1542519Y1209842D03*
X1546259D03*
X1516338Y1232283D03*
Y1236023D03*
Y1224803D03*
Y1243503D03*
Y1250984D03*
X1523819Y1221062D03*
X1527559D03*
X1542519Y1187401D03*
X1535039Y1183661D03*
X1531299D03*
X1527559D03*
X1523819D03*
X1527559Y1236023D03*
Y1232283D03*
X1523819Y1228543D03*
Y1224803D03*
X1520078Y1236023D03*
Y1232283D03*
Y1224803D03*
X1527559Y1250984D03*
Y1254724D03*
X1523819Y1247243D03*
Y1239763D03*
Y1243503D03*
X1527559Y1239763D03*
X1520078Y1250984D03*
Y1254724D03*
Y1243503D03*
X1512597Y1206103D03*
Y1213583D03*
Y1221063D03*
X1512596Y1239762D03*
Y1247242D03*
X1523819Y1258465D03*
X1512597Y1228542D03*
Y1191142D03*
X1550000Y1206102D03*
Y1202362D03*
Y1209842D03*
Y1198621D03*
Y1213582D03*
X1559350Y1114468D03*
X1555610D03*
X1536909Y1118208D03*
X1533169D03*
Y1121948D03*
X1544389Y1114468D03*
X1536909Y1110728D03*
X1533169D03*
X1540649Y1114468D03*
X1536909Y1073326D03*
X1533169Y1080807D03*
Y1084547D03*
X1540649Y1080807D03*
X1536909Y1077066D03*
X1540649Y1084547D03*
X1536909Y1092027D03*
Y1095767D03*
X1533169Y1099507D03*
X1540649Y1103247D03*
X1533169D03*
X1518208Y1099507D03*
X1525689D03*
X1529429Y1095767D03*
X1525689Y1103247D03*
X1518208Y1106988D03*
X1521949Y1095767D03*
Y1110728D03*
X1518208Y1114468D03*
X1525689Y1110728D03*
X1518208Y1121948D03*
X1521949Y1118208D03*
X1525689D03*
Y1125688D03*
X1521949D03*
Y1073326D03*
X1529429D03*
Y1077066D03*
X1525689Y1084547D03*
X1529429Y1092027D03*
X1521949D03*
X1518208Y1088287D03*
X1525689Y1080807D03*
X1514468Y1088287D03*
Y1099507D03*
Y1106988D03*
Y1121948D03*
Y1114468D03*
X1591141Y1108858D03*
X1636023Y1090157D03*
X1639763Y1075196D03*
X1647244D03*
X1643504Y1082677D03*
X1636023D03*
Y1086417D03*
X1643504Y1090157D03*
X1632283Y1093897D03*
X1617322D03*
Y1097637D03*
X1636023Y1101377D03*
X1654724Y1075196D03*
X1647244Y1097637D03*
Y1093897D03*
X1654724Y1078936D03*
Y1090157D03*
X1658464D03*
Y1086417D03*
Y1082677D03*
X1662204Y1078936D03*
X1662203Y1090157D03*
X1643504Y1101377D03*
X1650984Y1082677D03*
Y1086417D03*
X1662204Y1135039D03*
X1609842Y1108858D03*
X1628543D03*
X1617322Y1090157D03*
X1697736Y1140649D03*
X1693996D03*
X1617322Y1078936D03*
X1697736Y1148129D03*
X1693996D03*
X1697736Y1155610D03*
X1693996D03*
Y1151870D03*
X1697736D03*
X1693996Y1144389D03*
X1697736D03*
X1693996Y1170570D03*
Y1166830D03*
X1697736D03*
Y1170570D03*
Y1159350D03*
X1693996D03*
X1697736Y1178051D03*
X1693996D03*
X1697736Y1185531D03*
X1693996D03*
X1697736Y1174310D03*
X1693996Y1189271D03*
X1697736D03*
Y1181791D03*
X1693996D03*
Y1174310D03*
Y1193011D03*
X1697676D03*
X1628543Y1101377D03*
X1643504Y1086417D03*
X1686515Y1193011D03*
X1690256Y1140649D03*
X1632283Y1097637D03*
X1624803Y1093897D03*
X1679035Y1140649D03*
X1686515D03*
X1682775D03*
X1690256Y1144389D03*
X1682775D03*
X1679035Y1148129D03*
X1682775Y1151869D03*
X1679035Y1155610D03*
X1686515Y1144389D03*
X1690256Y1155610D03*
X1686515Y1151869D03*
X1690256D03*
Y1148129D03*
X1679035Y1151869D03*
Y1144389D03*
X1682775Y1148129D03*
X1686515Y1155610D03*
Y1148129D03*
X1682775Y1155610D03*
Y1166830D03*
X1679035Y1170570D03*
X1686515Y1159350D03*
X1690256D03*
X1682775D03*
X1679035D03*
X1686515Y1166830D03*
X1690256Y1170570D03*
Y1166830D03*
X1679035D03*
X1686515Y1170570D03*
X1682775D03*
X1690256Y1178051D03*
X1686515Y1174310D03*
X1690256D03*
X1682775D03*
X1679035Y1178051D03*
X1682775Y1181791D03*
X1679035Y1185531D03*
X1682775Y1189271D03*
X1686515Y1181791D03*
Y1189271D03*
X1690256D03*
Y1185531D03*
Y1181791D03*
X1679035D03*
Y1189271D03*
Y1174310D03*
X1686515Y1185531D03*
X1682775Y1178051D03*
X1686515D03*
X1682775Y1185531D03*
X1690256Y1193011D03*
X1639763Y1090157D03*
X1675295Y1140649D03*
X1671555D03*
X1650984Y1090157D03*
X1647244D03*
Y1078936D03*
X1667815Y1151869D03*
X1664074D03*
X1675295Y1155610D03*
Y1148129D03*
X1671555Y1155610D03*
Y1151869D03*
Y1148129D03*
Y1144389D03*
X1664074D03*
X1667815D03*
Y1155610D03*
X1664075Y1148129D03*
Y1155610D03*
X1675295Y1144389D03*
Y1151869D03*
X1664074Y1159350D03*
X1667815D03*
X1671555D03*
X1667815Y1166830D03*
X1664074D03*
X1675295Y1170570D03*
X1671555D03*
Y1166830D03*
X1675295D03*
Y1159350D03*
X1664075Y1170570D03*
X1667815D03*
X1664074Y1189271D03*
Y1174310D03*
X1671555Y1185531D03*
Y1181791D03*
Y1178051D03*
Y1174310D03*
X1667815D03*
Y1181791D03*
X1664074D03*
X1667815Y1189271D03*
X1675295Y1185531D03*
Y1178051D03*
X1671555Y1189271D03*
X1675295D03*
Y1174310D03*
Y1181791D03*
X1665945Y1194881D03*
X1675295Y1193011D03*
X1639763Y1093897D03*
Y1097637D03*
X1649114Y1200491D03*
Y1196751D03*
Y1204232D03*
Y1211712D03*
X1645374Y1207972D03*
X1660334D03*
Y1215452D03*
Y1211712D03*
X1652854D03*
X1645374Y1215452D03*
X1649114D03*
X1652854D03*
X1656594Y1211712D03*
X1645374D03*
X1656594Y1215452D03*
Y1207972D03*
X1649114D03*
Y1133169D03*
Y1140649D03*
X1652854Y1136909D03*
X1649114Y1125688D03*
X1645374D03*
Y1129429D03*
Y1136909D03*
X1656594Y1133169D03*
Y1140649D03*
Y1136909D03*
X1652854Y1148129D03*
X1649114Y1144389D03*
X1652854Y1155610D03*
X1649114Y1148129D03*
X1652854Y1151869D03*
X1656594D03*
X1660334D03*
Y1155610D03*
Y1144389D03*
X1649114Y1151870D03*
Y1155610D03*
X1660334Y1148129D03*
X1652854Y1144389D03*
X1656594Y1148129D03*
Y1144389D03*
X1652854Y1159350D03*
X1660334Y1166830D03*
Y1170570D03*
Y1159350D03*
X1652854Y1170570D03*
Y1166830D03*
X1649114Y1159350D03*
Y1170570D03*
Y1166830D03*
X1652854Y1185531D03*
X1656594Y1181791D03*
X1652854Y1178051D03*
Y1174310D03*
X1649114Y1181791D03*
X1656594Y1185531D03*
X1660334Y1174310D03*
Y1178051D03*
Y1185531D03*
X1645374Y1181791D03*
X1649114Y1178051D03*
Y1189271D03*
X1652854D03*
X1649114Y1185531D03*
X1656594Y1189271D03*
X1649114Y1174310D03*
X1652854Y1181791D03*
X1660334Y1189271D03*
X1645374Y1185531D03*
Y1189271D03*
X1660334Y1181791D03*
X1656594Y1178051D03*
X1645374D03*
Y1204232D03*
X1656594Y1193011D03*
X1652854Y1204232D03*
X1660334D03*
Y1200491D03*
Y1193011D03*
X1652854Y1196751D03*
Y1193011D03*
X1649114D03*
X1645374Y1196751D03*
X1660334D03*
X1645374Y1200491D03*
Y1193011D03*
X1656594Y1196751D03*
Y1200491D03*
Y1204232D03*
X1652854Y1200491D03*
X1645374Y1118208D03*
X1649114D03*
Y1121948D03*
X1645374D03*
X1656594Y1118208D03*
X1652854D03*
Y1114468D03*
X1645374D03*
X1649114D03*
X1656594D03*
X1649114Y1129429D03*
Y1136909D03*
X1652854Y1140649D03*
X1634153Y1189271D03*
X1637893D03*
X1641633Y1185531D03*
X1630413Y1181791D03*
X1634153D03*
X1637893D03*
X1641633Y1189271D03*
X1630413D03*
X1641633Y1181791D03*
X1630413Y1185531D03*
X1634153D03*
X1637893D03*
X1641653Y1196732D03*
X1641633Y1204232D03*
X1630413D03*
X1634153D03*
X1637893D03*
X1641633Y1200491D03*
X1630413Y1196751D03*
X1634153D03*
X1637893D03*
X1641633Y1193011D03*
X1634153D03*
X1637893D03*
X1630413D03*
X1641633Y1211712D03*
X1634153Y1207972D03*
X1630413D03*
X1634153Y1211712D03*
X1637893Y1207972D03*
Y1211712D03*
X1630413D03*
X1641633Y1207972D03*
X1630413Y1215452D03*
X1637893D03*
X1634153D03*
X1641633Y1118208D03*
X1637893Y1121948D03*
X1634153D03*
X1630413D03*
X1641633D03*
X1637893Y1118208D03*
Y1114468D03*
X1634153D03*
X1630413D03*
X1641633D03*
X1634153Y1118208D03*
X1630413D03*
X1641633Y1125688D03*
X1630413D03*
X1634153D03*
X1637893D03*
X1619193Y1185531D03*
X1626673D03*
X1622933D03*
X1619193Y1204232D03*
X1615452D03*
X1626673D03*
X1622933D03*
X1615452Y1196751D03*
X1619193D03*
X1622933D03*
X1626673D03*
X1622933Y1193011D03*
X1626673D03*
X1615452D03*
X1619193D03*
Y1207972D03*
X1622933D03*
X1626673Y1211712D03*
Y1207972D03*
X1615452Y1211712D03*
Y1207972D03*
X1622933Y1215452D03*
X1619192Y1215451D03*
X1626673Y1215452D03*
X1619192Y1211711D03*
X1622933D03*
X1626673Y1121948D03*
X1622933D03*
X1619193D03*
X1615452D03*
Y1118208D03*
X1619193D03*
X1615452Y1114468D03*
X1619193D03*
X1622933D03*
X1626673D03*
Y1118208D03*
X1622933D03*
X1615452Y1125688D03*
X1619193D03*
X1622933D03*
X1626673D03*
X1615452Y1181791D03*
X1619193D03*
X1622933D03*
X1626673D03*
X1615452Y1189271D03*
X1619193D03*
X1622933D03*
X1626673D03*
X1615452Y1185531D03*
X1607972Y1125688D03*
X1611712D03*
X1600492Y1181791D03*
X1611712D03*
X1607972D03*
Y1189271D03*
X1611712D03*
X1596752Y1181791D03*
X1600492Y1189271D03*
X1596752D03*
X1600492Y1185531D03*
X1596752D03*
X1611712D03*
X1607972D03*
X1611712Y1204232D03*
X1607972D03*
Y1196751D03*
X1611712D03*
X1600492D03*
X1596752D03*
Y1204232D03*
X1600492D03*
X1607972Y1193011D03*
X1611712D03*
X1600492D03*
X1596752D03*
Y1207972D03*
X1607972D03*
X1611712D03*
Y1211712D03*
X1600492Y1207972D03*
Y1211712D03*
Y1215452D03*
X1596752Y1211712D03*
X1607972D03*
X1596752Y1121948D03*
X1600492Y1118208D03*
Y1114468D03*
X1611712Y1121948D03*
X1607972D03*
X1596752Y1118208D03*
X1600492Y1121948D03*
X1596752Y1114468D03*
X1607972D03*
X1611712Y1118208D03*
X1607972D03*
X1611712Y1114468D03*
X1600492Y1125688D03*
X1596752D03*
X1593011Y1207972D03*
X1589271D03*
X1585531D03*
X1593012Y1211712D03*
X1581791Y1215452D03*
X1585531D03*
Y1211712D03*
X1581791Y1121948D03*
X1585531Y1118208D03*
X1589271D03*
X1593011D03*
X1589271Y1121948D03*
X1593011D03*
X1585531D03*
X1593012Y1114468D03*
X1581791D03*
X1589271Y1125688D03*
X1585531D03*
X1581791D03*
X1593011D03*
Y1181791D03*
X1589271D03*
X1585531D03*
X1581791D03*
X1593011Y1189271D03*
X1589271D03*
X1585531D03*
X1581791D03*
X1589271Y1185531D03*
X1585531D03*
X1581791D03*
X1593011D03*
Y1204232D03*
Y1196751D03*
X1589271D03*
X1585531D03*
X1581791D03*
Y1204232D03*
X1585531D03*
X1589271D03*
X1585531Y1193011D03*
X1589271D03*
X1593011D03*
X1581791D03*
X1589271Y1211712D03*
X1581791Y1207972D03*
Y1211712D03*
Y1118208D03*
X1574311Y1204232D03*
X1578051D03*
X1570571Y1193011D03*
X1574311D03*
X1578051D03*
X1617322Y1108858D03*
X1578051Y1207972D03*
X1574311D03*
X1570571D03*
X1578051Y1215452D03*
X1570571Y1211712D03*
X1574311Y1215452D03*
X1570571D03*
X1578051Y1211712D03*
X1574311D03*
X1578051Y1118208D03*
X1574311D03*
Y1121948D03*
X1578051D03*
X1574311Y1114468D03*
X1570571D03*
X1578051D03*
X1570571Y1125688D03*
X1574311D03*
X1578051D03*
Y1181791D03*
X1574311D03*
X1578051Y1189271D03*
X1574311D03*
X1570571D03*
X1574311Y1185531D03*
X1578051D03*
Y1196751D03*
X1574311D03*
X1570571D03*
Y1204232D03*
Y1118208D03*
Y1121948D03*
X1624803Y1097637D03*
X1621063Y1101377D03*
X1662204Y1075196D03*
X1602362Y1108858D03*
X1598622D03*
X1643504D03*
X1699607Y1213582D03*
X1652854Y1207972D03*
X1647244Y1108858D03*
X1662204D03*
X1594882D03*
X1606102D03*
X1654724D03*
X1641634Y1215452D03*
X1658464Y1108858D03*
X1639763Y1078936D03*
X1654724Y1097637D03*
X1665945Y1108858D03*
X1621063Y1105117D03*
X1628543D03*
X1658464Y1101377D03*
X1654724Y1093897D03*
X1662204D03*
Y1097637D03*
X1650984Y1101377D03*
X1669685Y1075196D03*
X1677166D03*
Y1078936D03*
X1669686D03*
X1680904Y1082677D03*
X1673424D03*
X1673425Y1086417D03*
X1680905D03*
X1669684Y1090157D03*
X1673424D03*
X1677164D03*
X1680904D03*
X1665944Y1082677D03*
X1665945Y1086417D03*
X1665944Y1090157D03*
X1669685Y1093897D03*
X1677165D03*
X1669685Y1097637D03*
X1677165D03*
X1680905Y1101377D03*
X1673425D03*
X1665944D03*
X1684646Y1075196D03*
X1692126D03*
Y1078936D03*
X1684646D03*
X1688385Y1082677D03*
X1695866Y1086417D03*
X1692126D03*
X1688386D03*
X1684644Y1090157D03*
X1688385D03*
X1695866Y1078936D03*
X1684645Y1093897D03*
Y1097637D03*
X1688385Y1101377D03*
X1692126Y1093897D03*
X1695866D03*
Y1097637D03*
X1692126D03*
X1576181Y1105117D03*
X1583661D03*
X1591141D03*
X1598622D03*
X1606102D03*
X1613582D03*
X1632283Y1108858D03*
X1662204Y1120078D03*
Y1116338D03*
Y1131299D03*
Y1123818D03*
Y1127558D03*
X1587401Y1108858D03*
X1636023Y1105117D03*
X1643504D03*
X1658464D03*
X1650984D03*
X1673425D03*
X1680905D03*
X1665945D03*
X1688386D03*
X1669685Y1108858D03*
X1673425D03*
Y1116338D03*
X1669685Y1112598D03*
Y1120078D03*
X1673425Y1123818D03*
X1665944Y1112598D03*
Y1120078D03*
X1677164Y1108857D03*
X1680904Y1108858D03*
X1680905Y1116338D03*
X1677165D03*
X1680905Y1112598D03*
Y1123818D03*
X1677165D03*
X1680905Y1120078D03*
X1669685Y1127558D03*
X1673425Y1131299D03*
X1665945Y1127558D03*
X1680905D03*
Y1131299D03*
X1677165D03*
X1692126Y1105117D03*
X1695866D03*
X1684645Y1108858D03*
X1688385D03*
X1684645Y1116338D03*
X1688385D03*
X1692126Y1112598D03*
X1695866D03*
X1684645Y1123818D03*
X1688385D03*
X1692126Y1120078D03*
X1695866D03*
Y1127558D03*
X1692126D03*
X1688385Y1131299D03*
X1684644D03*
X1665945Y1135039D03*
X1572441Y1075196D03*
X1579921D03*
X1572441Y1090157D03*
Y1078936D03*
X1576181Y1082677D03*
Y1086417D03*
Y1090157D03*
X1579921D03*
X1583661D03*
Y1086417D03*
Y1082677D03*
X1579921Y1078936D03*
Y1093897D03*
X1572441D03*
X1579921Y1097637D03*
X1572441D03*
X1576181Y1101377D03*
X1583661D03*
X1587401Y1075196D03*
X1594882D03*
X1587401Y1090157D03*
Y1078936D03*
X1591141Y1082677D03*
Y1086417D03*
Y1090157D03*
X1594882D03*
Y1078936D03*
X1598622Y1082677D03*
Y1086417D03*
Y1090157D03*
X1587401Y1097637D03*
Y1093897D03*
X1594882D03*
Y1097637D03*
X1591141Y1101377D03*
X1598622D03*
X1609842Y1075196D03*
X1602362D03*
X1606102Y1082677D03*
Y1086417D03*
X1609842Y1090157D03*
X1613582D03*
Y1086417D03*
X1606102Y1090157D03*
X1609842Y1078936D03*
X1613582Y1082677D03*
X1602362Y1090157D03*
Y1078936D03*
X1606102Y1101377D03*
X1609842Y1093897D03*
Y1097637D03*
X1613582Y1101377D03*
X1602362Y1093897D03*
Y1097637D03*
X1624803Y1075196D03*
X1632283D03*
X1617322D03*
X1624803Y1078936D03*
X1621063Y1082677D03*
Y1086417D03*
Y1090157D03*
X1632283Y1078936D03*
X1628543Y1082677D03*
Y1086417D03*
Y1090157D03*
X1624803D03*
X1632283D03*
X1695866Y1217322D03*
X1692126D03*
X1695866Y1209842D03*
X1692126D03*
X1688385Y1213582D03*
X1684645D03*
X1680905Y1217322D03*
X1669685D03*
X1673425Y1213582D03*
X1677165D03*
X1680905D03*
Y1209842D03*
X1669685D03*
X1665945Y1217322D03*
Y1209842D03*
X1695866Y1202362D03*
X1692126D03*
X1688385Y1206102D03*
X1684645D03*
X1688385Y1198621D03*
X1684645D03*
X1680905Y1206102D03*
X1677165D03*
X1673425D03*
X1669685Y1202362D03*
X1680905D03*
Y1198621D03*
X1677165D03*
X1673425D03*
X1688385Y1071455D03*
X1699607Y1082677D03*
Y1090158D03*
Y1101378D03*
Y1116339D03*
Y1108859D03*
Y1123819D03*
Y1131300D03*
X1598621Y1071455D03*
X1606101Y1071454D03*
X1613581Y1071455D03*
X1621062D03*
X1628542D03*
X1636022D03*
X1643503D03*
X1650983D03*
X1665944D03*
X1658463D03*
X1673425D03*
X1699607Y1198621D03*
X1591140Y1071455D03*
X1583660D03*
X1576180D03*
X1680905D03*
X1699607Y1206102D03*
X1576181Y1108858D03*
X1650984D03*
X1624803D03*
X1621063D03*
X1636023D03*
X1639763D03*
X1572441D03*
X1579921D03*
X1583661D03*
X1613582D03*
G54D61*
X970071Y1409152D03*
Y1365652D03*
G54D53*
X330800Y1174500D03*
X408523Y1332967D03*
X404657D03*
X626476Y1155610D03*
X622736Y1151870D03*
Y1159350D03*
X792277Y1173065D03*
X787887Y1174500D03*
X792382Y1191664D03*
X1079822Y1151870D03*
Y1159350D03*
X1536909Y1151870D03*
Y1159350D03*
X1540649Y1155610D03*
G54D56*
X723927Y550020D03*
X752942D03*
Y421555D03*
X659930Y455492D03*
X630915D03*
X1181014Y421555D03*
X1210029D03*
X1574104Y583957D03*
X1545089D03*
G54D54*
X407493Y354142D03*
X975925Y854783D03*
G54D55*
X886026Y346584D03*
X1079863Y345660D03*
X828385Y1120599D03*
X822006Y1130208D03*
X1579753Y599100D03*
G54D49*
X179173Y1489331D03*
Y1494449D03*
X187835Y1493662D03*
Y1498780D03*
Y1580670D03*
Y1585788D03*
X179173Y1591693D03*
Y1596811D03*
Y1607048D03*
Y1612166D03*
Y1622402D03*
X170512Y1452717D03*
X161850Y1622402D03*
X153189Y1452717D03*
X144528Y1622402D03*
X135866Y1452717D03*
X127205Y1622402D03*
X118543Y1452717D03*
X109882Y1622402D03*
X361063Y1493662D03*
Y1498780D03*
Y1585788D03*
Y1452717D03*
Y1462953D03*
Y1468071D03*
Y1478308D03*
Y1483426D03*
Y1580670D03*
X1209803Y1452717D03*
X1201141Y1458622D03*
Y1463741D03*
X1209803Y1462953D03*
Y1468071D03*
X1201141Y1473977D03*
Y1479095D03*
X1209803Y1478308D03*
Y1483426D03*
X1201141Y1489331D03*
Y1494449D03*
X1209803Y1493662D03*
Y1498780D03*
X1201141Y1504685D03*
Y1509804D03*
X1209803Y1509016D03*
Y1514134D03*
X1201141Y1560985D03*
Y1566103D03*
X1209803Y1565315D03*
Y1570434D03*
X1201141Y1576339D03*
Y1581457D03*
X1209803Y1580670D03*
Y1585788D03*
X1201141Y1591693D03*
Y1596811D03*
X1209803Y1596024D03*
Y1601142D03*
X1201141Y1607048D03*
Y1612166D03*
X1209803Y1611378D03*
Y1616496D03*
X1201141Y1622402D03*
X1192480Y1452717D03*
X1183818Y1622402D03*
X1175157Y1452717D03*
X1166496Y1622402D03*
X1157834Y1452717D03*
X1149173Y1622402D03*
X1140511Y1452717D03*
X1131850Y1622402D03*
X707520Y1452717D03*
X698858Y1458622D03*
Y1463741D03*
X707520Y1462953D03*
Y1468071D03*
X698858Y1473977D03*
Y1479095D03*
X707520Y1478308D03*
Y1483426D03*
X698858Y1489331D03*
Y1494449D03*
X707520Y1493662D03*
Y1498780D03*
X698858Y1504685D03*
Y1509804D03*
X707520Y1509016D03*
Y1514134D03*
X698858Y1560985D03*
Y1566103D03*
X707520Y1565315D03*
Y1570434D03*
X698858Y1576339D03*
Y1581457D03*
X707520Y1580670D03*
Y1585788D03*
X698858Y1591693D03*
Y1596811D03*
X707520Y1596024D03*
Y1601142D03*
X698858Y1607048D03*
Y1612166D03*
X707520Y1611378D03*
Y1616496D03*
X698858Y1622402D03*
X690197Y1452717D03*
X681535Y1622402D03*
X672874Y1452717D03*
X664213Y1622402D03*
X655551Y1452717D03*
X646890Y1622402D03*
X638228Y1452717D03*
X629567Y1622402D03*
X1720826Y1494449D03*
X1729488Y1493662D03*
Y1498780D03*
X1720826Y1504685D03*
Y1509804D03*
X1729488Y1509016D03*
Y1452717D03*
X1720826Y1458622D03*
Y1463741D03*
X1729488Y1462953D03*
Y1468071D03*
X1720826Y1473977D03*
Y1479095D03*
X1729488Y1478308D03*
Y1483426D03*
X1720826Y1489331D03*
X1729488Y1514134D03*
X1720826Y1560985D03*
Y1566103D03*
X1729488Y1565315D03*
Y1570434D03*
X1720826Y1576339D03*
Y1581457D03*
X1729488Y1580670D03*
Y1585788D03*
X1720826Y1591693D03*
Y1596811D03*
X1729488Y1596024D03*
Y1601142D03*
X1720826Y1607048D03*
Y1612166D03*
X1729488Y1611378D03*
Y1616496D03*
X1720826Y1622402D03*
X1712165Y1452717D03*
X1703503Y1622402D03*
X1694842Y1452717D03*
X1686181Y1622402D03*
X1677519Y1452717D03*
X1668858Y1622402D03*
X1660196Y1452717D03*
X1651535Y1622402D03*
X1383032Y1452717D03*
Y1462953D03*
Y1468071D03*
Y1478308D03*
Y1483426D03*
Y1493662D03*
Y1498780D03*
Y1509016D03*
Y1514134D03*
Y1565315D03*
Y1570434D03*
Y1580670D03*
Y1585788D03*
Y1596024D03*
Y1601142D03*
Y1611378D03*
Y1616496D03*
G54D46*
X909360Y230906D03*
G54D41*
X1729390Y144095D03*
X1627028D03*
X1169941D03*
X1067579D03*
X965217D03*
X815217D03*
G54D52*
X317125Y1236023D03*
X313385Y1224803D03*
X324606Y1228543D03*
X317125Y1232283D03*
X313385Y1228543D03*
X320866D03*
X324606Y1239763D03*
X320866D03*
X313385Y1120078D03*
X324606Y1123818D03*
X317125Y1112598D03*
X324606Y1116338D03*
X313385Y1112598D03*
X317125Y1120078D03*
X320866Y1116338D03*
Y1123818D03*
X313385Y1127558D03*
X324606Y1131299D03*
X317125Y1127558D03*
X320866Y1131299D03*
Y1090157D03*
X317125Y1093897D03*
X324606Y1090157D03*
Y1082676D03*
X317124Y1078936D03*
X313384Y1082677D03*
Y1086417D03*
X320866Y1082676D03*
X313385Y1101377D03*
X320866D03*
X324606D03*
X317125Y1097637D03*
X324606Y1108858D03*
X320866D03*
X317124Y1075196D03*
X305905Y1224803D03*
X302165Y1236023D03*
X298425Y1213582D03*
X305905Y1209842D03*
Y1217322D03*
X302165Y1209842D03*
X298425Y1206102D03*
X302165Y1217322D03*
Y1232283D03*
X309645D03*
X294685Y1236023D03*
X298425Y1224803D03*
X294685Y1232283D03*
X298425Y1228543D03*
X309645Y1236023D03*
X305905Y1228543D03*
Y1127559D03*
Y1135039D03*
X302165D03*
Y1127559D03*
X298425Y1123818D03*
Y1131299D03*
Y1198621D03*
X305905Y1202362D03*
X302165D03*
X298425Y1105117D03*
Y1101376D03*
X309644Y1097637D03*
X302164D03*
X305905Y1105117D03*
X294684Y1097637D03*
X313385Y1105117D03*
X305905Y1101376D03*
X302165Y1120078D03*
X305905Y1112598D03*
X298425Y1116338D03*
X305905Y1120078D03*
X302165Y1112598D03*
X294684Y1093897D03*
X309644D03*
X302164D03*
X305904Y1082677D03*
X302164Y1078936D03*
X305904Y1086417D03*
X294684Y1078936D03*
X309644D03*
X298424Y1086416D03*
Y1082676D03*
X294684Y1075196D03*
X302164D03*
X309644D03*
X283464Y1243503D03*
X279724Y1250984D03*
X283464Y1247243D03*
X287204Y1250984D03*
Y1254724D03*
X279724D03*
X294685Y1213582D03*
Y1206102D03*
X279724Y1232283D03*
Y1236023D03*
X287204Y1232283D03*
X283464Y1224803D03*
Y1228543D03*
X287204Y1236023D03*
X290944Y1224803D03*
Y1228543D03*
X294684Y1123818D03*
Y1131299D03*
X294685Y1198621D03*
X287203Y1093897D03*
X279723D03*
X290943Y1086417D03*
X287203Y1078936D03*
X290943Y1082677D03*
X283463Y1082676D03*
X279723Y1078936D03*
X283463Y1086416D03*
X283464Y1101376D03*
Y1105117D03*
X290944Y1101376D03*
X279723Y1097637D03*
X290944Y1105117D03*
X287203Y1097637D03*
X294684Y1116338D03*
X287203Y1075196D03*
X279723D03*
X268503Y1228543D03*
X264763Y1236023D03*
Y1250984D03*
X268503Y1243503D03*
Y1247243D03*
X272244Y1250984D03*
X275984Y1243503D03*
Y1247243D03*
X264763Y1254724D03*
X272244D03*
X264763Y1232283D03*
X268503Y1224803D03*
X275984D03*
X272244Y1236023D03*
X275984Y1228543D03*
X272244Y1232283D03*
X264762Y1097637D03*
X268503Y1105117D03*
X272243Y1097637D03*
X275984Y1105117D03*
X268503Y1101376D03*
X275984D03*
X264762Y1075196D03*
X272243D03*
Y1093897D03*
X264762D03*
X275982Y1082677D03*
Y1086417D03*
X268502Y1082676D03*
X272243Y1078936D03*
X268502Y1086416D03*
X264762Y1078936D03*
X261023Y1243503D03*
X246062D03*
X249803Y1250984D03*
X261023Y1247243D03*
X246062D03*
X257283Y1250984D03*
X253543Y1247243D03*
Y1243503D03*
X257283Y1254724D03*
X249803D03*
X261023Y1224803D03*
X253543Y1228543D03*
X249803Y1232283D03*
X246062Y1228543D03*
X257283Y1232283D03*
Y1236023D03*
X246062Y1224803D03*
X261023Y1228543D03*
X253543Y1224803D03*
X249803Y1236023D03*
X249802Y1097637D03*
X257282D03*
X253543Y1105117D03*
Y1101376D03*
X261023Y1105117D03*
Y1101376D03*
X249802Y1075196D03*
X257282D03*
X249802Y1093897D03*
X257282D03*
X249802Y1078936D03*
X261022Y1086417D03*
X253542Y1082676D03*
X257282Y1078936D03*
X246061Y1082677D03*
Y1086417D03*
X253542Y1086416D03*
X261022Y1082677D03*
X234842Y1254724D03*
X242322D03*
X238582Y1224803D03*
Y1228543D03*
X242322Y1236023D03*
Y1232283D03*
X234842D03*
Y1236023D03*
X238582Y1247243D03*
X242322Y1250984D03*
X234842D03*
X238582Y1243503D03*
X246062Y1105117D03*
X242321Y1097637D03*
X234841D03*
X238582Y1101376D03*
X246062D03*
X238582Y1105117D03*
X234841Y1075195D03*
X242321Y1075196D03*
X234841Y1093897D03*
X242321D03*
Y1078936D03*
X238581Y1082676D03*
X234841Y1078935D03*
X238581Y1086416D03*
X231102Y1224803D03*
X227362Y1093897D03*
X219881D03*
Y1078936D03*
X231102Y1082677D03*
Y1086417D03*
X223622Y1082677D03*
X227362Y1078936D03*
X223622Y1086417D03*
X231102Y1101376D03*
X219881Y1097637D03*
X223621Y1101376D03*
Y1105117D03*
X227362Y1097637D03*
X231102Y1105117D03*
X227362Y1075196D03*
X219881D03*
X208661Y1082677D03*
X216141Y1086417D03*
X201181Y1082677D03*
X216141D03*
X201181Y1086417D03*
X208661D03*
X204921Y1078936D03*
Y1097637D03*
X216141Y1101376D03*
X208661D03*
X212401Y1097637D03*
X208661Y1105117D03*
X216141D03*
X201181Y1101376D03*
Y1105117D03*
X204921Y1075196D03*
X212401D03*
Y1093897D03*
X204921D03*
X212401Y1078936D03*
X197440Y1093897D03*
Y1078936D03*
Y1097637D03*
Y1075196D03*
X609646Y1187401D03*
X613386D03*
X605905Y1228543D03*
Y1239763D03*
Y1247243D03*
X609646Y1236023D03*
Y1232283D03*
X613386Y1228543D03*
Y1224803D03*
X602165Y1206102D03*
X605905D03*
X602165Y1198621D03*
X605905D03*
X602165Y1191141D03*
X605905D03*
X602165Y1221062D03*
X605905D03*
Y1213582D03*
X602165D03*
Y1247243D03*
Y1239763D03*
Y1228543D03*
X613386Y1243503D03*
Y1247243D03*
X609646Y1250984D03*
Y1254724D03*
X613386Y1202362D03*
X609646D03*
X613386Y1194881D03*
X609646D03*
X613386Y1217322D03*
X609646D03*
Y1209842D03*
X613386D03*
X620866Y1187401D03*
Y1202362D03*
Y1194881D03*
Y1209842D03*
X624606Y1187401D03*
X632086Y1206102D03*
X628346D03*
X632086Y1198621D03*
X628346D03*
X624606Y1202362D03*
Y1194881D03*
X628346Y1191141D03*
X632086D03*
Y1213582D03*
X628346D03*
X624606Y1209842D03*
X639567Y1093897D03*
X635827Y1101376D03*
Y1105117D03*
X639567Y1097637D03*
X632086D03*
Y1075196D03*
X639567D03*
X647047Y1097637D03*
X635827Y1082677D03*
X647047Y1075196D03*
X643307Y1101376D03*
Y1105117D03*
X647047Y1078936D03*
X643307Y1082677D03*
Y1086417D03*
X639567Y1078936D03*
X635827Y1086417D03*
X632086Y1093897D03*
Y1078936D03*
X647047Y1093897D03*
X1077952Y1209842D03*
X1070472D03*
X1066732D03*
Y1217322D03*
X1070472D03*
X1062991Y1213582D03*
X1081692Y1209842D03*
X1085432Y1206102D03*
X1089172D03*
X1059251Y1221062D03*
Y1228543D03*
X1062991Y1221062D03*
X1070472Y1224803D03*
Y1228543D03*
X1066732Y1232283D03*
Y1236023D03*
X1074212D03*
Y1232283D03*
X1062991Y1228543D03*
X1066732Y1254724D03*
Y1250984D03*
X1070472Y1247243D03*
Y1243503D03*
X1062991Y1247243D03*
Y1239763D03*
X1085432Y1213582D03*
X1089172D03*
X770472Y1243503D03*
Y1247243D03*
X774212Y1254724D03*
Y1250984D03*
X777953Y1247243D03*
X781693D03*
X777953Y1239763D03*
X781693D03*
X1059251D03*
X774212Y1232283D03*
Y1236023D03*
X762992Y1243503D03*
Y1247243D03*
X766732Y1250984D03*
Y1254724D03*
X759252D03*
Y1250984D03*
X755512Y1247243D03*
Y1243503D03*
X759252Y1232283D03*
Y1236023D03*
X766732D03*
Y1232283D03*
X1059251Y1206102D03*
Y1213582D03*
X1062991Y1206102D03*
X1059251Y1247243D03*
X770472Y1112598D03*
X736810Y1093897D03*
Y1097637D03*
X658268Y1082677D03*
X759251Y1075196D03*
X654527Y1097637D03*
Y1093897D03*
X669488Y1078936D03*
X736810D03*
X744290Y1075196D03*
X721849Y1078936D03*
X725589Y1086416D03*
Y1082676D03*
X729330Y1078936D03*
X733069Y1086417D03*
Y1082677D03*
X729330Y1075196D03*
X718110Y1101376D03*
X714369Y1093897D03*
Y1097637D03*
X706889Y1093897D03*
Y1097637D03*
Y1078936D03*
X710629Y1086416D03*
Y1082676D03*
X714369Y1078936D03*
X718109Y1082677D03*
Y1086417D03*
X684449Y1078936D03*
X680709Y1086417D03*
Y1082677D03*
X676968Y1078936D03*
X673228Y1082677D03*
Y1086417D03*
X703149Y1105117D03*
X699408Y1097637D03*
X691928Y1093897D03*
Y1078935D03*
X695668Y1086416D03*
Y1082676D03*
X699408Y1078936D03*
X703148Y1086417D03*
Y1082677D03*
X691928Y1075195D03*
X699408Y1075196D03*
X691928Y1097637D03*
X695669Y1101376D03*
Y1105117D03*
X703149Y1101376D03*
X714369Y1075196D03*
X706889D03*
X710630Y1105117D03*
Y1101376D03*
X718110Y1105117D03*
X736810Y1075196D03*
X721849D03*
X684449Y1097637D03*
Y1093897D03*
X676968Y1097637D03*
Y1093897D03*
X688189Y1105117D03*
Y1101376D03*
X680708Y1105117D03*
Y1101376D03*
X673228Y1105117D03*
Y1101376D03*
X725590Y1105117D03*
X733071Y1101376D03*
Y1105117D03*
X725590Y1101376D03*
X665748Y1082677D03*
Y1086417D03*
X721849Y1097637D03*
X729330Y1093897D03*
X781693Y1213582D03*
X777953D03*
X774212Y1217322D03*
X770472D03*
Y1209842D03*
X774212D03*
X781693Y1198621D03*
X774212Y1202362D03*
X770472D03*
X777953Y1206102D03*
X781693D03*
X762992Y1217322D03*
X759252D03*
X755512Y1213582D03*
X759252Y1209842D03*
X762992D03*
Y1202362D03*
X759252D03*
X755512Y1206102D03*
Y1198621D03*
X751772Y1213582D03*
Y1206102D03*
Y1198621D03*
X759252Y1127559D03*
Y1135039D03*
X755512Y1131299D03*
X759252Y1112598D03*
Y1120078D03*
X755512Y1116338D03*
Y1123818D03*
X751771Y1131299D03*
Y1116338D03*
Y1123818D03*
X770472Y1135039D03*
X774212D03*
X777953Y1131299D03*
X781693D03*
X774212Y1127558D03*
X770472D03*
X777953Y1123818D03*
X781693D03*
X774212Y1120078D03*
X770472D03*
X777953Y1116338D03*
X781693D03*
X774212Y1112598D03*
X777953Y1108858D03*
X781693D03*
X751771Y1075196D03*
X658268Y1086417D03*
X669488Y1093897D03*
X774212D03*
X729330Y1097637D03*
X721849Y1093897D03*
X781693Y1101377D03*
X669488Y1097637D03*
X762992Y1120078D03*
X777953Y1101377D03*
X770472D03*
X654527Y1075196D03*
X770472Y1105117D03*
X669488Y1075196D03*
X774212Y1097637D03*
X654527Y1078936D03*
X774211D03*
X770471Y1086417D03*
Y1082677D03*
X777953Y1082676D03*
X781693D03*
Y1090157D03*
X777953D03*
X762992Y1112598D03*
Y1135039D03*
Y1127559D03*
X662008Y1093897D03*
X755511Y1082676D03*
X662008Y1097637D03*
X658268Y1105117D03*
X774211Y1075196D03*
X755511Y1086416D03*
X676968Y1075196D03*
X762991Y1082677D03*
X665748Y1105117D03*
X762992D03*
X684449Y1075196D03*
X755512Y1101376D03*
X766731Y1097637D03*
X759251Y1078936D03*
X755512Y1105117D03*
X766731Y1093897D03*
Y1078936D03*
X762991Y1086417D03*
X759251Y1097637D03*
X762992Y1101376D03*
X759251Y1093897D03*
X662008Y1075196D03*
X665748Y1101376D03*
X748030Y1086417D03*
X751771Y1078936D03*
X658268Y1101376D03*
X740550Y1086416D03*
X744290Y1097637D03*
X748031Y1105117D03*
X688189Y1086417D03*
Y1082677D03*
X766731Y1075196D03*
X740550Y1082676D03*
X748030Y1082677D03*
X744290Y1078936D03*
Y1093897D03*
X740551Y1101376D03*
X751771Y1097637D03*
Y1093897D03*
X748031Y1101376D03*
X740551Y1105117D03*
X662008Y1078936D03*
X699408Y1093897D03*
X1089172Y1075196D03*
Y1078936D03*
X1092913Y1086417D03*
Y1082677D03*
X1089172Y1097637D03*
Y1093897D03*
X1092913Y1101376D03*
X1096653Y1078936D03*
Y1097637D03*
Y1093897D03*
X1092913Y1105117D03*
X1089172Y1191141D03*
X1085432D03*
X1059251D03*
X1062991D03*
X1104133Y1075196D03*
Y1078936D03*
Y1093897D03*
Y1097637D03*
X1149015Y1236023D03*
Y1232283D03*
X1152755Y1224803D03*
X1156495Y1232283D03*
Y1236023D03*
X1152755Y1228543D03*
X1145275Y1224803D03*
X1152755Y1247243D03*
Y1243503D03*
X1156495Y1250984D03*
Y1254724D03*
X1163976Y1236023D03*
Y1232283D03*
X1167716Y1228543D03*
Y1224803D03*
X1175196D03*
Y1228543D03*
X1171456Y1232283D03*
Y1236023D03*
X1160235Y1224803D03*
Y1228543D03*
X1163976Y1254724D03*
Y1250984D03*
X1167716Y1243503D03*
Y1247243D03*
X1171456Y1250984D03*
Y1254724D03*
X1175196Y1247243D03*
Y1243503D03*
X1160235Y1247243D03*
Y1243503D03*
X1178936Y1236023D03*
Y1232283D03*
X1182676Y1224803D03*
Y1228543D03*
X1186417Y1236023D03*
Y1232283D03*
X1190157Y1228543D03*
Y1224803D03*
X1178936Y1254724D03*
Y1250984D03*
X1182676Y1243503D03*
Y1247243D03*
X1186417Y1250984D03*
Y1254724D03*
X1190157Y1247243D03*
Y1243503D03*
X1197637Y1224803D03*
Y1228543D03*
X1201377Y1232283D03*
Y1236023D03*
X1205117Y1228543D03*
Y1224803D03*
X1193897Y1236023D03*
Y1232283D03*
X1197637Y1247243D03*
X1201377Y1254724D03*
Y1250984D03*
X1197637Y1243503D03*
X1193897Y1254724D03*
Y1250984D03*
X1212598Y1224803D03*
Y1228543D03*
X1220078Y1224803D03*
Y1228543D03*
X1216338Y1232283D03*
Y1236023D03*
X1223818D03*
Y1232283D03*
X1208858Y1236023D03*
Y1232283D03*
X1227558Y1228543D03*
X1235039D03*
X1238779D03*
X1231298Y1232283D03*
Y1236023D03*
X1238779Y1239763D03*
X1235039D03*
X1220078Y1202362D03*
X1216338D03*
X1212598Y1206102D03*
Y1198621D03*
X1208858Y1206102D03*
Y1198621D03*
X1220078Y1217322D03*
X1216338D03*
X1212598Y1213582D03*
X1216338Y1209842D03*
X1220078D03*
X1208858Y1213582D03*
X1126574Y1075196D03*
X1119094D03*
X1126574Y1078936D03*
X1122834Y1086417D03*
Y1082677D03*
X1119094Y1078936D03*
X1115354Y1086417D03*
Y1082677D03*
X1126574Y1093897D03*
Y1097637D03*
X1119094Y1093897D03*
Y1097637D03*
X1115354Y1101376D03*
X1122834D03*
X1141535Y1075196D03*
X1134054D03*
X1141535Y1078936D03*
X1137795Y1086417D03*
Y1082677D03*
X1134054Y1078936D03*
X1130314Y1082677D03*
Y1086417D03*
X1141535Y1097637D03*
Y1093897D03*
X1134054Y1097637D03*
Y1093897D03*
X1137794Y1101376D03*
X1130314D03*
X1149014Y1075195D03*
X1156494Y1075196D03*
X1149014Y1078935D03*
X1152754Y1086416D03*
Y1082676D03*
X1156494Y1078936D03*
X1145275Y1086417D03*
Y1082677D03*
X1152755Y1101376D03*
X1156494Y1093897D03*
Y1097637D03*
X1149014D03*
Y1093897D03*
X1145275Y1101376D03*
X1163975Y1075196D03*
X1171455D03*
X1163975Y1078936D03*
X1167715Y1086416D03*
Y1082676D03*
X1171455Y1078936D03*
X1175195Y1082677D03*
Y1086417D03*
X1160234D03*
Y1082677D03*
X1175196Y1101376D03*
X1167716D03*
X1171455Y1093897D03*
Y1097637D03*
X1163975Y1093897D03*
Y1097637D03*
X1160235Y1101376D03*
X1178935Y1075196D03*
X1186416D03*
X1178935Y1078936D03*
X1182675Y1086416D03*
Y1082676D03*
X1186416Y1078936D03*
X1190155Y1086417D03*
Y1082677D03*
X1190157Y1101376D03*
X1182676D03*
X1186416Y1093897D03*
Y1097637D03*
X1178935Y1093897D03*
Y1097637D03*
X1201376Y1075196D03*
X1193896D03*
X1201376Y1078936D03*
X1197636Y1086416D03*
Y1082676D03*
X1205116Y1082677D03*
Y1086417D03*
X1193896Y1078936D03*
X1205117Y1101376D03*
X1197637D03*
X1201376Y1097637D03*
Y1093897D03*
X1193896Y1097637D03*
Y1093897D03*
X1216337Y1075196D03*
X1223817D03*
X1208857D03*
X1212597Y1082676D03*
Y1086416D03*
X1216337Y1078936D03*
X1223817D03*
X1220077Y1086417D03*
Y1082677D03*
X1208857Y1078936D03*
X1220078Y1101376D03*
X1212598D03*
X1223817Y1093897D03*
Y1097637D03*
X1216337Y1093897D03*
Y1097637D03*
X1208857D03*
Y1093897D03*
X1231297Y1075196D03*
Y1078936D03*
X1227557Y1086417D03*
Y1082677D03*
X1235039Y1082676D03*
X1238779D03*
Y1090157D03*
X1235039D03*
X1231298Y1097637D03*
Y1093897D03*
X1227558Y1101377D03*
X1238779D03*
X1235039D03*
X1115354Y1105117D03*
X1122834D03*
X1137794D03*
X1130314D03*
X1152755D03*
X1145275D03*
X1175196D03*
X1167716D03*
X1160235D03*
X1190157D03*
X1182676D03*
X1205117D03*
X1197637D03*
X1220078D03*
X1212598D03*
X1227558D03*
X1216338Y1112598D03*
Y1120078D03*
X1212598Y1116338D03*
Y1123818D03*
X1208857Y1116338D03*
Y1123818D03*
X1220078Y1112598D03*
Y1120078D03*
X1216338Y1127559D03*
X1212598Y1131299D03*
X1208857D03*
X1220078Y1127559D03*
X1235039Y1123818D03*
X1238779D03*
X1231298Y1120078D03*
X1227558D03*
X1235039Y1116338D03*
X1238779D03*
X1227558Y1112598D03*
X1231298D03*
X1235039Y1108858D03*
X1238779D03*
X1235039Y1131299D03*
X1238779D03*
X1231298Y1127558D03*
X1227558D03*
X1216338Y1135039D03*
X1220078D03*
X1527559Y1228543D03*
X1523819Y1232283D03*
Y1236023D03*
X1520078Y1228543D03*
X1523819Y1254724D03*
Y1250984D03*
X1527559Y1247243D03*
Y1243503D03*
X1520078Y1247243D03*
Y1239763D03*
X1542519Y1213582D03*
X1546259D03*
X1516338Y1247243D03*
X1527559Y1224803D03*
X1520078Y1221062D03*
X1516338Y1239763D03*
Y1191141D03*
Y1198621D03*
Y1206102D03*
Y1213582D03*
X1535039Y1187401D03*
X1527559D03*
X1523819D03*
X1535039Y1194881D03*
Y1202362D03*
X1523819Y1194881D03*
X1527559D03*
X1523819Y1202362D03*
X1527559D03*
X1520078Y1191141D03*
Y1198621D03*
Y1206102D03*
X1535039Y1209842D03*
X1527559D03*
X1523819D03*
Y1217322D03*
X1527559D03*
X1520078Y1213582D03*
X1538779Y1187401D03*
Y1194881D03*
Y1202362D03*
Y1209842D03*
X1546259Y1191141D03*
X1542519D03*
Y1198621D03*
X1546259D03*
X1542519Y1206102D03*
X1546259D03*
X1516338Y1221062D03*
Y1228543D03*
X1695866Y1239763D03*
X1692126D03*
X1695866Y1247243D03*
X1692126D03*
X1688385Y1250984D03*
Y1254724D03*
X1684645Y1247243D03*
Y1243503D03*
X1665945Y1254724D03*
X1688385Y1232283D03*
Y1236023D03*
X1673425Y1232283D03*
Y1236023D03*
X1680905D03*
Y1232283D03*
X1677165Y1243503D03*
Y1247243D03*
X1680905Y1250984D03*
Y1254724D03*
X1673425D03*
Y1250984D03*
X1669685Y1247243D03*
Y1243503D03*
X1557480Y1086417D03*
Y1082677D03*
X1553740Y1078936D03*
X1561220Y1093897D03*
Y1097637D03*
X1557480Y1101376D03*
X1553740Y1097637D03*
Y1093897D03*
X1546259Y1078936D03*
X1550000Y1086417D03*
Y1082677D03*
X1546259Y1097637D03*
Y1093897D03*
X1550000Y1101376D03*
X1561220Y1075196D03*
X1553740D03*
X1546259D03*
X1550000Y1105117D03*
X1557480D03*
X1583661Y1075196D03*
X1576181D03*
X1583661Y1078936D03*
X1579921Y1086417D03*
Y1082677D03*
X1576181Y1078936D03*
X1572441Y1086417D03*
Y1082677D03*
X1583661Y1093897D03*
Y1097637D03*
X1576181Y1093897D03*
Y1097637D03*
X1572441Y1101376D03*
X1579921D03*
X1598622Y1075196D03*
X1591141D03*
X1598622Y1078936D03*
X1594882Y1086417D03*
Y1082677D03*
X1591141Y1078936D03*
X1587401Y1082677D03*
Y1086417D03*
X1598622Y1097637D03*
Y1093897D03*
X1591141Y1097637D03*
Y1093897D03*
X1594881Y1101376D03*
X1587401D03*
X1606101Y1075195D03*
X1613581Y1075196D03*
X1606101Y1078935D03*
X1609841Y1086416D03*
Y1082676D03*
X1613581Y1078936D03*
X1602362Y1086417D03*
Y1082677D03*
X1609842Y1101376D03*
X1613581Y1093897D03*
Y1097637D03*
X1606101D03*
Y1093897D03*
X1602362Y1101376D03*
X1621062Y1075196D03*
X1628542D03*
X1621062Y1078936D03*
X1624802Y1086416D03*
Y1082676D03*
X1628542Y1078936D03*
X1632282Y1082677D03*
Y1086417D03*
X1695866Y1213582D03*
X1692126D03*
X1688385Y1217322D03*
X1684645D03*
Y1209842D03*
X1688385D03*
X1665945Y1198621D03*
X1677165Y1217322D03*
X1673425D03*
X1669685Y1213582D03*
X1673425Y1209842D03*
X1677165D03*
X1665945Y1213582D03*
X1695866Y1198621D03*
X1692126D03*
X1688385Y1202362D03*
X1684645D03*
X1692126Y1206102D03*
X1695866D03*
X1677165Y1202362D03*
X1673425D03*
X1669685Y1206102D03*
Y1198621D03*
X1617321Y1082677D03*
Y1086417D03*
X1632283Y1105117D03*
X1617322D03*
X1639763D03*
X1662204D03*
X1654724D03*
X1677165D03*
X1669685D03*
X1684645D03*
X1673425Y1112598D03*
Y1120078D03*
X1669685Y1116338D03*
Y1123818D03*
X1665944Y1116338D03*
Y1123818D03*
X1677165Y1112598D03*
Y1120078D03*
X1673425Y1127559D03*
X1669685Y1131299D03*
X1665944D03*
X1677165Y1127559D03*
X1692126Y1123818D03*
X1695866D03*
X1688385Y1120078D03*
X1684645D03*
X1692126Y1116338D03*
X1695866D03*
X1684645Y1112598D03*
X1688385D03*
X1692126Y1108858D03*
X1695866D03*
X1692126Y1131299D03*
X1695866D03*
X1688385Y1127558D03*
X1684645D03*
X1677165Y1135039D03*
X1628542Y1093897D03*
X1647244Y1105117D03*
X1624803D03*
X1650983Y1097637D03*
Y1093897D03*
X1673424Y1075196D03*
X1680904D03*
X1665944D03*
X1669684Y1082676D03*
Y1086416D03*
X1673424Y1078936D03*
X1680904D03*
X1677164Y1086417D03*
Y1082677D03*
X1665944Y1078936D03*
X1677165Y1101376D03*
X1669685D03*
X1680904Y1093897D03*
Y1097637D03*
X1673424Y1093897D03*
Y1097637D03*
X1665944D03*
Y1093897D03*
X1688384Y1075196D03*
Y1078936D03*
X1684644Y1086417D03*
Y1082677D03*
X1692126Y1082676D03*
X1695866D03*
Y1090157D03*
X1692126D03*
X1688385Y1097637D03*
Y1093897D03*
X1684645Y1101377D03*
X1695866D03*
X1692126D03*
X1572441Y1105117D03*
X1579921D03*
X1594881D03*
X1587401D03*
X1609842D03*
X1602362D03*
X1643503Y1078936D03*
X1647242Y1082677D03*
X1636022Y1075196D03*
X1643503D03*
X1639762Y1086416D03*
Y1082676D03*
X1658463Y1097637D03*
X1636022Y1078936D03*
X1647242Y1086417D03*
X1617322Y1101376D03*
X1639763D03*
X1636022Y1097637D03*
Y1093897D03*
X1662204Y1101376D03*
X1658463Y1075196D03*
X1650983D03*
X1658463Y1078936D03*
X1654723Y1086416D03*
Y1082676D03*
X1662203Y1082677D03*
Y1086417D03*
X1621062Y1093897D03*
X1658463D03*
X1628542Y1097637D03*
X1643503D03*
Y1093897D03*
X1647244Y1101376D03*
X1650983Y1078936D03*
X1621062Y1097637D03*
X1632283Y1101376D03*
X1624803D03*
X1654724D03*
G54D43*
X1657510Y374862D03*
X286250D03*
G54D45*
X51043Y144095D03*
X57933Y66811D03*
X153405Y144095D03*
X160295Y66811D03*
X255767Y144095D03*
X262657Y66811D03*
X358129Y144095D03*
X365019Y66811D03*
X508130Y144095D03*
X515020Y66811D03*
X610492Y144095D03*
X617382Y66811D03*
X712854Y144095D03*
X719744Y66811D03*
X822106D03*
X972106D03*
X1074468D03*
X1176830D03*
X1272302Y144095D03*
X1279192Y66811D03*
X1422303Y144095D03*
X1429193Y66811D03*
X1524665Y144095D03*
X1531555Y66811D03*
X1633917D03*
X1736279D03*
G54D44*
X279360Y630650D03*
X190325Y374862D03*
X1650620Y630650D03*
G54D37*
X1817323Y56693D03*
G54D38*
X7982Y1527335D03*
X28388Y134215D03*
X35688Y127128D03*
X28388Y120042D03*
X35688Y112955D03*
X130750Y134215D03*
Y120042D03*
X138290Y428160D03*
X148692Y421047D03*
X138290Y413987D03*
X148692Y406874D03*
X140690Y399813D03*
X148692Y392701D03*
X138050Y127128D03*
Y112955D03*
X148692Y435221D03*
X138290Y442333D03*
X205680Y399782D03*
X212980Y406868D03*
Y392695D03*
Y435215D03*
X205680Y442302D03*
Y413955D03*
Y428128D03*
X212980Y421041D03*
X233112Y134215D03*
X240412Y127128D03*
Y112955D03*
X233112Y120042D03*
X335474Y134215D03*
X342774Y127128D03*
Y112955D03*
X335474Y120042D03*
X533092Y127096D03*
Y112923D03*
X543494Y134209D03*
Y120035D03*
X635454Y127096D03*
Y112923D03*
X645856Y134209D03*
Y120035D03*
X748218Y134209D03*
X737816Y127096D03*
X748218Y120035D03*
X737816Y112923D03*
X840178Y127096D03*
Y112923D03*
X850580Y134209D03*
Y120035D03*
X893284Y235040D03*
X990178Y127096D03*
X1000580Y134209D03*
X1092540Y127096D03*
X1102942Y134209D03*
Y120035D03*
X1205304Y134209D03*
X1194902Y127096D03*
X1205304Y120035D03*
X1297264Y127096D03*
X1307666Y134209D03*
Y120035D03*
X1399648Y134215D03*
Y120042D03*
X1406948Y127128D03*
Y112955D03*
X1509310Y127128D03*
X1502010Y134215D03*
X1509310Y112955D03*
X1502010Y120042D03*
X1576940Y442302D03*
Y413955D03*
Y428128D03*
Y399782D03*
X1584240Y435215D03*
Y421041D03*
Y406868D03*
X1604372Y134215D03*
X1611672Y127128D03*
X1604372Y120042D03*
X1611672Y112955D03*
X1706734Y134215D03*
Y120042D03*
X1714034Y127128D03*
Y112955D03*
X138290Y471087D03*
X148692Y478199D03*
X212980Y471081D03*
X205680Y478168D03*
X1576940D03*
X1584240Y471081D03*
X148692Y536506D03*
X138290Y529394D03*
X148692Y522333D03*
X138290Y515221D03*
X148692Y492373D03*
X138290Y485260D03*
X205680Y492341D03*
X212980Y485254D03*
Y529388D03*
X205680Y536475D03*
Y522302D03*
X212980Y515215D03*
X1576940Y492341D03*
X1584240Y485254D03*
X1754906Y822634D03*
G54D40*
X213969Y1460153D03*
Y1449153D03*
G54D62*
X1817323Y1567323D03*
G54D57*
X820079Y388583D03*
X1020866D03*
G54D39*
X76005Y127096D03*
X86407Y134209D03*
Y120035D03*
X178367Y127096D03*
X188769Y134209D03*
Y120035D03*
X264005Y469037D03*
X280729Y127096D03*
X291131Y134209D03*
Y120035D03*
X295011Y461917D03*
X320993Y469005D03*
X393493Y134209D03*
X383091Y127096D03*
X393493Y120035D03*
X485475Y134215D03*
Y120042D03*
X492775Y127128D03*
Y112955D03*
X587837Y134215D03*
Y120042D03*
X595137Y127128D03*
Y112955D03*
X690199Y120042D03*
X697499Y112955D03*
X690199Y134215D03*
X697499Y127128D03*
X792561Y134215D03*
X799861Y127128D03*
X792561Y120042D03*
X799861Y112955D03*
X942561Y134215D03*
Y120042D03*
X949861Y127128D03*
Y112955D03*
X1044923Y134215D03*
X1052223Y127128D03*
X1044923Y120042D03*
X1052223Y112955D03*
X1147285Y134215D03*
Y120042D03*
X1154585Y112955D03*
Y127128D03*
X1249647Y120042D03*
X1256947Y112955D03*
X1249647Y134215D03*
X1256947Y127128D03*
X1447265Y127096D03*
Y112923D03*
X1457667Y134209D03*
Y120035D03*
X1549627Y127096D03*
X1560029Y134209D03*
X1549627Y112923D03*
X1560029Y120035D03*
X1651989Y127096D03*
Y112923D03*
X1635265Y469037D03*
X1662391Y134209D03*
Y120035D03*
X1666271Y461919D03*
X1692253Y469006D03*
X1754351Y127096D03*
Y112923D03*
X1764753Y120035D03*
Y134209D03*
X256705Y476124D03*
X264005Y483210D03*
X331395Y476118D03*
X320993Y483179D03*
X1627965Y476124D03*
X1635265Y483210D03*
X1702655Y476118D03*
X1692253Y483179D03*
X174923Y543562D03*
X264005Y513171D03*
X256705Y520258D03*
Y490297D03*
Y612817D03*
X264005Y605730D03*
X256705Y598644D03*
X264005Y591557D03*
Y577384D03*
X256705Y584471D03*
X264005Y563210D03*
X256705Y570297D03*
Y534431D03*
X264005Y527344D03*
X320993Y513139D03*
Y591525D03*
Y605699D03*
Y577352D03*
Y563179D03*
Y527313D03*
X331395Y490291D03*
Y612811D03*
Y598638D03*
Y584465D03*
Y570291D03*
Y534425D03*
Y520252D03*
X1627965Y534431D03*
Y520258D03*
Y490297D03*
X1635265Y527344D03*
Y513171D03*
X1692253Y527313D03*
Y513139D03*
X1702655Y534425D03*
Y520252D03*
Y490291D03*
X397267Y1516347D03*
X1009333Y1344993D03*
X1627965Y584471D03*
Y570297D03*
Y612817D03*
Y598644D03*
X1635265Y605730D03*
Y591557D03*
Y577384D03*
Y563210D03*
X1692253Y605699D03*
Y591525D03*
Y577352D03*
Y563179D03*
X1702655Y612811D03*
Y598638D03*
Y584465D03*
Y570291D03*
G54D60*
X770472Y1490945D03*
X1070472D03*
G54D42*
X26789Y1373669D03*
X1809883Y120792D03*
X184851Y334492D03*
X1796847Y1517889D03*
G54D48*
X837480Y61614D03*
X792973Y81595D03*
X530394Y61614D03*
X73307D03*
X28819Y81575D03*
X1444567Y61614D03*
X1546929D03*
X942973Y81595D03*
X1751654Y61614D03*
X1250060Y81595D03*
X1192205Y61614D03*
X1089843D03*
X690611Y81595D03*
X380394Y61614D03*
X233543Y81575D03*
X278032Y61614D03*
X1502441Y81575D03*
X1649291Y61614D03*
X1147697Y81595D03*
X1045335D03*
X987480Y61614D03*
X588248Y81594D03*
X632756Y61614D03*
X131181Y81575D03*
X335906D03*
X1294567Y61614D03*
X1604784Y81595D03*
X1400060D03*
X1707146D03*
X485886D03*
X735118Y61614D03*
X175669D03*
G54D51*
X352952Y1263386D03*
Y1066535D03*
X810038D03*
X1267125Y1263386D03*
Y1066535D03*
X1487991Y1263386D03*
X1724212Y1066535D03*
G54D58*
X573818D03*
X810038Y1263386D03*
X1030905Y1066535D03*
X1724212Y1263386D03*
X1487991Y1066535D03*
%LPD*%
G75*
G36*
G01X26565Y116496D02*
G03I-577J0D01*
G37*
G36*
G01D02*
G03I-577J0D01*
G37*
G36*
G01X33865Y109409D02*
G03I-577J0D01*
G37*
G36*
G01D02*
G03I-577J0D01*
G37*
G36*
G01Y116496D02*
G03I-577J0D01*
G37*
G36*
G01D02*
G03I-577J0D01*
G37*
G36*
G01X31365D02*
G03I-577J0D01*
G37*
G36*
G01D02*
G03I-577J0D01*
G37*
G36*
G01Y123582D02*
G03I-577J0D01*
G37*
G36*
G01D02*
G03I-577J0D01*
G37*
G36*
G01X33865D02*
G03I-577J0D01*
G37*
G36*
G01D02*
G03I-577J0D01*
G37*
G36*
G01X26565D02*
G03I-577J0D01*
G37*
G36*
G01D02*
G03I-577J0D01*
G37*
G36*
G01X33865Y130669D02*
G03I-577J0D01*
G37*
G36*
G01D02*
G03I-577J0D01*
G37*
G36*
G01X31365D02*
G03I-577J0D01*
G37*
G36*
G01D02*
G03I-577J0D01*
G37*
G36*
G01X26565D02*
G03I-577J0D01*
G37*
G36*
G01D02*
G03I-577J0D01*
G37*
G36*
G01X31365Y137755D02*
G03I-577J0D01*
G37*
G36*
G01D02*
G03I-577J0D01*
G37*
G36*
G01X26565D02*
G03I-577J0D01*
G37*
G36*
G01D02*
G03I-577J0D01*
G37*
G36*
G01X114240Y881266D02*
G03I-639J0D01*
G37*
G36*
G01X128927Y116496D02*
G03I-577J0D01*
G37*
G36*
G01D02*
G03I-577J0D01*
G37*
G36*
G01X133727D02*
G03I-577J0D01*
G37*
G36*
G01D02*
G03I-577J0D01*
G37*
G36*
G01Y123582D02*
G03I-577J0D01*
G37*
G36*
G01X128927D02*
G03I-577J0D01*
G37*
G36*
G01X133727Y130669D02*
G03I-577J0D01*
G37*
G36*
G01X128927D02*
G03I-577J0D01*
G37*
G36*
G01Y137755D02*
G03I-577J0D01*
G37*
G36*
G01X133727D02*
G03I-577J0D01*
G37*
G36*
G01X127706Y891495D02*
G03I-639J0D01*
G37*
G36*
G01X136227Y116496D02*
G03I-577J0D01*
G37*
G36*
G01D02*
G03I-577J0D01*
G37*
G36*
G01Y109409D02*
G03I-577J0D01*
G37*
G36*
G01D02*
G03I-577J0D01*
G37*
G36*
G01Y123582D02*
G03I-577J0D01*
G37*
G36*
G01Y130669D02*
G03I-577J0D01*
G37*
G36*
G01X241459Y681478D02*
X250876D01*
G02X251018Y681419I0J-200D01*
G01X251965Y680472D01*
G02X252024Y680330I-141J-142D01*
G01Y637830D01*
G02X251926Y637658I-200J0D01*
G03Y635070I761J-1294D01*
G02X252024Y634898I-102J-172D01*
G01Y582069D01*
G02X251965Y581927I-200J0D01*
G01X226114Y556076D01*
G02X225973Y556017I-142J141D01*
G01X225652Y556016D01*
X225580Y556045D01*
X225551Y556073D01*
G03X224500Y556502I-1051J-1073D01*
G03X222998Y555000I0J-1502D01*
G03X223427Y553949I1502J0D01*
G01X223455Y553920D01*
X223484Y553848D01*
X223483Y553527D01*
G02X223424Y553386I-200J1D01*
G01X219833Y549795D01*
G02X219691Y549736I-142J141D01*
G01X187678D01*
G02X187537Y549794I0J200D01*
G01X187308Y550021D01*
X187278Y550093D01*
Y550133D01*
G03X186764Y551254I-1502J-10D01*
G01X186733Y551282D01*
X186697Y551355D01*
X186681Y551727D01*
X186709Y551803D01*
X186738Y551833D01*
G03X187156Y552872I-1084J1040D01*
G03X184152I-1502J0D01*
G03X184666Y551741I1501J0D01*
G01X184697Y551713D01*
X184733Y551640D01*
X184749Y551268D01*
X184721Y551192D01*
X184692Y551162D01*
G03X184274Y550133I1084J-1040D01*
G01Y550093D01*
X184244Y550021D01*
X184015Y549794D01*
G02X183874Y549736I-141J142D01*
G01X154443D01*
G02X154301Y549795I0J200D01*
G01X143161Y560935D01*
G02X143102Y561077I141J142D01*
G01Y623131D01*
G02X143161Y623273I200J0D01*
G01X145781Y625893D01*
G02X145923Y625952I142J-141D01*
G01X190331D01*
G02X190473Y625893I0J-200D01*
G01X195222Y621144D01*
G02X195281Y621002I-141J-142D01*
G01Y611888D01*
G02X195222Y611746I-200J0D01*
G01X192145Y608669D01*
G02X192003Y608610I-142J141D01*
G01X159158D01*
G03X159016Y608551I0J-200D01*
G01X153810Y603345D01*
G03X153751Y603203I141J-142D01*
G01Y574312D01*
G03X153810Y574170I200J0D01*
G01X163123Y564857D01*
G03X163265Y564798I142J141D01*
G01X202246D01*
G02X202422Y564694I1J-200D01*
G03X205058I1318J720D01*
G02X205234Y564798I175J-96D01*
G01X207673D01*
G03X207815Y564857I0J200D01*
G01X238122Y595164D01*
G03X238181Y595306I-141J142D01*
G01Y678200D01*
G02X238240Y678342I200J0D01*
G01X241317Y681419D01*
G02X241459Y681478I142J-141D01*
G37*
G36*
G01X209040Y96471D02*
G03I-577J0D01*
G37*
G36*
G01D02*
G03I-577J0D01*
G37*
G36*
G01X231289Y116496D02*
G03I-577J0D01*
G37*
G36*
G01D02*
G03I-577J0D01*
G37*
G36*
G01Y130669D02*
G03I-577J0D01*
G37*
G36*
G01Y123582D02*
G03I-577J0D01*
G37*
G36*
G01Y137755D02*
G03I-577J0D01*
G37*
G36*
G01X238589Y116496D02*
G03I-577J0D01*
G37*
G36*
G01D02*
G03I-577J0D01*
G37*
G36*
G01X236089D02*
G03I-577J0D01*
G37*
G36*
G01D02*
G03I-577J0D01*
G37*
G36*
G01X238589Y109409D02*
G03I-577J0D01*
G37*
G36*
G01D02*
G03I-577J0D01*
G37*
G36*
G01Y130669D02*
G03I-577J0D01*
G37*
G36*
G01X236089D02*
G03I-577J0D01*
G37*
G36*
G01X238589Y123582D02*
G03I-577J0D01*
G37*
G36*
G01X236089D02*
G03I-577J0D01*
G37*
G36*
G01Y137755D02*
G03I-577J0D01*
G37*
G36*
G01X257858Y312081D02*
G03I-632J0D01*
G37*
G36*
G01X311459Y96612D02*
G03I-577J0D01*
G37*
G36*
G01D02*
G03I-577J0D01*
G37*
G36*
G01X301735Y380307D02*
G03I-577J0D01*
G37*
G36*
G01X301885Y395346D02*
G03I-577J0D01*
G37*
G36*
G01X301970Y400039D02*
G03I-577J0D01*
G37*
G36*
G01X340951Y116496D02*
G03I-577J0D01*
G37*
G36*
G01D02*
G03I-577J0D01*
G37*
G36*
G01Y109409D02*
G03I-577J0D01*
G37*
G36*
G01D02*
G03I-577J0D01*
G37*
G36*
G01X333651Y116496D02*
G03I-577J0D01*
G37*
G36*
G01D02*
G03I-577J0D01*
G37*
G36*
G01X338451D02*
G03I-577J0D01*
G37*
G36*
G01D02*
G03I-577J0D01*
G37*
G36*
G01X333651Y123582D02*
G03I-577J0D01*
G37*
G36*
G01D02*
G03I-577J0D01*
G37*
G36*
G01X340951Y130668D02*
G03I-577J0D01*
G37*
G36*
G01X338451D02*
G03I-577J0D01*
G37*
G36*
G01X333651D02*
G03I-577J0D01*
G37*
G36*
G01X340951Y123582D02*
G03I-577J0D01*
G37*
G36*
G01D02*
G03I-577J0D01*
G37*
G36*
G01X338451D02*
G03I-577J0D01*
G37*
G36*
G01D02*
G03I-577J0D01*
G37*
G36*
G01Y137755D02*
G03I-577J0D01*
G37*
G36*
G01X333651D02*
G03I-577J0D01*
G37*
G36*
G01X345651Y116496D02*
G03I-577J0D01*
G37*
G36*
G01Y109408D02*
G03I-577J0D01*
G37*
G36*
G01X349007Y322284D02*
G03I-632J0D01*
G37*
G36*
G01X349600Y333138D02*
G03I-632J0D01*
G37*
G36*
G01X356506Y1132042D02*
G03I-577J0D01*
G37*
G36*
G01X352140Y1132410D02*
G03I-577J0D01*
G37*
G36*
G01X365565Y374232D02*
G03I-632J0D01*
G37*
G36*
G01X368583Y946082D02*
G03I-639J0D01*
G37*
G36*
G01X408132Y354142D02*
G03I-639J0D01*
G37*
G36*
G01X467014Y366365D02*
G03I-639J0D01*
G37*
G36*
G01X471028Y389553D02*
G03I-639J0D01*
G37*
G36*
G01X490952Y116496D02*
G03I-577J0D01*
G37*
G36*
G01X483652D02*
G03I-577J0D01*
G37*
G36*
G01D02*
G03I-577J0D01*
G37*
G36*
G01X488452D02*
G03I-577J0D01*
G37*
G36*
G01D02*
G03I-577J0D01*
G37*
G36*
G01X490952Y109409D02*
G03I-577J0D01*
G37*
G36*
G01D02*
G03I-577J0D01*
G37*
G36*
G01Y116496D02*
G03I-577J0D01*
G37*
G36*
G01X483652Y130669D02*
G03I-577J0D01*
G37*
G36*
G01D02*
G03I-577J0D01*
G37*
G36*
G01X488452Y123582D02*
G03I-577J0D01*
G37*
G36*
G01D02*
G03I-577J0D01*
G37*
G36*
G01Y130669D02*
G03I-577J0D01*
G37*
G36*
G01D02*
G03I-577J0D01*
G37*
G36*
G01X490952Y123582D02*
G03I-577J0D01*
G37*
G36*
G01D02*
G03I-577J0D01*
G37*
G36*
G01Y130669D02*
G03I-577J0D01*
G37*
G36*
G01D02*
G03I-577J0D01*
G37*
G36*
G01X483652Y123582D02*
G03I-577J0D01*
G37*
G36*
G01D02*
G03I-577J0D01*
G37*
G36*
G01Y137755D02*
G03I-577J0D01*
G37*
G36*
G01D02*
G03I-577J0D01*
G37*
G36*
G01X488452D02*
G03I-577J0D01*
G37*
G36*
G01D02*
G03I-577J0D01*
G37*
G36*
G01X485644Y659771D02*
G03I-639J0D01*
G37*
G36*
G01X525292Y643595D02*
G03I-639J0D01*
G37*
G36*
G01X563801Y96812D02*
G03I-577J0D01*
G37*
G36*
G01D02*
G03I-577J0D01*
G37*
G36*
G01X586014Y116496D02*
G03I-577J0D01*
G37*
G36*
G01D02*
G03I-577J0D01*
G37*
G36*
G01Y123582D02*
G03I-577J0D01*
G37*
G36*
G01D02*
G03I-577J0D01*
G37*
G36*
G01Y130669D02*
G03I-577J0D01*
G37*
G36*
G01D02*
G03I-577J0D01*
G37*
G36*
G01Y137755D02*
G03I-577J0D01*
G37*
G36*
G01D02*
G03I-577J0D01*
G37*
G36*
G01X593314Y109409D02*
G03I-577J0D01*
G37*
G36*
G01D02*
G03I-577J0D01*
G37*
G36*
G01X590814Y116496D02*
G03I-577J0D01*
G37*
G36*
G01D02*
G03I-577J0D01*
G37*
G36*
G01X593314D02*
G03I-577J0D01*
G37*
G36*
G01D02*
G03I-577J0D01*
G37*
G36*
G01X590814Y123582D02*
G03I-577J0D01*
G37*
G36*
G01Y130669D02*
G03I-577J0D01*
G37*
G36*
G01D02*
G03I-577J0D01*
G37*
G36*
G01X593314D02*
G03I-577J0D01*
G37*
G36*
G01D02*
G03I-577J0D01*
G37*
G36*
G01Y123582D02*
G03I-577J0D01*
G37*
G36*
G01D02*
G03I-577J0D01*
G37*
G36*
G01X590814D02*
G03I-577J0D01*
G37*
G36*
G01Y137755D02*
G03I-577J0D01*
G37*
G36*
G01D02*
G03I-577J0D01*
G37*
G36*
G01X603860Y390223D02*
G03I-577J0D01*
G37*
G36*
G01X600850Y397335D02*
G03I-577J0D01*
G37*
G36*
G01X603860Y395179D02*
G03I-577J0D01*
G37*
G36*
G01Y404396D02*
G03I-577J0D01*
G37*
G36*
G01Y409352D02*
G03I-577J0D01*
G37*
G36*
G01X595858Y402291D02*
G03I-577J0D01*
G37*
G36*
G01X600850D02*
G03I-577J0D01*
G37*
G36*
G01X595858Y397335D02*
G03I-577J0D01*
G37*
G36*
G01X598450Y425682D02*
G03I-577J0D01*
G37*
G36*
G01X593458D02*
G03I-577J0D01*
G37*
G36*
G01X598450Y416465D02*
G03I-577J0D01*
G37*
G36*
G01Y411509D02*
G03I-577J0D01*
G37*
G36*
G01X593458Y416465D02*
G03I-577J0D01*
G37*
G36*
G01Y411509D02*
G03I-577J0D01*
G37*
G36*
G01X603860Y418569D02*
G03I-577J0D01*
G37*
G36*
G01Y423525D02*
G03I-577J0D01*
G37*
G36*
G01X593458Y439855D02*
G03I-577J0D01*
G37*
G36*
G01X598450Y430638D02*
G03I-577J0D01*
G37*
G36*
G01X593458D02*
G03I-577J0D01*
G37*
G36*
G01X603860Y432743D02*
G03I-577J0D01*
G37*
G36*
G01Y437699D02*
G03I-577J0D01*
G37*
G36*
G01X598450Y439855D02*
G03I-577J0D01*
G37*
G36*
G01Y444811D02*
G03I-577J0D01*
G37*
G36*
G01X593458D02*
G03I-577J0D01*
G37*
G36*
G01Y473565D02*
G03I-577J0D01*
G37*
G36*
G01X598450D02*
G03I-577J0D01*
G37*
G36*
G01X593458Y468609D02*
G03I-577J0D01*
G37*
G36*
G01X598450D02*
G03I-577J0D01*
G37*
G36*
G01X603860Y489895D02*
G03I-577J0D01*
G37*
G36*
G01X593458Y487738D02*
G03I-577J0D01*
G37*
G36*
G01X598450D02*
G03I-577J0D01*
G37*
G36*
G01X603860Y480677D02*
G03I-577J0D01*
G37*
G36*
G01Y475721D02*
G03I-577J0D01*
G37*
G36*
G01X593458Y482782D02*
G03I-577J0D01*
G37*
G36*
G01X598450D02*
G03I-577J0D01*
G37*
G36*
G01X603860Y494851D02*
G03I-577J0D01*
G37*
G36*
G01X593458Y517699D02*
G03I-577J0D01*
G37*
G36*
G01X598450D02*
G03I-577J0D01*
G37*
G36*
G01X603860Y519855D02*
G03I-577J0D01*
G37*
G36*
G01X593458Y526916D02*
G03I-577J0D01*
G37*
G36*
G01X598450Y531872D02*
G03I-577J0D01*
G37*
G36*
G01X593458D02*
G03I-577J0D01*
G37*
G36*
G01X603860Y524811D02*
G03I-577J0D01*
G37*
G36*
G01Y538984D02*
G03I-577J0D01*
G37*
G36*
G01Y534028D02*
G03I-577J0D01*
G37*
G36*
G01X598450Y526916D02*
G03I-577J0D01*
G37*
G36*
G01X608852Y390223D02*
G03I-577J0D01*
G37*
G36*
G01Y395179D02*
G03I-577J0D01*
G37*
G36*
G01Y404396D02*
G03I-577J0D01*
G37*
G36*
G01Y409352D02*
G03I-577J0D01*
G37*
G36*
G01Y423525D02*
G03I-577J0D01*
G37*
G36*
G01Y418569D02*
G03I-577J0D01*
G37*
G36*
G01Y432743D02*
G03I-577J0D01*
G37*
G36*
G01Y437699D02*
G03I-577J0D01*
G37*
G36*
G01Y489895D02*
G03I-577J0D01*
G37*
G36*
G01Y480677D02*
G03I-577J0D01*
G37*
G36*
G01Y475721D02*
G03I-577J0D01*
G37*
G36*
G01Y494851D02*
G03I-577J0D01*
G37*
G36*
G01Y519855D02*
G03I-577J0D01*
G37*
G36*
G01Y538984D02*
G03I-577J0D01*
G37*
G36*
G01Y534028D02*
G03I-577J0D01*
G37*
G36*
G01Y524811D02*
G03I-577J0D01*
G37*
G36*
G01X666000Y96852D02*
G03I-577J0D01*
G37*
G36*
G01D02*
G03I-577J0D01*
G37*
G36*
G01X668244Y389152D02*
G03I-577J0D01*
G37*
G36*
G01X665744Y403326D02*
G03I-577J0D01*
G37*
G36*
G01X668244Y403325D02*
G03I-577J0D01*
G37*
G36*
G01X665744Y396239D02*
G03I-577J0D01*
G37*
G36*
G01X668244D02*
G03I-577J0D01*
G37*
G36*
G01X665744Y410412D02*
G03I-577J0D01*
G37*
G36*
G01X668244D02*
G03I-577J0D01*
G37*
G36*
G01Y417498D02*
G03I-577J0D01*
G37*
G36*
G01X665744Y424585D02*
G03I-577J0D01*
G37*
G36*
G01X668244D02*
G03I-577J0D01*
G37*
G36*
G01X665744Y417499D02*
G03I-577J0D01*
G37*
G36*
G01Y431672D02*
G03I-577J0D01*
G37*
G36*
G01Y438759D02*
G03I-577J0D01*
G37*
G36*
G01X668244D02*
G03I-577J0D01*
G37*
G36*
G01Y431672D02*
G03I-577J0D01*
G37*
G36*
G01X665744Y445846D02*
G03I-577J0D01*
G37*
G36*
G01X668244Y467538D02*
G03I-577J0D01*
G37*
G36*
G01X665744Y488798D02*
G03I-577J0D01*
G37*
G36*
G01X668244D02*
G03I-577J0D01*
G37*
G36*
G01X665744Y474625D02*
G03I-577J0D01*
G37*
G36*
G01X668244D02*
G03I-577J0D01*
G37*
G36*
G01Y481711D02*
G03I-577J0D01*
G37*
G36*
G01X665744D02*
G03I-577J0D01*
G37*
G36*
G01Y495885D02*
G03I-577J0D01*
G37*
G36*
G01X673044Y389152D02*
G03I-577J0D01*
G37*
G36*
G01Y396239D02*
G03I-577J0D01*
G37*
G36*
G01Y403325D02*
G03I-577J0D01*
G37*
G36*
G01X743153Y499473D02*
X818959D01*
G02X819101Y499414I0J-200D01*
G01X819447Y499068D01*
G02X819449Y499066I-140J-142D01*
G02X819506Y498926I-143J-140D01*
G01Y493376D01*
G02X819447Y493234I-200J0D01*
G01X819031Y492818D01*
G03X819010Y492794I140J-143D01*
G01X818936Y492760D01*
X818897Y492758D01*
G03X817471Y491258I76J-1500D01*
G03X817841Y490271I1501J0D01*
G01X817865Y490243D01*
X817890Y490177D01*
Y489839D01*
X817865Y489773D01*
X817841Y489745D01*
G03X817471Y488758I1131J-987D01*
G01Y488757D01*
G03X817473Y488687I1502J8D01*
G01Y488681D01*
X817474Y488659D01*
X817466Y488611D01*
G02X817387Y488483I-197J33D01*
G01X817195Y488342D01*
X817194Y488341D01*
X817075Y488256D01*
X817023Y488250D01*
X816970Y488244D01*
X816919Y488264D01*
X816918D01*
G03X816364Y488372I-559J-1393D01*
G03X815377Y488002I0J-1501D01*
G01X815349Y487978D01*
X815283Y487953D01*
X814945D01*
X814879Y487978D01*
X814851Y488002D01*
G03X813864Y488372I-987J-1131D01*
G03X812372Y487039I0J-1501D01*
G02X812006Y486950I-199J22D01*
G03X811888Y487105I-1251J-830D01*
G01X811864Y487133D01*
X811839Y487199D01*
Y487537D01*
X811864Y487603D01*
X811888Y487631D01*
G03Y489605I-1131J987D01*
G01X811864Y489633D01*
X811839Y489699D01*
Y490037D01*
X811864Y490103D01*
X811888Y490131D01*
G03X812258Y491118I-1131J987D01*
G03X809254I-1502J0D01*
G03X809624Y490131I1501J0D01*
G01X809648Y490103D01*
X809673Y490037D01*
Y489699D01*
X809648Y489633D01*
X809624Y489605D01*
G03Y487631I1131J-987D01*
G01X809648Y487603D01*
X809673Y487537D01*
Y487199D01*
X809648Y487133D01*
X809624Y487105D01*
G03Y485131I1131J-987D01*
G01X809648Y485103D01*
X809673Y485037D01*
Y484699D01*
X809648Y484633D01*
X809624Y484605D01*
G03X809254Y483618I1131J-987D01*
G03X812258I1502J0D01*
G03X811888Y484605I-1501J0D01*
G01X811864Y484633D01*
X811839Y484699D01*
Y484963D01*
G02X811852Y485035I200J1D01*
G01X811890Y485133D01*
X811912Y485159D01*
G03X811965Y485226I-1151J965D01*
G01X811975Y485240D01*
G03X812020Y485306I-1218J879D01*
G03X812176Y485625I-1262J815D01*
G01X812193Y485673D01*
X812268Y485741D01*
X812641Y485830D01*
X812736D01*
X812808Y485801D01*
X812836Y485775D01*
G03X813864Y485368I1029J1096D01*
G03X814851Y485738I0J1501D01*
G01X814879Y485762D01*
X814945Y485787D01*
X815283D01*
X815349Y485762D01*
X815377Y485738D01*
G03X816364Y485368I987J1131D01*
G03X817866Y486870I0J1502D01*
G01Y486871D01*
G03X817864Y486941I-1502J-8D01*
G01Y486947D01*
X817863Y486969D01*
X817871Y487017D01*
G02X817932Y487132I198J-31D01*
G01X817941Y487140D01*
X818104Y487258D01*
X818218Y487341D01*
X818220D01*
X818254Y487366D01*
X818338Y487384D01*
X818400Y487370D01*
X818416Y487364D01*
G03X818973Y487256I559J1394D01*
G01X818983D01*
G03X819028Y487257I-11J1502D01*
G03X819769Y487484I-55J1501D01*
G01X819875Y487515D01*
G02X819973Y487489I-1J-200D01*
G01X820278Y487318D01*
X820293Y487305D01*
G03X820301Y487299I121J153D01*
G01X820337Y487272D01*
G02X820341Y487267I-156J-129D01*
G01X820374Y487199D01*
G02X820380Y487170I-194J-55D01*
G01Y483119D01*
G02X820321Y482977I-200J0D01*
G01X819073Y481729D01*
X819045Y481700D01*
X818971Y481670D01*
X809084D01*
G03X808942Y481611I0J-200D01*
G01X806885Y479554D01*
G03X806826Y479412I141J-142D01*
G01Y467894D01*
G03X806885Y467752I200J0D01*
G01X810888Y463749D01*
G03X811030Y463690I142J141D01*
G01X824621D01*
G02X824779Y463613I0J-200D01*
G01X824794Y463593D01*
X824993Y463245D01*
X824994Y463191D01*
Y463134D01*
X824961Y463076D01*
X824957Y463071D01*
G03X824956Y463069I177J-90D01*
G01X824935Y463028D01*
X824919Y462996D01*
G03X824760Y462326I1343J-672D01*
G03X825339Y461141I1502J0D01*
G02X825416Y460984I-123J-158D01*
G01Y460668D01*
G02X825339Y460511I-200J1D01*
G03X824760Y459326I923J-1185D01*
G03X827764I1502J0D01*
G03X827185Y460511I-1502J0D01*
G02X827108Y460668I123J158D01*
G01Y460984D01*
G02X827185Y461141I200J-1D01*
G03X827741Y462062I-923J1185D01*
G03X827764Y462317I-1479J262D01*
G01Y462327D01*
G03X827563Y463077I-1502J-1D01*
G01X827559Y463084D01*
X827551Y463100D01*
X827531Y463141D01*
X827530Y463186D01*
X827529Y463242D01*
X827729Y463590D01*
G02X827902Y463690I173J-100D01*
G01X834281D01*
G02X834314Y463687I-2J-200D01*
G02X834421Y463633I-32J-197D01*
G01X834937Y463117D01*
G02X834939Y463115I-140J-142D01*
G02X834996Y462975I-143J-140D01*
G01Y457586D01*
G02X834885Y457407I-200J0D01*
G01X834868Y457398D01*
X834501Y457256D01*
X834441D01*
G02X834361Y457273I1J200D01*
G01X834323Y457290D01*
X834294Y457321D01*
X834293Y457322D01*
G03X833185Y457811I-1108J-1011D01*
G03X831683Y456309I0J-1502D01*
G03X832355Y455057I1502J0D01*
G01X832375Y455043D01*
X832407Y455009D01*
X832464Y454906D01*
G02X832489Y454809I-175J-97D01*
G01Y453809D01*
G02X832464Y453712I-200J0D01*
G01X832407Y453609D01*
X832375Y453575D01*
X832354Y453561D01*
G03X831683Y452310I831J-1251D01*
G01Y452309D01*
G03X832125Y451245I1502J0D01*
G02X832184Y451103I-141J-142D01*
G01Y450911D01*
G02X832125Y450769I-200J0D01*
G01X831829Y450473D01*
X831801Y450444D01*
X831727Y450414D01*
X826255D01*
G02X826067Y450545I0J200D01*
G01Y450546D01*
G03X824650Y451541I-1417J-511D01*
G03X823232Y450546I0J-1508D01*
G01X823210Y450486D01*
X823107Y450414D01*
X801235D01*
G02X801093Y450473I0J200D01*
G01X801088Y450478D01*
G03X800946Y450537I-142J-141D01*
G01X795819D01*
X795818Y450538D01*
X795783D01*
X795672Y450636D01*
X795662Y450711D01*
G03X792684Y450710I-1489J-201D01*
G01X792674Y450635D01*
X792564Y450538D01*
X792528D01*
X792526Y450537D01*
X780675D01*
X780674Y450538D01*
X780639D01*
X780528Y450636D01*
X780518Y450711D01*
G03X777540Y450710I-1489J-201D01*
G01X777530Y450635D01*
X777420Y450538D01*
X777384D01*
X777382Y450537D01*
X758073D01*
G03X757931Y450478I0J-200D01*
G01X754028Y446575D01*
X754000Y446546D01*
X753926Y446516D01*
X737563D01*
G03X737421Y446457I0J-200D01*
G01X735491Y444526D01*
G03X735432Y444384I141J-142D01*
G01Y425456D01*
G02X735232Y425256I-200J0D01*
G01X732796D01*
G03Y417854I0J-3701D01*
G01X738514D01*
G02X738636Y417795I-21J-199D01*
G01X750748Y405683D01*
G03X750890Y405624I142J141D01*
G01X751678D01*
G02X751714Y405621I1J-200D01*
G01X751751Y405614D01*
X751778Y405606D01*
X751784Y405604D01*
X751786Y405603D01*
G03X751913Y405564I545J1548D01*
G03X752341Y405508I425J1584D01*
G03X752783Y405568I2J1640D01*
G03X752915Y405611I-442J1580D01*
G01X752949Y405624D01*
X755315D01*
G02X755498Y405504I0J-200D01*
G01X755620Y405224D01*
Y405222D01*
X755641Y405175D01*
G02X755658Y405095I-183J-81D01*
G01Y405045D01*
X755631Y404975D01*
X755604Y404947D01*
G03X755160Y403825I1196J-1122D01*
G01Y403824D01*
G03X758440I1640J0D01*
G01Y403825D01*
G03X757993Y404950I-1640J0D01*
G02X757956Y405170I145J138D01*
G01X757980Y405222D01*
Y405224D01*
X758101Y405503D01*
G02X758158Y405579I184J-79D01*
G01X758159D01*
G02X758285Y405624I126J-155D01*
G01X764481D01*
G02X764514Y405621I-2J-200D01*
G02X764621Y405567I-32J-197D01*
G01X765086Y405102D01*
X765097Y405086D01*
G03X765499Y404681I1248J837D01*
G01X765506Y404676D01*
X765535Y404653D01*
X766108Y404080D01*
G02X766110Y404078I-140J-142D01*
G02X766167Y403938I-143J-140D01*
G01Y403780D01*
X766160Y403728D01*
X766103Y403517D01*
G02X765962Y403376I-193J52D01*
G01X765961D01*
G03X764842Y401924I383J-1452D01*
G03X766344Y400422I1502J0D01*
G03X767796Y401540I0J1502D01*
G01X767803Y401567D01*
X767829Y401612D01*
X767849Y401632D01*
G02X767937Y401683I141J-142D01*
G01X768190Y401752D01*
X768192Y401754D01*
X768271Y401775D01*
G02X768427Y401751I50J-194D01*
G01X768452Y401736D01*
X787770Y382418D01*
G02X787772Y382416I-140J-142D01*
G02X787829Y382276I-143J-140D01*
G01Y305160D01*
G02X787770Y305018I-200J0D01*
G01X785056Y302304D01*
X785028Y302275D01*
X784954Y302245D01*
X782404D01*
G03X782390Y302246I-93J-1198D01*
G01X782318Y302290D01*
G03X782293Y302308I-715J-967D01*
G01X782269Y302358D01*
X782116Y302673D01*
G02X782113Y302841I180J87D01*
G01X782137Y302894D01*
X782152Y302914D01*
G03X782470Y303837I-1184J924D01*
G01Y303839D01*
G03X779466I-1502J0D01*
G01Y303837D01*
G03X779784Y302914I1502J1D01*
G01X779799Y302894D01*
X779823Y302841D01*
G02X779820Y302673I-183J-81D01*
G01X779667Y302358D01*
G02X779487Y302245I-180J87D01*
G01X777359D01*
G02X777217Y302304I0J200D01*
G01X769880Y309641D01*
X769856Y309664D01*
G03X769850Y309670I-852J-846D01*
G01X769821Y309743D01*
Y323015D01*
X769886Y323114D01*
X769942Y323138D01*
G03Y325898I-593J1380D01*
G01X769886Y325922D01*
X769821Y326021D01*
Y364678D01*
G03X769762Y364820I-200J0D01*
G01X757518Y377064D01*
X757489Y377092D01*
X757459Y377166D01*
Y377303D01*
X757474Y377339D01*
G03X757588Y377912I-1388J574D01*
G03X756086Y379414I-1502J0D01*
G03X755478Y379285I1J-1502D01*
G02X755245Y379337I-82J183D01*
G01X753911Y380671D01*
G02X753873Y380723I140J143D01*
G01X753813Y380844D01*
X753832Y380969D01*
X753875Y381015D01*
G03X754287Y382047I-1090J1033D01*
G03X752785Y383549I-1502J0D01*
G03X751764Y383148I1J-1502D01*
G01X751737Y383123D01*
X751664Y383093D01*
G02X751517Y383090I-77J185D01*
G01X751476Y383106D01*
X751016Y383566D01*
G02X751003Y383581I144J138D01*
G01X751002D01*
G02X750967Y383771I155J127D01*
G01X750972Y383786D01*
X750976Y383796D01*
X750978Y383799D01*
G03X751108Y384410I-1372J611D01*
G03X749606Y385912I-1502J0D01*
G03X748987Y385778I1J-1502D01*
G01X748986D01*
G02X748763Y385819I-82J182D01*
G01X740953Y393629D01*
G03X740811Y393688I-142J-141D01*
G01X736269D01*
X736157Y393784D01*
X736146Y393858D01*
G03X733176I-1485J-225D01*
G01X733165Y393784D01*
X733053Y393688D01*
X686592D01*
X686553Y393705D01*
X686493Y393731D01*
G02X686462Y393748I80J183D01*
G01X686420Y393776D01*
X686406Y393790D01*
G03X685882Y394124I-1052J-1072D01*
G03X685354Y394220I-528J-1406D01*
G01X685333D01*
G03X685198Y394212I21J-1502D01*
G03X684849Y394133I155J-1494D01*
G01X684794Y394113D01*
X684681Y394139D01*
X681879Y396941D01*
G02X681820Y397083I141J142D01*
G01Y486406D01*
G02X681877Y486546I200J0D01*
G01X694745Y499414D01*
G02X694747Y499416I142J-140D01*
G02X694887Y499473I140J-143D01*
G01X729739D01*
G02X729826Y499453I0J-200D01*
G01X729918Y499409D01*
X729950Y499383D01*
X729964Y499367D01*
X729965Y499366D01*
G03X732793Y498050I2831J2386D01*
G01X740099D01*
G03X742927Y499366I-3J3702D01*
G01X742928Y499367D01*
X742942Y499383D01*
X742974Y499409D01*
X743067Y499453D01*
G02X743153Y499473I87J-180D01*
G37*
G36*
G01X673044Y410412D02*
G03I-577J0D01*
G37*
G36*
G01Y424585D02*
G03I-577J0D01*
G37*
G36*
G01Y417498D02*
G03I-577J0D01*
G37*
G36*
G01Y438759D02*
G03I-577J0D01*
G37*
G36*
G01Y431672D02*
G03I-577J0D01*
G37*
G36*
G01Y467538D02*
G03I-577J0D01*
G37*
G36*
G01Y488798D02*
G03I-577J0D01*
G37*
G36*
G01Y474625D02*
G03I-577J0D01*
G37*
G36*
G01Y481711D02*
G03I-577J0D01*
G37*
G36*
G01X693176Y116495D02*
G03I-577J0D01*
G37*
G36*
G01X688376D02*
G03I-577J0D01*
G37*
G36*
G01X695676D02*
G03I-577J0D01*
G37*
G36*
G01X693176Y123582D02*
G03I-577J0D01*
G37*
G36*
G01X688376D02*
G03I-577J0D01*
G37*
G36*
G01X695676Y130668D02*
G03I-577J0D01*
G37*
G36*
G01X693176D02*
G03I-577J0D01*
G37*
G36*
G01X688376D02*
G03I-577J0D01*
G37*
G36*
G01X695676Y123581D02*
G03I-577J0D01*
G37*
G36*
G01X693176Y137755D02*
G03I-577J0D01*
G37*
G36*
G01X688376D02*
G03I-577J0D01*
G37*
G36*
G01X711969Y516712D02*
G03I-577J0D01*
G37*
G36*
G01X716769D02*
G03I-577J0D01*
G37*
G36*
G01Y523799D02*
G03I-577J0D01*
G37*
G36*
G01X711969D02*
G03I-577J0D01*
G37*
G36*
G01X716769Y530885D02*
G03I-577J0D01*
G37*
G36*
G01Y537972D02*
G03I-577J0D01*
G37*
G36*
G01X711969Y530885D02*
G03I-577J0D01*
G37*
G36*
G01Y537972D02*
G03I-577J0D01*
G37*
G36*
G01X719269Y516712D02*
G03I-577J0D01*
G37*
G36*
G01Y509625D02*
G03I-577J0D01*
G37*
G36*
G01Y523799D02*
G03I-577J0D01*
G37*
G36*
G01Y530885D02*
G03I-577J0D01*
G37*
G36*
G01X735245Y379562D02*
G03I-639J0D01*
G37*
G36*
G01X752980Y407148D02*
G03I-639J0D01*
G37*
G36*
G01X757439Y403824D02*
G03I-639J0D01*
G37*
G36*
G01X768506Y96889D02*
G03I-577J0D01*
G37*
G36*
G01D02*
G03I-577J0D01*
G37*
G36*
G01X781153Y510661D02*
G03I-577J0D01*
G37*
G36*
G01X776161Y515617D02*
G03I-577J0D01*
G37*
G36*
G01X781153D02*
G03I-577J0D01*
G37*
G36*
G01X776161Y510661D02*
G03I-577J0D01*
G37*
G36*
G01X781153Y529791D02*
G03I-577J0D01*
G37*
G36*
G01X776161Y524835D02*
G03I-577J0D01*
G37*
G36*
G01Y529791D02*
G03I-577J0D01*
G37*
G36*
G01X781153Y524835D02*
G03I-577J0D01*
G37*
G36*
G01Y560701D02*
G03I-577J0D01*
G37*
G36*
G01Y565657D02*
G03I-577J0D01*
G37*
G36*
G01X776161Y560701D02*
G03I-577J0D01*
G37*
G36*
G01Y565657D02*
G03I-577J0D01*
G37*
G36*
G01Y579830D02*
G03I-577J0D01*
G37*
G36*
G01X781153D02*
G03I-577J0D01*
G37*
G36*
G01X776161Y574874D02*
G03I-577J0D01*
G37*
G36*
G01X781153D02*
G03I-577J0D01*
G37*
G36*
G01X776161Y589047D02*
G03I-577J0D01*
G37*
G36*
G01X781153D02*
G03I-577J0D01*
G37*
G36*
G01X776161Y603221D02*
G03I-577J0D01*
G37*
G36*
G01X781153D02*
G03I-577J0D01*
G37*
G36*
G01Y594003D02*
G03I-577J0D01*
G37*
G36*
G01X776161D02*
G03I-577J0D01*
G37*
G36*
G01Y608177D02*
G03I-577J0D01*
G37*
G36*
G01X781153D02*
G03I-577J0D01*
G37*
G36*
G01X928491Y1449561D02*
X931282Y1446769D01*
Y1446735D01*
X931590Y1446461D01*
G02X931635Y1446357I-154J-128D01*
G02X931636Y1446333I-199J-20D01*
G01Y1443069D01*
G02X931577Y1442927I-200J0D01*
G01X930547Y1441897D01*
G03X930488Y1441755I141J-142D01*
G01Y1421754D01*
G03X930547Y1421612I200J0D01*
G01X931577Y1420582D01*
G02X931636Y1420440I-141J-142D01*
G01Y1412496D01*
G02X931591Y1412370I-200J0D01*
G02X931578Y1412355I-157J123D01*
G01X931567Y1412344D01*
X931565Y1412343D01*
X930732Y1411509D01*
X929094Y1409871D01*
X929088Y1409866D01*
G03X929086Y1409864I843J-845D01*
G03X929082Y1409860I844J-848D01*
G01X929051Y1409828D01*
X929048Y1409825D01*
X929020Y1409796D01*
X928982Y1409781D01*
G02X928907Y1409766I-76J185D01*
G01X796029D01*
G02X795709Y1410406I0J400D01*
G03X796009Y1411307I-1203J901D01*
G03X793003I-1503J0D01*
G03X793303Y1410406I1503J0D01*
G02X792983Y1409766I-320J-240D01*
G01X785415D01*
G02X785148Y1409869I1J400D01*
G02X785146Y1409871I140J142D01*
G02X785079Y1409951I270J294D01*
G03X785077Y1409955I-180J-87D01*
G01X785075Y1409957D01*
G02X785067Y1409970I166J111D01*
G02X785054Y1410336I349J196D01*
G03X785197Y1410975I-1360J640D01*
G01Y1410977D01*
G03X782191I-1503J0D01*
G01Y1410975D01*
G03X782334Y1410336I1503J1D01*
G02X782321Y1409970I-362J-170D01*
G02X782313Y1409957I-174J98D01*
G01X782311Y1409955D01*
G03X782309Y1409951I178J-91D01*
G02X782242Y1409871I-337J214D01*
G02X782240Y1409869I-142J140D01*
G02X781973Y1409766I-268J297D01*
G01X776345D01*
G02X776219Y1409811I0J200D01*
G02X776204Y1409824I123J157D01*
G01X774347Y1411681D01*
X774342Y1411687D01*
G03X774340Y1411689I-847J-845D01*
G03X774336Y1411693I-846J-842D01*
G01X774304Y1411724D01*
X774301Y1411727D01*
X774272Y1411755D01*
X774257Y1411793D01*
G02X774242Y1411868I185J76D01*
G01Y1430939D01*
G03X774227Y1431015I-200J0D01*
G01X774199Y1431081D01*
G02X774184Y1431158I185J76D01*
G01Y1458468D01*
G02X774187Y1458501I200J-2D01*
G02X774241Y1458608I197J-32D01*
G01X775554Y1459921D01*
X777874Y1462240D01*
X777908D01*
X778182Y1462548D01*
G02X778193Y1462557I132J-150D01*
G02X778218Y1462571I110J-167D01*
G01X778229Y1462577D01*
G02X778310Y1462594I81J-183D01*
G01X778327D01*
X795354Y1479620D01*
G02X795396Y1479647I128J-153D01*
G02X795468Y1479666I86J-180D01*
G01X802706D01*
G02X802804Y1479640I-1J-200D01*
G02X802844Y1479610I-99J-174D01*
G01X803721Y1478733D01*
G03X803738Y1478716I858J841D01*
G01X804212Y1478242D01*
G02X804270Y1478100I-142J-141D01*
G01Y1476043D01*
G02X804212Y1475901I-200J-1D01*
G01X803892Y1475582D01*
G03X803834Y1475440I142J-141D01*
G01Y1467298D01*
G02X803744Y1467131I-200J0D01*
G01X803423Y1466919D01*
X803323Y1466911D01*
X803303Y1466919D01*
G03X802686Y1467052I-618J-1369D01*
G01X802684D01*
G03Y1464046I0J-1503D01*
G01X802686D01*
G03X803302Y1464178I0J1503D01*
G02X803305Y1464180I111J-163D01*
G01X803323Y1464187D01*
X803423Y1464179D01*
X803744Y1463967D01*
G02X803834Y1463800I-110J-167D01*
G01Y1461757D01*
G02X803775Y1461615I-200J0D01*
G01X803329Y1461169D01*
G03X803270Y1461027I141J-142D01*
G01Y1450944D01*
G02X803211Y1450802I-200J0D01*
G01X803068Y1450661D01*
X803057D01*
G03X801554Y1449158I0J-1503D01*
G03X801556Y1449078I1503J-2D01*
G01Y1449076D01*
G02X801498Y1448926I-200J-9D01*
G01X801289Y1448717D01*
G02X801157Y1448659I-141J142D01*
G01X801137D01*
G03X801057Y1448661I-78J-1501D01*
G03X800977Y1448659I-2J-1503D01*
G01X800975D01*
G02X800825Y1448717I-9J200D01*
G01X800616Y1448926D01*
G02X800558Y1449076I142J141D01*
G01Y1449078D01*
G03X800560Y1449158I-1501J78D01*
G03X799057Y1447655I-1503J0D01*
G03X799137Y1447657I2J1503D01*
G01X799139D01*
G02X799289Y1447599I9J-200D01*
G01X799498Y1447390D01*
G02X799556Y1447240I-142J-141D01*
G01Y1447238D01*
G03X799554Y1447158I1501J-78D01*
G03X802560I1503J0D01*
G03X802558Y1447238I-1503J2D01*
G01Y1447240D01*
G02X802616Y1447390I200J9D01*
G01X802825Y1447599D01*
G02X802957Y1447657I141J-142D01*
G01X802977D01*
G03X803057Y1447655I78J1501D01*
G01X803068D01*
X803211Y1447514D01*
G02X803270Y1447372I-141J-142D01*
G01Y1445347D01*
G03X803328Y1445205I200J-1D01*
G01X803722Y1444812D01*
G02X803780Y1444670I-142J-141D01*
G01Y1433480D01*
X803476Y1433176D01*
X798601D01*
G03X797098Y1431673I0J-1503D01*
G03X798170Y1430233I1503J0D01*
G01X798204Y1430222D01*
X799932Y1428495D01*
G02X799989Y1428381I-141J-142D01*
G02X799826Y1428000I-396J-56D01*
G03X799200Y1426779I878J-1221D01*
G03X800703Y1425276I1503J0D01*
G03X801924Y1425902I0J1504D01*
G02X802305Y1426065I325J-233D01*
G02X802419Y1426008I-28J-198D01*
G01X806548Y1421878D01*
G03X806787Y1421690I922J926D01*
G02X806823Y1421661I-107J-169D01*
G01X806889Y1421595D01*
G03X807030Y1421536I142J141D01*
G01X807148D01*
X807171Y1421531D01*
G03X807471Y1421496I300J1271D01*
G01X831706D01*
G03X832006Y1421531I0J1306D01*
G01X832029Y1421536D01*
X832147D01*
G03X832288Y1421595I-1J200D01*
G01X832354Y1421661D01*
G02X832390Y1421690I143J-140D01*
G03X832629Y1421878I-683J1114D01*
G01X835981Y1425230D01*
G03X836169Y1425469I-926J922D01*
G01X836182Y1425489D01*
X836264Y1425571D01*
G03X836323Y1425712I-141J142D01*
G01Y1425830D01*
X836328Y1425853D01*
G03X836364Y1426154I-1271J305D01*
G01Y1435217D01*
G03X836328Y1435518I-1307J-4D01*
G01X836323Y1435541D01*
Y1435659D01*
G03X836264Y1435800I-200J-1D01*
G01X836182Y1435882D01*
X836169Y1435902D01*
G03X835981Y1436141I-1114J-683D01*
G01X830403Y1441719D01*
G02X830344Y1441861I141J142D01*
G01Y1459883D01*
G02X830385Y1460004I200J0D01*
G02X830993Y1460038I318J-241D01*
G03X832084Y1459569I1091J1034D01*
G03X832564Y1459648I-1J1504D01*
G01X832566D01*
G03X832582Y1459654I-519J1409D01*
G01X832589Y1459657D01*
X832603Y1459661D01*
X832618Y1459664D01*
X832641Y1459668D01*
G02X832754Y1459655I35J-197D01*
G01X832963Y1459566D01*
X832998Y1459551D01*
X833100Y1459451D01*
X833115Y1459419D01*
G03X833936Y1458656I1360J640D01*
G01X833976Y1458641D01*
X834006Y1458610D01*
G02X834051Y1458540I-142J-141D01*
G01X834154Y1458266D01*
G02X834163Y1458233I-188J-69D01*
G02X834156Y1458132I-197J-37D01*
G01X834145Y1458099D01*
X834138Y1458085D01*
X834137Y1458084D01*
G03X833971Y1457398I1337J-687D01*
G01Y1457397D01*
G03X836977I1503J0D01*
G03X836014Y1458800I-1504J0D01*
G01X836012Y1458801D01*
G02X835898Y1458917I73J186D01*
G01X835796Y1459191D01*
G02X835793Y1459324I187J71D01*
G01X835804Y1459357D01*
X835811Y1459371D01*
X835812Y1459372D01*
G03X835978Y1460058I-1337J687D01*
G01Y1460059D01*
G03X834475Y1461562I-1503J0D01*
G03X833995Y1461483I1J-1504D01*
G01X833993D01*
G03X833977Y1461477I519J-1409D01*
G01X833970Y1461474D01*
X833956Y1461470D01*
X833941Y1461467D01*
X833918Y1461463D01*
G02X833805Y1461476I-35J197D01*
G01X833596Y1461565D01*
X833561Y1461580D01*
X833459Y1461680D01*
X833444Y1461712D01*
G03X833397Y1461803I-1358J-644D01*
G01X833514Y1462002D01*
G02X833686Y1462100I172J-102D01*
G01X837672D01*
G02X837814Y1462041I0J-200D01*
G01X838293Y1461562D01*
X838304Y1461528D01*
G03X839744Y1460456I1440J431D01*
G01X839745D01*
G03X840445Y1460629I0J1503D01*
G02X840538Y1460652I93J-177D01*
G01X841332D01*
G02X841474Y1460593I0J-200D01*
G01X852747Y1449320D01*
G02X852806Y1449178I-141J-142D01*
G01Y1423298D01*
G03X852842Y1422997I1307J4D01*
G01X852847Y1422974D01*
Y1422856D01*
G03X852906Y1422715I200J1D01*
G01X852988Y1422633D01*
X853001Y1422613D01*
G03X853189Y1422374I1114J683D01*
G01X854926Y1420637D01*
G03X855165Y1420449I922J926D01*
G02X855201Y1420420I-107J-169D01*
G01X855267Y1420354D01*
G03X855408Y1420295I142J141D01*
G01X855526D01*
X855549Y1420290D01*
G03X855850Y1420254I305J1271D01*
G01X876086D01*
G03X876387Y1420290I-4J1307D01*
G01X876410Y1420295D01*
X876528D01*
G03X876669Y1420354I-1J200D01*
G01X876735Y1420420D01*
G02X876771Y1420449I143J-140D01*
G03X877010Y1420637I-683J1114D01*
G01X878623Y1422250D01*
G03X878811Y1422489I-926J922D01*
G01X878824Y1422509D01*
X878906Y1422591D01*
G03X878965Y1422732I-141J142D01*
G01Y1422850D01*
X878970Y1422873D01*
G03X879006Y1423174I-1271J305D01*
G01Y1443099D01*
G03X878970Y1443400I-1307J-4D01*
G01X878965Y1443423D01*
Y1443541D01*
G03X878906Y1443682I-200J-1D01*
G01X878824Y1443764D01*
X878811Y1443784D01*
G03X878623Y1444023I-1114J-683D01*
G01X875119Y1447527D01*
G02X875117Y1447554I198J28D01*
G01Y1451684D01*
G02X875565Y1452081I400J0D01*
G03X875744Y1452070I182J1492D01*
G01X875747D01*
G03X876244Y1452154I1J1504D01*
G02X876270Y1452162I72J-187D01*
G02X876749Y1451776I79J-392D01*
G01X876748Y1451755D01*
Y1451751D01*
X876747Y1451745D01*
Y1451743D01*
G03X876741Y1451607I1497J-134D01*
G01Y1451605D01*
G03X878244Y1453108I1503J0D01*
G01X878241D01*
G03X877744Y1453024I-1J-1504D01*
G02X877718Y1453016I-72J187D01*
G02X877239Y1453402I-79J392D01*
G01X877240Y1453423D01*
Y1453427D01*
X877241Y1453433D01*
Y1453435D01*
G03X877247Y1453571I-1497J134D01*
G01Y1453573D01*
G03X875744Y1455076I-1503J0D01*
G03X875565Y1455065I3J-1503D01*
G02X875117Y1455462I-48J397D01*
G01Y1468858D01*
G02X875119Y1468886I200J0D01*
G01X881641Y1475408D01*
X881675Y1475419D01*
G03X882297Y1475787I-432J1440D01*
G03X882711Y1476531I-1053J1073D01*
G01Y1476532D01*
G02X882906Y1476688I195J-44D01*
G01X886828D01*
G02X886970Y1476629I0J-200D01*
G01X891081Y1472518D01*
G02X891135Y1472411I-143J-139D01*
G02X891138Y1472378I-197J-35D01*
G01Y1470405D01*
G02X890455Y1470122I-400J0D01*
G01X890452Y1470125D01*
X890252D01*
X890229Y1470130D01*
G03X890032Y1470161I-301J-1271D01*
G02X889953Y1470184I15J200D01*
G03X889245Y1470362I-709J-1325D01*
G01X889244D01*
G03Y1467356I0J-1503D01*
G03X889454Y1467371I-2J1503D01*
G01X889456D01*
X889521Y1467380D01*
G02X889560Y1467379I14J-199D01*
G01X893116Y1463824D01*
G02X893173Y1463710I-141J-142D01*
G02X893017Y1463334I-396J-56D01*
G03X892416Y1462132I901J-1202D01*
G03X893919Y1460629I1503J0D01*
G03X895121Y1461230I0J1502D01*
G02X895497Y1461386I320J-240D01*
G02X895611Y1461329I-28J-198D01*
G01X896259Y1460681D01*
G02X896318Y1460539I-141J-142D01*
G01Y1459154D01*
G02X896278Y1459033I-200J-1D01*
G02X895808Y1458903I-320J241D01*
G03X895244Y1459013I-564J-1393D01*
G03Y1456007I0J-1503D01*
G03X895808Y1456117I0J1503D01*
G02X896278Y1455987I150J-371D01*
G02X896318Y1455866I-160J-120D01*
G01Y1424291D01*
G03X896353Y1423991I1306J0D01*
G01X896358Y1423968D01*
Y1423850D01*
G03X896417Y1423709I200J1D01*
G01X896499Y1423627D01*
X896512Y1423607D01*
G03X896700Y1423368I1114J683D01*
G01X898314Y1421754D01*
G03X898553Y1421566I922J926D01*
G02X898589Y1421537I-107J-169D01*
G01X898655Y1421471D01*
G03X898796Y1421412I142J141D01*
G01X898914D01*
X898937Y1421407D01*
G03X899237Y1421372I300J1271D01*
G01X917674D01*
G03X917974Y1421407I0J1306D01*
G01X917997Y1421412D01*
X918115D01*
G03X918256Y1421471I-1J200D01*
G01X918322Y1421537D01*
G02X918358Y1421566I143J-140D01*
G03X918597Y1421754I-683J1114D01*
G01X924524Y1427681D01*
G03X924906Y1428603I-924J923D01*
G01Y1451545D01*
G03X924524Y1452467I-1306J-1D01*
G01X923135Y1453856D01*
G02X923076Y1453998I141J142D01*
G01Y1476366D01*
G02X923134Y1476508I200J1D01*
G01X923375Y1476749D01*
G02X923517Y1476808I142J-141D01*
G01X924665D01*
X924712Y1476796D01*
X924734Y1476784D01*
G03X925434Y1476611I700J1330D01*
G01X925435D01*
G03X926569Y1477127I0J1504D01*
G01X927873D01*
X928432Y1476568D01*
Y1449703D01*
G03X928491Y1449561I200J0D01*
G37*
G36*
G01X798038Y116495D02*
G03I-577J0D01*
G37*
G36*
G01X795538D02*
G03I-577J0D01*
G37*
G36*
G01X790738D02*
G03I-577J0D01*
G37*
G36*
G01X798038Y123581D02*
G03I-577J0D01*
G37*
G36*
G01X795538Y123582D02*
G03I-577J0D01*
G37*
G36*
G01X790738D02*
G03I-577J0D01*
G37*
G36*
G01X798038Y130668D02*
G03I-577J0D01*
G37*
G36*
G01X795538D02*
G03I-577J0D01*
G37*
G36*
G01X790738D02*
G03I-577J0D01*
G37*
G36*
G01X795538Y137755D02*
G03I-577J0D01*
G37*
G36*
G01X790738D02*
G03I-577J0D01*
G37*
G36*
G01X786563Y517774D02*
G03I-577J0D01*
G37*
G36*
G01Y522730D02*
G03I-577J0D01*
G37*
G36*
G01X791555Y517774D02*
G03I-577J0D01*
G37*
G36*
G01Y522730D02*
G03I-577J0D01*
G37*
G36*
G01X786563Y531947D02*
G03I-577J0D01*
G37*
G36*
G01Y536903D02*
G03I-577J0D01*
G37*
G36*
G01X791555Y531947D02*
G03I-577J0D01*
G37*
G36*
G01Y536903D02*
G03I-577J0D01*
G37*
G36*
G01X786563Y567813D02*
G03I-577J0D01*
G37*
G36*
G01X791555D02*
G03I-577J0D01*
G37*
G36*
G01X786563Y572769D02*
G03I-577J0D01*
G37*
G36*
G01X791555D02*
G03I-577J0D01*
G37*
G36*
G01X786563Y581987D02*
G03I-577J0D01*
G37*
G36*
G01Y586943D02*
G03I-577J0D01*
G37*
G36*
G01X791555Y581987D02*
G03I-577J0D01*
G37*
G36*
G01Y586943D02*
G03I-577J0D01*
G37*
G36*
G01Y601116D02*
G03I-577J0D01*
G37*
G36*
G01X786563D02*
G03I-577J0D01*
G37*
G36*
G01Y596160D02*
G03I-577J0D01*
G37*
G36*
G01X791555D02*
G03I-577J0D01*
G37*
G36*
G01Y615289D02*
G03I-577J0D01*
G37*
G36*
G01Y610333D02*
G03I-577J0D01*
G37*
G36*
G01X786563Y615289D02*
G03I-577J0D01*
G37*
G36*
G01Y610333D02*
G03I-577J0D01*
G37*
G36*
G01X839781Y388583D02*
G02I-19702J0D01*
G37*
G36*
G01X810259Y1133284D02*
G03I-577J0D01*
G37*
G36*
G01X809046Y1441994D02*
X809441Y1442389D01*
G02X809583Y1442448I142J-141D01*
G01X822343D01*
G02X822485Y1442389I0J-200D01*
G01X822957Y1441917D01*
G02X823016Y1441775I-141J-142D01*
G01Y1437224D01*
G03X823075Y1437082I200J0D01*
G01X823609Y1436548D01*
G03X823751Y1436489I142J141D01*
G01X828643D01*
G02X828785Y1436430I0J-200D01*
G01X831894Y1433321D01*
G02X831953Y1433179I-141J-142D01*
G01Y1429713D01*
G02X831894Y1429571I-200J0D01*
G01X828816Y1426493D01*
G02X828674Y1426434I-142J141D01*
G01X821049D01*
G02X820907Y1426493I0J200D01*
G01X815656Y1431744D01*
G03X815514Y1431803I-142J-141D01*
G01X809659D01*
G02X809517Y1431862I0J200D01*
G01X809046Y1432333D01*
G02X808987Y1432475I141J142D01*
G01Y1441852D01*
G02X809046Y1441994I200J0D01*
G37*
G36*
G01X822554Y1626504D02*
X927703D01*
G02X927845Y1626445I0J-200D01*
G01X932332Y1621958D01*
G02X932391Y1621816I-141J-142D01*
G01Y1585734D01*
G03X932450Y1585592I200J0D01*
G01X940497Y1577545D01*
G03X940639Y1577486I142J141D01*
G01X956366D01*
G02X956508Y1577427I0J-200D01*
G01X960090Y1573845D01*
G02X960149Y1573703I-141J-142D01*
G01Y1545224D01*
G03X960208Y1545082I200J0D01*
G01X960222Y1545068D01*
Y1543190D01*
G03X960281Y1543048I200J0D01*
G01X964685Y1538644D01*
G03X964827Y1538585I142J141D01*
G01X1020051D01*
G02X1020193Y1538526I0J-200D01*
G01X1031736Y1526983D01*
G02X1031795Y1526841I-141J-142D01*
G01Y1492779D01*
G02X1031736Y1492637I-200J0D01*
G01X1031447Y1492348D01*
G02X1031305Y1492289I-142J141D01*
G01X957250D01*
X957246Y1492293D01*
X947172D01*
G02X947030Y1492352I0J200D01*
G01X944500Y1494882D01*
G03X944358Y1494941I-142J-141D01*
G01X933345D01*
G03X933203Y1494882I0J-200D01*
G01X917090Y1478769D01*
G03X917031Y1478627I141J-142D01*
G01Y1464953D01*
G02X916972Y1464811I-200J0D01*
G01X914131Y1461970D01*
G03X914072Y1461828I141J-142D01*
G01Y1460856D01*
G02X914013Y1460714I-200J0D01*
G01X913858Y1460559D01*
X913852D01*
X913446Y1460153D01*
G03X913387Y1460011I141J-142D01*
G01Y1446377D01*
G02X913328Y1446235I-200J0D01*
G01X913012Y1445919D01*
G02X912870Y1445860I-142J141D01*
G01X900424D01*
G02X900282Y1445919I0J200D01*
G01X900057Y1446144D01*
G02X899998Y1446286I141J142D01*
G01Y1459953D01*
G03X899939Y1460095I-200J0D01*
G01X899336Y1460698D01*
G02X899277Y1460840I141J142D01*
G01Y1462388D01*
G03X899218Y1462530I-200J0D01*
G01X894243Y1467505D01*
G02X894184Y1467647I141J142D01*
G01Y1473419D01*
G03X894125Y1473561I-200J0D01*
G01X888556Y1479130D01*
G03X888414Y1479189I-142J-141D01*
G01X886878D01*
G03X886829Y1479190I-80J-2700D01*
G01X882906D01*
G03X882856Y1479189I29J-2701D01*
G01X880246D01*
G03X880104Y1479130I0J-200D01*
G01X872204Y1471230D01*
G03X872145Y1471088I141J-142D01*
G01Y1460906D01*
G02X872086Y1460764I-200J0D01*
G01X871408Y1460086D01*
G03X871349Y1459944I141J-142D01*
G01Y1446298D01*
G02X871290Y1446156I-200J0D01*
G01X871040Y1445906D01*
G02X870898Y1445847I-142J141D01*
G01X858576D01*
G02X858434Y1445906I0J200D01*
G01X857939Y1446401D01*
G02X857880Y1446543I141J142D01*
G01Y1459845D01*
G03X857821Y1459987I-200J0D01*
G01X853265Y1464543D01*
G03X853123Y1464602I-142J-141D01*
G01X838903D01*
X838857Y1464613D01*
X838836Y1464624D01*
G03X838244Y1464766I-592J-1165D01*
G01X830651D01*
G03X830059Y1464624I0J-1307D01*
G01X830038Y1464613D01*
X829992Y1464602D01*
X828106D01*
G03X827964Y1464543I0J-200D01*
G01X826987Y1463566D01*
G03X826928Y1463424I141J-142D01*
G01Y1461709D01*
G02X826869Y1461567I-200J0D01*
G01X826719Y1461417D01*
G02X826577Y1461359I-141J142D01*
G01X824706D01*
G03X824564Y1461300I0J-200D01*
G01X822174Y1458910D01*
G03X822115Y1458768I141J-142D01*
G01Y1458505D01*
G02X822056Y1458363I-200J0D01*
G01X822029Y1458336D01*
X819764D01*
G03X819622Y1458277I0J-200D01*
G01X819287Y1457942D01*
G03X819228Y1457800I141J-142D01*
G01Y1446396D01*
G02X819169Y1446254I-200J0D01*
G01X818882Y1445967D01*
G02X818740Y1445908I-142J141D01*
G01X806246D01*
G02X806104Y1445967I0J200D01*
G01X805830Y1446241D01*
G02X805772Y1446382I142J141D01*
G01Y1447372D01*
G03X805771Y1447422I-2702J-29D01*
G01Y1450894D01*
G03X805772Y1450944I-2701J79D01*
G01Y1459992D01*
G02X805830Y1460133I200J0D01*
G01X806276Y1460579D01*
G03X806335Y1460721I-141J142D01*
G01Y1461707D01*
G03X806336Y1461756I-2700J80D01*
G01Y1463800D01*
G03X806335Y1463850I-2701J-29D01*
G01Y1467248D01*
G03X806336Y1467298I-2700J79D01*
G01Y1467878D01*
G02X806430Y1468048I200J0D01*
G01X806762Y1468255D01*
X806865Y1468260D01*
X806912Y1468237D01*
G03X807576Y1468082I664J1347D01*
G03Y1471086I0J1502D01*
G03X806912Y1470931I0J-1502D01*
G01X806865Y1470908D01*
X806762Y1470913D01*
X806430Y1471120D01*
G02X806336Y1471290I106J170D01*
G01Y1474405D01*
G02X806394Y1474546I200J0D01*
G01X806713Y1474865D01*
G03X806772Y1475007I-141J142D01*
G01Y1523862D01*
G02X806831Y1524004I200J0D01*
G01X816897Y1534070D01*
G03X816956Y1534212I-141J142D01*
G01Y1620906D01*
G02X817015Y1621048I200J0D01*
G01X822412Y1626445D01*
G02X822554Y1626504I142J-141D01*
G37*
G36*
G01X829958Y348036D02*
G03I-577J0D01*
G37*
G36*
G01X828962Y1120599D02*
G03I-577J0D01*
G37*
G36*
G01X817583Y1133027D02*
G03I-577J0D01*
G37*
G36*
G01X822583Y1130208D02*
G03I-577J0D01*
G37*
G36*
G01X840150Y325327D02*
G03I-577J0D01*
G37*
G36*
G01X857027Y1441916D02*
X857407Y1442296D01*
G02X857549Y1442355I142J-141D01*
G01X873302D01*
G02X873444Y1442296I0J-200D01*
G01X873886Y1441854D01*
G02X873945Y1441712I-141J-142D01*
G01Y1425958D01*
G02X873886Y1425816I-200J0D01*
G01X873507Y1425437D01*
G02X873365Y1425378I-142J141D01*
G01X857578D01*
G02X857436Y1425437I0J200D01*
G01X857027Y1425846D01*
G02X856968Y1425988I141J142D01*
G01Y1441774D01*
G02X857027Y1441916I200J0D01*
G37*
G36*
G01X870972Y96737D02*
G03I-577J0D01*
G37*
G36*
G01D02*
G03I-577J0D01*
G37*
G36*
G01X874310Y357844D02*
G03I-577J0D01*
G37*
G36*
G01X896653Y237517D02*
G03I-577J0D01*
G37*
G36*
G01D02*
G03I-577J0D01*
G37*
G36*
G01Y232561D02*
G03I-577J0D01*
G37*
G36*
G01D02*
G03I-577J0D01*
G37*
G36*
G01X886603Y346584D02*
G03I-577J0D01*
G37*
G36*
G01X902425Y307782D02*
G03I-577J0D01*
G37*
G36*
G01X913363Y306697D02*
G03I-577J0D01*
G37*
G36*
G01X910653Y304843D02*
G03I-577J0D01*
G37*
G36*
G01X905697D02*
G03I-577J0D01*
G37*
G36*
G01X915640Y545094D02*
G02X915781Y545036I0J-200D01*
G01X915782Y545035D01*
X915990Y544788D01*
G02X916031Y544711I-152J-130D01*
G01X916041Y544673D01*
X916034Y544627D01*
G03X916009Y544325I1777J-299D01*
G03X919613I1802J0D01*
G03X919588Y544627I-1802J3D01*
G01X919581Y544673D01*
X919591Y544711D01*
G02X919632Y544788I193J-53D01*
G01X919840Y545035D01*
X919841Y545036D01*
G02X919982Y545094I141J-142D01*
G01X922876D01*
G02X923018Y545035I0J-200D01*
G01X925509Y542544D01*
G02X925568Y542402I-141J-142D01*
G01Y530511D01*
G02X925509Y530369I-200J0D01*
G01X924497Y529357D01*
G02X924355Y529298I-142J141D01*
G01X906968D01*
G02X906826Y529357I0J200D01*
G01X906152Y530031D01*
X905958Y530225D01*
G02X905900Y530367I142J141D01*
G01Y532519D01*
G03X905899Y532547I-1201J-29D01*
G01Y533295D01*
G02X905958Y533437I200J0D01*
G01X906209Y533688D01*
G03X906226Y533705I-841J858D01*
G01X907947Y535426D01*
G03X908006Y535568I-141J142D01*
G01Y543876D01*
G02X908065Y544018I200J0D01*
G01X909082Y545035D01*
G02X909224Y545094I142J-141D01*
G01X915640D01*
G37*
G36*
G01X899018Y1441948D02*
X899489Y1442419D01*
G02X899631Y1442478I142J-141D01*
G01X915107D01*
G02X915249Y1442419I0J-200D01*
G01X916000Y1441668D01*
G02X916059Y1441526I-141J-142D01*
G01Y1425927D01*
G02X916000Y1425785I-200J0D01*
G01X915373Y1425158D01*
G02X915231Y1425099I-142J141D01*
G01X899911D01*
G02X899769Y1425158I0J200D01*
G01X899018Y1425909D01*
G02X898959Y1426051I141J142D01*
G01Y1441806D01*
G02X899018Y1441948I200J0D01*
G37*
G36*
G01X918483Y321670D02*
G03I-577J0D01*
G37*
G36*
G01X923206Y336609D02*
G03I-577J0D01*
G37*
G36*
G01X913783Y336489D02*
G03I-577J0D01*
G37*
G36*
G01X922775Y342051D02*
G03I-577J0D01*
G37*
G36*
G01X918435Y331453D02*
G03I-577J0D01*
G37*
G36*
G01X945538Y116495D02*
G03I-577J0D01*
G37*
G36*
G01X940738D02*
G03I-577J0D01*
G37*
G36*
G01X945538Y123582D02*
G03I-577J0D01*
G37*
G36*
G01Y130668D02*
G03I-577J0D01*
G37*
G36*
G01Y137755D02*
G03I-577J0D01*
G37*
G36*
G01X940183Y310521D02*
G03I-577J0D01*
G37*
G36*
G01X940230Y317474D02*
G03I-577J0D01*
G37*
G36*
G01X937185Y326058D02*
G03I-577J0D01*
G37*
G36*
G01X945697Y326441D02*
G03I-577J0D01*
G37*
G36*
G01X930975Y342050D02*
G03I-577J0D01*
G37*
G36*
G01X941501Y328959D02*
G03I-577J0D01*
G37*
G36*
G01X941549Y338238D02*
G03I-577J0D01*
G37*
G36*
G01X937030Y345336D02*
G03I-577J0D01*
G37*
G36*
G01X940683Y372200D02*
X956587D01*
G02X956729Y372141I0J-200D01*
G01X959817Y369053D01*
G02X959876Y368911I-141J-142D01*
G01Y355643D01*
G02X959817Y355501I-200J0D01*
G01X959092Y354776D01*
X958872Y354556D01*
G02X958731Y354498I-141J142D01*
G01X946368D01*
G03X946336Y354497I22J-1201D01*
G01X943071D01*
G02X942930Y354556I1J200D01*
G01X941964Y355521D01*
X939759Y357726D01*
G02X939700Y357868I141J142D01*
G01Y361236D01*
G02X939735Y361349I200J0D01*
G03Y363055I-1235J853D01*
G02X939700Y363168I165J113D01*
G01Y371217D01*
G02X939759Y371359I200J0D01*
G01X940541Y372141D01*
G02X940683Y372200I142J-141D01*
G37*
G36*
G01X932197Y584416D02*
G03I-577J0D01*
G37*
G36*
G01X932171Y599419D02*
G03I-577J0D01*
G37*
G36*
G01X932224Y593270D02*
G03I-577J0D01*
G37*
G36*
G01X932155Y590668D02*
G03I-577J0D01*
G37*
G36*
G01X1045542Y1422733D02*
X1031567D01*
G03X1031425Y1422674I0J-200D01*
G01X1029584Y1420833D01*
G03X1029525Y1420691I141J-142D01*
G01Y1406120D01*
G02X1029466Y1405978I-200J0D01*
G01X1028644Y1405156D01*
G02X1028502Y1405097I-142J141D01*
G01X997127D01*
G02X996985Y1405156I0J200D01*
G01X995905Y1406236D01*
G02X995846Y1406378I141J142D01*
G01Y1411565D01*
G03X995787Y1411707I-200J0D01*
G01X991112Y1416382D01*
G03X990970Y1416441I-142J-141D01*
G01X971645D01*
G02X971503Y1416500I0J200D01*
G01X967547Y1420456D01*
G03X967405Y1420515I-142J-141D01*
G01X935215D01*
X935206Y1420524D01*
X935173D01*
X933049Y1422648D01*
G02X932990Y1422790I141J142D01*
G01Y1440719D01*
G02X933049Y1440861I200J0D01*
G01X934135Y1441947D01*
G02X934277Y1442006I142J-141D01*
G01X1046898D01*
G02X1047040Y1441947I0J-200D01*
G01X1048619Y1440368D01*
G02X1048678Y1440226I-141J-142D01*
G01Y1425869D01*
G02X1048619Y1425727I-200J0D01*
G01X1045684Y1422792D01*
G02X1045542Y1422733I-142J141D01*
G37*
G36*
G01X954038Y1480156D02*
Y1451122D01*
G02X953979Y1450980I-200J0D01*
G01X953597Y1450598D01*
G02X953455Y1450539I-142J141D01*
G01X932938D01*
X932912Y1450565D01*
X930905D01*
G02X930763Y1450624I0J200D01*
G01X929532Y1451855D01*
G02X929473Y1451997I141J142D01*
G01Y1480693D01*
G02X929532Y1480835I200J0D01*
G01X930777Y1482080D01*
G02X930919Y1482139I142J-141D01*
G01X952055D01*
G02X952197Y1482080I0J-200D01*
G01X953979Y1480298D01*
G02X954038Y1480156I-141J-142D01*
G37*
G36*
G01X948038Y116495D02*
G03I-577J0D01*
G37*
G36*
G01Y123581D02*
G03I-577J0D01*
G37*
G36*
G01Y130668D02*
G03I-577J0D01*
G37*
G36*
G01X946176Y345383D02*
G03I-577J0D01*
G37*
G36*
G01X958794Y1450939D02*
X955821D01*
G02X955679Y1450998I0J200D01*
G01X955197Y1451480D01*
G02X955138Y1451622I141J142D01*
G01Y1485156D01*
G02X955197Y1485298I200J0D01*
G01X957035Y1487135D01*
G02X957177Y1487194I142J-141D01*
G01X1039022D01*
G02X1039220Y1487019I0J-200D01*
G03X1049086Y1467821I31202J3901D01*
G02X1049150Y1467674I-136J-147D01*
G01Y1451861D01*
G02X1049091Y1451719I-200J0D01*
G01X1048392Y1451020D01*
G02X1048250Y1450961I-142J141D01*
G01X958816D01*
X958794Y1450939D01*
G37*
G36*
G01X974140Y323878D02*
X987382D01*
G02X987524Y323819I0J-200D01*
G01X988161Y323182D01*
G02X988220Y323040I-141J-142D01*
G01Y315970D01*
G02X988150Y315817I-200J-1D01*
G01X987884Y315591D01*
X987800Y315568D01*
X987756Y315575D01*
G03X987517Y315594I-238J-1483D01*
G03Y312590I0J-1502D01*
G03X987756Y312609I1J1502D01*
G01X987800Y312616D01*
X987884Y312593D01*
X988150Y312367D01*
G02X988220Y312214I-130J-152D01*
G01Y308703D01*
G02X988161Y308561I-200J0D01*
G01X985975Y306375D01*
X985947Y306346D01*
X985873Y306316D01*
X975034D01*
G02X974893Y306375I1J200D01*
G01X973845Y307422D01*
G02X973787Y307564I142J141D01*
G01Y323525D01*
G02X973846Y323667I200J0D01*
G01X973998Y323819D01*
G02X974140Y323878I142J-141D01*
G37*
G36*
G01X976564Y854783D02*
G03I-639J0D01*
G37*
G36*
G01X964962Y1566784D02*
X993823D01*
G02X993965Y1566725I0J-200D01*
G01X995797Y1564893D01*
G02X995856Y1564751I-141J-142D01*
G01Y1547091D01*
G02X995797Y1546949I-200J0D01*
G01X993903Y1545055D01*
G02X993761Y1544996I-142J141D01*
G01X965293D01*
G02X965151Y1545055I0J200D01*
G01X963569Y1546637D01*
G02X963510Y1546779I141J142D01*
G01Y1565332D01*
G02X963569Y1565474I200J0D01*
G01X964820Y1566725D01*
G02X964962Y1566784I142J-141D01*
G37*
G36*
G01X998661Y122511D02*
G03I-577J0D01*
G37*
G36*
G01Y117555D02*
G03I-577J0D01*
G37*
G36*
G01X1040568Y388583D02*
G02I-19702J0D01*
G37*
G36*
G01X1020831Y97067D02*
G03I-577J0D01*
G37*
G36*
G01D02*
G03I-577J0D01*
G37*
G36*
G01X1043100Y116496D02*
G03I-577J0D01*
G37*
G36*
G01D02*
G03I-577J0D01*
G37*
G36*
G01Y130669D02*
G03I-577J0D01*
G37*
G36*
G01D02*
G03I-577J0D01*
G37*
G36*
G01Y123582D02*
G03I-577J0D01*
G37*
G36*
G01D02*
G03I-577J0D01*
G37*
G36*
G01Y137755D02*
G03I-577J0D01*
G37*
G36*
G01D02*
G03I-577J0D01*
G37*
G36*
G01X1050400Y109409D02*
G03I-577J0D01*
G37*
G36*
G01D02*
G03I-577J0D01*
G37*
G36*
G01Y116496D02*
G03I-577J0D01*
G37*
G36*
G01D02*
G03I-577J0D01*
G37*
G36*
G01X1047900D02*
G03I-577J0D01*
G37*
G36*
G01D02*
G03I-577J0D01*
G37*
G36*
G01X1050400Y130669D02*
G03I-577J0D01*
G37*
G36*
G01D02*
G03I-577J0D01*
G37*
G36*
G01X1047900D02*
G03I-577J0D01*
G37*
G36*
G01D02*
G03I-577J0D01*
G37*
G36*
G01Y123582D02*
G03I-577J0D01*
G37*
G36*
G01D02*
G03I-577J0D01*
G37*
G36*
G01X1050400D02*
G03I-577J0D01*
G37*
G36*
G01D02*
G03I-577J0D01*
G37*
G36*
G01X1047900Y137755D02*
G03I-577J0D01*
G37*
G36*
G01D02*
G03I-577J0D01*
G37*
G36*
G01X1052944Y402291D02*
G03I-577J0D01*
G37*
G36*
G01X1057936D02*
G03I-577J0D01*
G37*
G36*
G01X1052944Y397335D02*
G03I-577J0D01*
G37*
G36*
G01X1057936D02*
G03I-577J0D01*
G37*
G36*
G01X1050544Y411509D02*
G03I-577J0D01*
G37*
G36*
G01X1055536Y425682D02*
G03I-577J0D01*
G37*
G36*
G01X1050544D02*
G03I-577J0D01*
G37*
G36*
G01X1055536Y416465D02*
G03I-577J0D01*
G37*
G36*
G01Y411509D02*
G03I-577J0D01*
G37*
G36*
G01X1050544Y416465D02*
G03I-577J0D01*
G37*
G36*
G01Y439855D02*
G03I-577J0D01*
G37*
G36*
G01X1055536Y430638D02*
G03I-577J0D01*
G37*
G36*
G01X1050544D02*
G03I-577J0D01*
G37*
G36*
G01X1055536Y439855D02*
G03I-577J0D01*
G37*
G36*
G01X1050544Y444811D02*
G03I-577J0D01*
G37*
G36*
G01X1055536D02*
G03I-577J0D01*
G37*
G36*
G01X1050544Y473565D02*
G03I-577J0D01*
G37*
G36*
G01X1055536D02*
G03I-577J0D01*
G37*
G36*
G01X1050544Y468609D02*
G03I-577J0D01*
G37*
G36*
G01X1055536D02*
G03I-577J0D01*
G37*
G36*
G01X1050544Y487738D02*
G03I-577J0D01*
G37*
G36*
G01X1055536D02*
G03I-577J0D01*
G37*
G36*
G01X1050544Y482782D02*
G03I-577J0D01*
G37*
G36*
G01X1055536D02*
G03I-577J0D01*
G37*
G36*
G01X1050544Y512743D02*
G03I-577J0D01*
G37*
G36*
G01X1055536D02*
G03I-577J0D01*
G37*
G36*
G01X1050544Y517699D02*
G03I-577J0D01*
G37*
G36*
G01X1055536D02*
G03I-577J0D01*
G37*
G36*
G01Y526916D02*
G03I-577J0D01*
G37*
G36*
G01X1050544D02*
G03I-577J0D01*
G37*
G36*
G01X1055536Y531872D02*
G03I-577J0D01*
G37*
G36*
G01X1050544D02*
G03I-577J0D01*
G37*
G36*
G01X1060946Y390223D02*
G03I-577J0D01*
G37*
G36*
G01X1065938D02*
G03I-577J0D01*
G37*
G36*
G01Y404396D02*
G03I-577J0D01*
G37*
G36*
G01Y409352D02*
G03I-577J0D01*
G37*
G36*
G01X1060946Y395179D02*
G03I-577J0D01*
G37*
G36*
G01Y404396D02*
G03I-577J0D01*
G37*
G36*
G01Y409352D02*
G03I-577J0D01*
G37*
G36*
G01X1065938Y395179D02*
G03I-577J0D01*
G37*
G36*
G01X1060946Y418569D02*
G03I-577J0D01*
G37*
G36*
G01Y423525D02*
G03I-577J0D01*
G37*
G36*
G01X1065938D02*
G03I-577J0D01*
G37*
G36*
G01Y418569D02*
G03I-577J0D01*
G37*
G36*
G01X1060946Y432743D02*
G03I-577J0D01*
G37*
G36*
G01Y437699D02*
G03I-577J0D01*
G37*
G36*
G01X1065938Y432743D02*
G03I-577J0D01*
G37*
G36*
G01Y437699D02*
G03I-577J0D01*
G37*
G36*
G01Y489895D02*
G03I-577J0D01*
G37*
G36*
G01X1060946D02*
G03I-577J0D01*
G37*
G36*
G01Y480677D02*
G03I-577J0D01*
G37*
G36*
G01Y475721D02*
G03I-577J0D01*
G37*
G36*
G01X1065938Y480677D02*
G03I-577J0D01*
G37*
G36*
G01Y475721D02*
G03I-577J0D01*
G37*
G36*
G01X1060946Y494851D02*
G03I-577J0D01*
G37*
G36*
G01X1065938D02*
G03I-577J0D01*
G37*
G36*
G01X1060946Y519855D02*
G03I-577J0D01*
G37*
G36*
G01X1065938D02*
G03I-577J0D01*
G37*
G36*
G01Y524811D02*
G03I-577J0D01*
G37*
G36*
G01X1060946D02*
G03I-577J0D01*
G37*
G36*
G01Y538984D02*
G03I-577J0D01*
G37*
G36*
G01Y534028D02*
G03I-577J0D01*
G37*
G36*
G01X1065938Y538984D02*
G03I-577J0D01*
G37*
G36*
G01Y534028D02*
G03I-577J0D01*
G37*
G36*
G01X1078432Y327478D02*
G03I-577J0D01*
G37*
G36*
G01X1077829Y323521D02*
G03I-577J0D01*
G37*
G36*
G01Y318565D02*
G03I-577J0D01*
G37*
G36*
G01X1078432Y332434D02*
G03I-577J0D01*
G37*
G36*
G01X1080440Y345660D02*
G03I-577J0D01*
G37*
G36*
G01X1123190Y97041D02*
G03I-577J0D01*
G37*
G36*
G01D02*
G03I-577J0D01*
G37*
G36*
G01X1152762Y109409D02*
G03I-577J0D01*
G37*
G36*
G01D02*
G03I-577J0D01*
G37*
G36*
G01Y116496D02*
G03I-577J0D01*
G37*
G36*
G01D02*
G03I-577J0D01*
G37*
G36*
G01X1150262D02*
G03I-577J0D01*
G37*
G36*
G01D02*
G03I-577J0D01*
G37*
G36*
G01X1145462D02*
G03I-577J0D01*
G37*
G36*
G01D02*
G03I-577J0D01*
G37*
G36*
G01Y130669D02*
G03I-577J0D01*
G37*
G36*
G01Y123582D02*
G03I-577J0D01*
G37*
G36*
G01D02*
G03I-577J0D01*
G37*
G36*
G01X1152762Y130669D02*
G03I-577J0D01*
G37*
G36*
G01D02*
G03I-577J0D01*
G37*
G36*
G01X1150262D02*
G03I-577J0D01*
G37*
G36*
G01D02*
G03I-577J0D01*
G37*
G36*
G01Y123582D02*
G03I-577J0D01*
G37*
G36*
G01D02*
G03I-577J0D01*
G37*
G36*
G01X1152762D02*
G03I-577J0D01*
G37*
G36*
G01D02*
G03I-577J0D01*
G37*
G36*
G01X1145462Y130669D02*
G03I-577J0D01*
G37*
G36*
G01Y137755D02*
G03I-577J0D01*
G37*
G36*
G01X1150262D02*
G03I-577J0D01*
G37*
G36*
G01D02*
G03I-577J0D01*
G37*
G36*
G01X1145462D02*
G03I-577J0D01*
G37*
G36*
G01X1168333Y92733D02*
G03I-577J0D01*
G37*
G36*
G01D02*
G03I-577J0D01*
G37*
G36*
G01X1225618Y97079D02*
G03I-577J0D01*
G37*
G36*
G01D02*
G03I-577J0D01*
G37*
G36*
G01X1238239Y471484D02*
G03I-577J0D01*
G37*
G36*
G01X1233247Y466528D02*
G03I-577J0D01*
G37*
G36*
G01X1238239D02*
G03I-577J0D01*
G37*
G36*
G01X1233247Y471484D02*
G03I-577J0D01*
G37*
G36*
G01X1238239Y485657D02*
G03I-577J0D01*
G37*
G36*
G01Y480701D02*
G03I-577J0D01*
G37*
G36*
G01X1233247D02*
G03I-577J0D01*
G37*
G36*
G01Y485657D02*
G03I-577J0D01*
G37*
G36*
G01X1247824Y116496D02*
G03I-577J0D01*
G37*
G36*
G01D02*
G03I-577J0D01*
G37*
G36*
G01X1252624D02*
G03I-577J0D01*
G37*
G36*
G01D02*
G03I-577J0D01*
G37*
G36*
G01X1247824Y123582D02*
G03I-577J0D01*
G37*
G36*
G01D02*
G03I-577J0D01*
G37*
G36*
G01Y130669D02*
G03I-577J0D01*
G37*
G36*
G01D02*
G03I-577J0D01*
G37*
G36*
G01X1252624Y123582D02*
G03I-577J0D01*
G37*
G36*
G01D02*
G03I-577J0D01*
G37*
G36*
G01Y130669D02*
G03I-577J0D01*
G37*
G36*
G01D02*
G03I-577J0D01*
G37*
G36*
G01X1247824Y137755D02*
G03I-577J0D01*
G37*
G36*
G01D02*
G03I-577J0D01*
G37*
G36*
G01X1252624D02*
G03I-577J0D01*
G37*
G36*
G01D02*
G03I-577J0D01*
G37*
G36*
G01X1248641Y473640D02*
G03I-577J0D01*
G37*
G36*
G01X1243649D02*
G03I-577J0D01*
G37*
G36*
G01Y487813D02*
G03I-577J0D01*
G37*
G36*
G01X1248641D02*
G03I-577J0D01*
G37*
G36*
G01X1243649Y478596D02*
G03I-577J0D01*
G37*
G36*
G01X1248641D02*
G03I-577J0D01*
G37*
G36*
G01X1243649Y492769D02*
G03I-577J0D01*
G37*
G36*
G01X1248641D02*
G03I-577J0D01*
G37*
G36*
G01X1255124Y109409D02*
G03I-577J0D01*
G37*
G36*
G01D02*
G03I-577J0D01*
G37*
G36*
G01Y116496D02*
G03I-577J0D01*
G37*
G36*
G01D02*
G03I-577J0D01*
G37*
G36*
G01Y123582D02*
G03I-577J0D01*
G37*
G36*
G01D02*
G03I-577J0D01*
G37*
G36*
G01Y130669D02*
G03I-577J0D01*
G37*
G36*
G01D02*
G03I-577J0D01*
G37*
G36*
G01X1265058Y300223D02*
G03I-577J0D01*
G37*
G36*
G01X1397825Y116496D02*
G03I-577J0D01*
G37*
G36*
G01D02*
G03I-577J0D01*
G37*
G36*
G01Y130669D02*
G03I-577J0D01*
G37*
G36*
G01D02*
G03I-577J0D01*
G37*
G36*
G01Y123582D02*
G03I-577J0D01*
G37*
G36*
G01D02*
G03I-577J0D01*
G37*
G36*
G01Y137755D02*
G03I-577J0D01*
G37*
G36*
G01D02*
G03I-577J0D01*
G37*
G36*
G01X1405125Y116496D02*
G03I-577J0D01*
G37*
G36*
G01D02*
G03I-577J0D01*
G37*
G36*
G01X1402625D02*
G03I-577J0D01*
G37*
G36*
G01D02*
G03I-577J0D01*
G37*
G36*
G01X1405125Y109409D02*
G03I-577J0D01*
G37*
G36*
G01D02*
G03I-577J0D01*
G37*
G36*
G01X1402625Y123582D02*
G03I-577J0D01*
G37*
G36*
G01D02*
G03I-577J0D01*
G37*
G36*
G01X1405125D02*
G03I-577J0D01*
G37*
G36*
G01D02*
G03I-577J0D01*
G37*
G36*
G01Y130669D02*
G03I-577J0D01*
G37*
G36*
G01D02*
G03I-577J0D01*
G37*
G36*
G01X1402625D02*
G03I-577J0D01*
G37*
G36*
G01D02*
G03I-577J0D01*
G37*
G36*
G01Y137755D02*
G03I-577J0D01*
G37*
G36*
G01D02*
G03I-577J0D01*
G37*
G36*
G01X1404894Y989436D02*
G03I-577J0D01*
G37*
G36*
G01X1411615Y985379D02*
G03I-577J0D01*
G37*
G36*
G01X1504987Y116496D02*
G03I-577J0D01*
G37*
G36*
G01D02*
G03I-577J0D01*
G37*
G36*
G01X1507487Y109409D02*
G03I-577J0D01*
G37*
G36*
G01D02*
G03I-577J0D01*
G37*
G36*
G01X1500187Y116496D02*
G03I-577J0D01*
G37*
G36*
G01D02*
G03I-577J0D01*
G37*
G36*
G01X1507487D02*
G03I-577J0D01*
G37*
G36*
G01D02*
G03I-577J0D01*
G37*
G36*
G01X1504987Y130669D02*
G03I-577J0D01*
G37*
G36*
G01Y123582D02*
G03I-577J0D01*
G37*
G36*
G01D02*
G03I-577J0D01*
G37*
G36*
G01X1507487D02*
G03I-577J0D01*
G37*
G36*
G01D02*
G03I-577J0D01*
G37*
G36*
G01X1500187Y130669D02*
G03I-577J0D01*
G37*
G36*
G01D02*
G03I-577J0D01*
G37*
G36*
G01Y123582D02*
G03I-577J0D01*
G37*
G36*
G01D02*
G03I-577J0D01*
G37*
G36*
G01X1507487Y130669D02*
G03I-577J0D01*
G37*
G36*
G01D02*
G03I-577J0D01*
G37*
G36*
G01X1504987D02*
G03I-577J0D01*
G37*
G36*
G01X1500187Y137755D02*
G03I-577J0D01*
G37*
G36*
G01D02*
G03I-577J0D01*
G37*
G36*
G01X1504987D02*
G03I-577J0D01*
G37*
G36*
G01D02*
G03I-577J0D01*
G37*
G36*
G01X1501057Y295727D02*
G03I-577J0D01*
G37*
G36*
G01X1579256Y613047D02*
G03I-577J0D01*
G37*
G36*
G01X1578691Y607563D02*
G03I-577J0D01*
G37*
G36*
G01X1574799Y629871D02*
G03I-577J0D01*
G37*
G36*
G01X1579917Y396239D02*
G03I-577J0D01*
G37*
G36*
G01Y403326D02*
G03I-577J0D01*
G37*
G36*
G01X1582417Y396239D02*
G03I-577J0D01*
G37*
G36*
G01X1587217D02*
G03I-577J0D01*
G37*
G36*
G01Y403325D02*
G03I-577J0D01*
G37*
G36*
G01X1582417D02*
G03I-577J0D01*
G37*
G36*
G01X1579917Y424585D02*
G03I-577J0D01*
G37*
G36*
G01X1587217Y417498D02*
G03I-577J0D01*
G37*
G36*
G01X1582417D02*
G03I-577J0D01*
G37*
G36*
G01Y424585D02*
G03I-577J0D01*
G37*
G36*
G01X1587217D02*
G03I-577J0D01*
G37*
G36*
G01X1579917Y410412D02*
G03I-577J0D01*
G37*
G36*
G01X1582417D02*
G03I-577J0D01*
G37*
G36*
G01X1587217D02*
G03I-577J0D01*
G37*
G36*
G01X1579917Y417499D02*
G03I-577J0D01*
G37*
G36*
G01Y438759D02*
G03I-577J0D01*
G37*
G36*
G01X1582417D02*
G03I-577J0D01*
G37*
G36*
G01X1587217D02*
G03I-577J0D01*
G37*
G36*
G01Y431672D02*
G03I-577J0D01*
G37*
G36*
G01X1582417D02*
G03I-577J0D01*
G37*
G36*
G01X1579917D02*
G03I-577J0D01*
G37*
G36*
G01Y445846D02*
G03I-577J0D01*
G37*
G36*
G01X1587217Y467538D02*
G03I-577J0D01*
G37*
G36*
G01X1582417D02*
G03I-577J0D01*
G37*
G36*
G01X1579917Y488798D02*
G03I-577J0D01*
G37*
G36*
G01X1582417D02*
G03I-577J0D01*
G37*
G36*
G01X1587217D02*
G03I-577J0D01*
G37*
G36*
G01X1579917Y474625D02*
G03I-577J0D01*
G37*
G36*
G01X1582417D02*
G03I-577J0D01*
G37*
G36*
G01X1587217D02*
G03I-577J0D01*
G37*
G36*
G01X1579917Y481711D02*
G03I-577J0D01*
G37*
G36*
G01X1582417D02*
G03I-577J0D01*
G37*
G36*
G01X1587217D02*
G03I-577J0D01*
G37*
G36*
G01X1579917Y495885D02*
G03I-577J0D01*
G37*
G36*
G01X1580330Y599100D02*
G03I-577J0D01*
G37*
G36*
G01X1609849Y109409D02*
G03I-577J0D01*
G37*
G36*
G01D02*
G03I-577J0D01*
G37*
G36*
G01X1602549Y116496D02*
G03I-577J0D01*
G37*
G36*
G01D02*
G03I-577J0D01*
G37*
G36*
G01X1609849D02*
G03I-577J0D01*
G37*
G36*
G01D02*
G03I-577J0D01*
G37*
G36*
G01X1607349D02*
G03I-577J0D01*
G37*
G36*
G01D02*
G03I-577J0D01*
G37*
G36*
G01X1602549Y123582D02*
G03I-577J0D01*
G37*
G36*
G01D02*
G03I-577J0D01*
G37*
G36*
G01Y130669D02*
G03I-577J0D01*
G37*
G36*
G01D02*
G03I-577J0D01*
G37*
G36*
G01X1607349Y123582D02*
G03I-577J0D01*
G37*
G36*
G01D02*
G03I-577J0D01*
G37*
G36*
G01X1609849D02*
G03I-577J0D01*
G37*
G36*
G01D02*
G03I-577J0D01*
G37*
G36*
G01Y130669D02*
G03I-577J0D01*
G37*
G36*
G01D02*
G03I-577J0D01*
G37*
G36*
G01X1607349D02*
G03I-577J0D01*
G37*
G36*
G01D02*
G03I-577J0D01*
G37*
G36*
G01Y137755D02*
G03I-577J0D01*
G37*
G36*
G01X1602549D02*
G03I-577J0D01*
G37*
G36*
G01D02*
G03I-577J0D01*
G37*
G36*
G01X1607349D02*
G03I-577J0D01*
G37*
G36*
G01X1597583Y290417D02*
G03I-577J0D01*
G37*
G36*
G01X1597291Y383002D02*
G03I-577J0D01*
G37*
G36*
G01X1599077Y1472500D02*
G03I-577J0D01*
G37*
G36*
G01X1598577Y1486000D02*
G03I-577J0D01*
G37*
G36*
G01X1604577Y1516000D02*
G03I-577J0D01*
G37*
G36*
G01X1626142Y472578D02*
G03I-577J0D01*
G37*
G36*
G01Y486751D02*
G03I-577J0D01*
G37*
G36*
G01Y479665D02*
G03I-577J0D01*
G37*
G36*
G01Y493838D02*
G03I-577J0D01*
G37*
G36*
G01Y516712D02*
G03I-577J0D01*
G37*
G36*
G01Y523799D02*
G03I-577J0D01*
G37*
G36*
G01Y537972D02*
G03I-577J0D01*
G37*
G36*
G01Y530885D02*
G03I-577J0D01*
G37*
G36*
G01Y566752D02*
G03I-577J0D01*
G37*
G36*
G01Y588012D02*
G03I-577J0D01*
G37*
G36*
G01Y573839D02*
G03I-577J0D01*
G37*
G36*
G01Y580925D02*
G03I-577J0D01*
G37*
G36*
G01Y595098D02*
G03I-577J0D01*
G37*
G36*
G01Y602185D02*
G03I-577J0D01*
G37*
G36*
G01Y609271D02*
G03I-577J0D01*
G37*
G36*
G01Y616358D02*
G03I-577J0D01*
G37*
G36*
G01X1636564Y335615D02*
G03I-577J0D01*
G37*
G36*
G01X1631280Y350654D02*
G03I-577J0D01*
G37*
G36*
G01X1637045Y345594D02*
G03I-577J0D01*
G37*
G36*
G01X1633442Y472578D02*
G03I-577J0D01*
G37*
G36*
G01X1630942D02*
G03I-577J0D01*
G37*
G36*
G01X1633442Y465491D02*
G03I-577J0D01*
G37*
G36*
G01X1630942Y479665D02*
G03I-577J0D01*
G37*
G36*
G01X1633442Y479664D02*
G03I-577J0D01*
G37*
G36*
G01X1630942Y486751D02*
G03I-577J0D01*
G37*
G36*
G01X1633442D02*
G03I-577J0D01*
G37*
G36*
G01X1630942Y493838D02*
G03I-577J0D01*
G37*
G36*
G01X1633442D02*
G03I-577J0D01*
G37*
G36*
G01Y516712D02*
G03I-577J0D01*
G37*
G36*
G01X1630942D02*
G03I-577J0D01*
G37*
G36*
G01Y523799D02*
G03I-577J0D01*
G37*
G36*
G01X1633442D02*
G03I-577J0D01*
G37*
G36*
G01X1630942Y537972D02*
G03I-577J0D01*
G37*
G36*
G01Y530885D02*
G03I-577J0D01*
G37*
G36*
G01X1633442D02*
G03I-577J0D01*
G37*
G36*
G01X1630942Y566752D02*
G03I-577J0D01*
G37*
G36*
G01X1633442D02*
G03I-577J0D01*
G37*
G36*
G01Y573838D02*
G03I-577J0D01*
G37*
G36*
G01X1630942Y580925D02*
G03I-577J0D01*
G37*
G36*
G01X1633442D02*
G03I-577J0D01*
G37*
G36*
G01X1630942Y588012D02*
G03I-577J0D01*
G37*
G36*
G01X1633442Y588011D02*
G03I-577J0D01*
G37*
G36*
G01X1630942Y573839D02*
G03I-577J0D01*
G37*
G36*
G01X1633442Y602184D02*
G03I-577J0D01*
G37*
G36*
G01X1630942Y602185D02*
G03I-577J0D01*
G37*
G36*
G01X1633442Y595098D02*
G03I-577J0D01*
G37*
G36*
G01X1630942D02*
G03I-577J0D01*
G37*
G36*
G01Y616358D02*
G03I-577J0D01*
G37*
G36*
G01X1633442Y609271D02*
G03I-577J0D01*
G37*
G36*
G01X1630942D02*
G03I-577J0D01*
G37*
G36*
G01X1655149Y771701D02*
G03I-577J0D01*
G37*
G36*
G01X1667835Y305338D02*
G03I-577J0D01*
G37*
G36*
G01X1690334Y466528D02*
G03I-577J0D01*
G37*
G36*
G01Y471484D02*
G03I-577J0D01*
G37*
G36*
G01Y480701D02*
G03I-577J0D01*
G37*
G36*
G01Y485657D02*
G03I-577J0D01*
G37*
G36*
G01Y515617D02*
G03I-577J0D01*
G37*
G36*
G01Y510661D02*
G03I-577J0D01*
G37*
G36*
G01Y524835D02*
G03I-577J0D01*
G37*
G36*
G01Y529791D02*
G03I-577J0D01*
G37*
G36*
G01Y565657D02*
G03I-577J0D01*
G37*
G36*
G01Y579830D02*
G03I-577J0D01*
G37*
G36*
G01Y574874D02*
G03I-577J0D01*
G37*
G36*
G01Y589047D02*
G03I-577J0D01*
G37*
G36*
G01Y603221D02*
G03I-577J0D01*
G37*
G36*
G01Y594003D02*
G03I-577J0D01*
G37*
G36*
G01Y608177D02*
G03I-577J0D01*
G37*
G36*
G01X1704911Y116496D02*
G03I-577J0D01*
G37*
G36*
G01D02*
G03I-577J0D01*
G37*
G36*
G01Y123582D02*
G03I-577J0D01*
G37*
G36*
G01D02*
G03I-577J0D01*
G37*
G36*
G01Y130669D02*
G03I-577J0D01*
G37*
G36*
G01D02*
G03I-577J0D01*
G37*
G36*
G01Y137756D02*
G03I-577J0D01*
G37*
G36*
G01D02*
G03I-577J0D01*
G37*
G36*
G01X1700736Y473640D02*
G03I-577J0D01*
G37*
G36*
G01X1705728D02*
G03I-577J0D01*
G37*
G36*
G01X1695326Y471484D02*
G03I-577J0D01*
G37*
G36*
G01Y466528D02*
G03I-577J0D01*
G37*
G36*
G01X1700736Y487813D02*
G03I-577J0D01*
G37*
G36*
G01X1705728D02*
G03I-577J0D01*
G37*
G36*
G01X1695326Y485657D02*
G03I-577J0D01*
G37*
G36*
G01X1705728Y478596D02*
G03I-577J0D01*
G37*
G36*
G01X1695326Y480701D02*
G03I-577J0D01*
G37*
G36*
G01X1700736Y478596D02*
G03I-577J0D01*
G37*
G36*
G01Y492769D02*
G03I-577J0D01*
G37*
G36*
G01X1705728D02*
G03I-577J0D01*
G37*
G36*
G01Y522730D02*
G03I-577J0D01*
G37*
G36*
G01X1695326Y510661D02*
G03I-577J0D01*
G37*
G36*
G01Y515617D02*
G03I-577J0D01*
G37*
G36*
G01X1700736Y517774D02*
G03I-577J0D01*
G37*
G36*
G01Y522730D02*
G03I-577J0D01*
G37*
G36*
G01X1705728Y517774D02*
G03I-577J0D01*
G37*
G36*
G01X1700736Y536903D02*
G03I-577J0D01*
G37*
G36*
G01X1705728D02*
G03I-577J0D01*
G37*
G36*
G01Y531947D02*
G03I-577J0D01*
G37*
G36*
G01X1695326Y524835D02*
G03I-577J0D01*
G37*
G36*
G01Y529791D02*
G03I-577J0D01*
G37*
G36*
G01X1700736Y531947D02*
G03I-577J0D01*
G37*
G36*
G01X1705728Y567813D02*
G03I-577J0D01*
G37*
G36*
G01X1700736D02*
G03I-577J0D01*
G37*
G36*
G01X1695326Y565657D02*
G03I-577J0D01*
G37*
G36*
G01Y579830D02*
G03I-577J0D01*
G37*
G36*
G01X1705728Y572769D02*
G03I-577J0D01*
G37*
G36*
G01X1700736D02*
G03I-577J0D01*
G37*
G36*
G01X1705728Y586943D02*
G03I-577J0D01*
G37*
G36*
G01Y581987D02*
G03I-577J0D01*
G37*
G36*
G01X1700736Y586943D02*
G03I-577J0D01*
G37*
G36*
G01Y581987D02*
G03I-577J0D01*
G37*
G36*
G01X1695326Y574874D02*
G03I-577J0D01*
G37*
G36*
G01Y589047D02*
G03I-577J0D01*
G37*
G36*
G01Y603221D02*
G03I-577J0D01*
G37*
G36*
G01X1700736Y601116D02*
G03I-577J0D01*
G37*
G36*
G01X1705728D02*
G03I-577J0D01*
G37*
G36*
G01Y596160D02*
G03I-577J0D01*
G37*
G36*
G01X1700736D02*
G03I-577J0D01*
G37*
G36*
G01X1695326Y594003D02*
G03I-577J0D01*
G37*
G36*
G01X1700736Y610333D02*
G03I-577J0D01*
G37*
G36*
G01X1695326Y608177D02*
G03I-577J0D01*
G37*
G36*
G01X1700736Y615289D02*
G03I-577J0D01*
G37*
G36*
G01X1705728Y610333D02*
G03I-577J0D01*
G37*
G36*
G01Y615289D02*
G03I-577J0D01*
G37*
G36*
G01X1709711Y116496D02*
G03I-577J0D01*
G37*
G36*
G01D02*
G03I-577J0D01*
G37*
G36*
G01X1712211D02*
G03I-577J0D01*
G37*
G36*
G01D02*
G03I-577J0D01*
G37*
G36*
G01Y109409D02*
G03I-577J0D01*
G37*
G36*
G01D02*
G03I-577J0D01*
G37*
G36*
G01Y130669D02*
G03I-577J0D01*
G37*
G36*
G01X1709711Y123582D02*
G03I-577J0D01*
G37*
G36*
G01D02*
G03I-577J0D01*
G37*
G36*
G01Y130669D02*
G03I-577J0D01*
G37*
G36*
G01D02*
G03I-577J0D01*
G37*
G36*
G01X1712211Y123582D02*
G03I-577J0D01*
G37*
G36*
G01D02*
G03I-577J0D01*
G37*
G36*
G01Y130669D02*
G03I-577J0D01*
G37*
G36*
G01X1709711Y137756D02*
G03I-577J0D01*
G37*
G36*
G01D02*
G03I-577J0D01*
G37*
G36*
G01X1716282Y328691D02*
G03I-577J0D01*
G37*
G36*
G01X1713311Y340533D02*
G03I-577J0D01*
G37*
G36*
G01X1731252Y1132361D02*
G03I-577J0D01*
G37*
G36*
G01X1727540Y1132319D02*
G03I-577J0D01*
G37*
G36*
G01X1743801Y1119055D02*
G03I-577J0D01*
G37*
G36*
G01X1791110Y303750D02*
G03I-577J0D01*
G37*
G36*
G01X1805570Y297591D02*
G03I-577J0D01*
G37*
G36*
G01X1792393Y1096776D02*
X1797172D01*
G02X1797331Y1096698I1J-200D01*
G01X1797553Y1096410D01*
X1797571Y1096320D01*
X1797559Y1096274D01*
G03X1797510Y1095893I1453J-381D01*
G03X1797936Y1094845I1502J0D01*
G01X1797969Y1094811D01*
X1797997Y1094724D01*
X1797938Y1094316D01*
X1797886Y1094241D01*
X1797845Y1094217D01*
G03X1797317Y1093721I734J-1310D01*
G01X1797295Y1093688D01*
X1797232Y1093643D01*
X1796883Y1093563D01*
X1796806Y1093576D01*
X1796772Y1093596D01*
G03X1795990Y1093816I-783J-1282D01*
G03X1794963Y1093410I0J-1502D01*
G01X1794935Y1093384D01*
X1794866Y1093356D01*
X1794514D01*
X1794445Y1093384D01*
X1794417Y1093410D01*
G03X1792363I-1027J-1096D01*
G01X1792335Y1093384D01*
X1792266Y1093356D01*
X1791914D01*
X1791845Y1093384D01*
X1791817Y1093410D01*
G03X1791775Y1093448I-1029J-1095D01*
G01X1791741Y1093478D01*
X1791705Y1093559D01*
X1791715Y1093957D01*
X1791755Y1094037D01*
X1791790Y1094064D01*
G03X1792365Y1095246I-927J1182D01*
G03X1792071Y1096138I-1502J-1D01*
G01X1792037Y1096184D01*
X1792028Y1096296D01*
X1792214Y1096666D01*
G02X1792393Y1096776I179J-90D01*
G37*
%LPC*%
G75*
G36*
G01X246639Y601484D02*
G02X246034Y602689I898J1205D01*
G02X249038I1502J0D01*
G02X248273Y601380I-1502J0D01*
G03X248230Y600711I196J-348D01*
G02X248835Y599506I-898J-1205D01*
G02X245831I-1502J0D01*
G02X246596Y600815I1502J0D01*
G03X246639Y601484I-196J348D01*
G37*
G36*
G01X241580Y636373D02*
G03X241161Y636743I-399J-29D01*
G02X241084Y636741I-77J1500D01*
G02Y639745I0J1502D01*
G02X242582Y638356I0J-1502D01*
G03X243001Y637986I399J29D01*
G02X243078Y637988I77J-1500D01*
G02Y634984I0J-1502D01*
G02X241580Y636373I0J1502D01*
G37*
G36*
G01X241630Y617558D02*
X241807Y617858D01*
X241818Y617932D01*
X241810Y617969D01*
G02X241776Y618288I1468J318D01*
G02X244780I1502J0D01*
G02X243710Y616850I-1501J0D01*
G01X243674Y616839D01*
X243615Y616793D01*
X243438Y616493D01*
X243427Y616419D01*
X243435Y616382D01*
G02X243469Y616063I-1468J-318D01*
G02X240465I-1502J0D01*
G02X241535Y617501I1501J0D01*
G01X241571Y617512D01*
X241630Y617558D01*
G37*
G36*
G01X146061Y599077D02*
X146364Y599351D01*
X146398Y599436D01*
X146395Y599482D01*
G02X146391Y599588I1498J110D01*
G02X147893Y598086I1502J0D01*
G02X147493Y598140I-1J1502D01*
G03X147305Y598096I-54J-193D01*
G01X147129Y597937D01*
G02X147141Y597882I-1461J-348D01*
G01X147149Y597842D01*
X147193Y597778D01*
X147494Y597577D01*
X147570Y597562D01*
X147609Y597569D01*
G02X147896Y597597I289J-1474D01*
G02Y594593I0J-1502D01*
G02X147554Y594632I-2J1502D01*
G01X147515Y594642D01*
X147437Y594629D01*
X147128Y594436D01*
X147082Y594371D01*
X147073Y594332D01*
G02X147069Y594315I-1464J336D01*
G01X147059Y594275D01*
X147073Y594195D01*
X147274Y593882D01*
X147340Y593836D01*
X147381Y593828D01*
G02X148596Y592354I-287J-1474D01*
G02X148135Y591271I-1503J0D01*
G01X148104Y591242D01*
X148073Y591166D01*
X148081Y590786D01*
X148116Y590711D01*
X148148Y590683D01*
G02X148657Y589556I-993J-1127D01*
G02X145653I-1502J0D01*
G02X146114Y590639I1503J0D01*
G01X146145Y590668D01*
X146176Y590744D01*
X146168Y591124D01*
X146133Y591199D01*
X146101Y591227D01*
G02X145592Y592354I993J1127D01*
G02X145634Y592707I1502J0D01*
G01X145644Y592747D01*
X145630Y592827D01*
X145429Y593140D01*
X145363Y593186D01*
X145322Y593194D01*
G02X144107Y594668I287J1474D01*
G02X144667Y595838I1502J0D01*
G01X144702Y595866D01*
X144741Y595944D01*
X144749Y596341D01*
X144714Y596421D01*
X144680Y596450D01*
G02X144168Y597580I991J1130D01*
G02X145670Y599082I1502J0D01*
G02X145927Y599060I1J-1502D01*
G01X145973Y599052D01*
X146061Y599077D01*
G37*
G36*
G01X185368Y560573D02*
G03X184997Y560944I-399J-28D01*
G02X183597Y562443I103J1499D01*
G02X185099Y563945I1502J0D01*
G02X186598Y562545I0J-1503D01*
G03X186969Y562174I399J28D01*
G02X188369Y560675I-103J-1499D01*
G02X186867Y559173I-1502J0D01*
G02X185368Y560573I0J1503D01*
G37*
G36*
G01X203592Y560000D02*
Y560337D01*
X203567Y560404D01*
X203543Y560432D01*
G02X203172Y561420I1130J988D01*
G02X206176I1502J0D01*
G02X205805Y560432I-1501J0D01*
G01X205781Y560404D01*
X205756Y560337D01*
Y560000D01*
X205781Y559933D01*
X205805Y559905D01*
G02X206176Y558917I-1130J-988D01*
G02X203172I-1502J0D01*
G02X203543Y559905I1501J0D01*
G01X203567Y559933D01*
X203592Y560000D01*
G37*
G36*
G01X203271Y552322D02*
X203081Y552664D01*
X203012Y552714D01*
X202969Y552724D01*
G02X201778Y554193I310J1469D01*
G02X204782I1502J0D01*
G02X204692Y553680I-1502J-1D01*
G01X204677Y553639D01*
X204683Y553554D01*
X204873Y553212D01*
X204942Y553162D01*
X204985Y553152D01*
G02X206176Y551683I-310J-1469D01*
G02X203172I-1502J0D01*
G02X203262Y552196I1502J1D01*
G01X203277Y552237D01*
X203271Y552322D01*
G37*
G36*
G01X721529Y440098D02*
G02X724533I1502J0D01*
G02X724163Y439111I-1501J0D01*
G01Y439110D01*
X724162D01*
G03X724114Y438980I152J-130D01*
G01Y438716D01*
G03X724162Y438586I200J0D01*
G01X724163Y438585D01*
G02Y436611I-1131J-987D01*
G01Y436610D01*
X724162D01*
G03X724114Y436480I152J-130D01*
G01Y436216D01*
G03X724162Y436086I200J0D01*
G01X724163Y436085D01*
G02Y434111I-1131J-987D01*
G01Y434110D01*
X724162D01*
G03X724114Y433980I152J-130D01*
G01Y433716D01*
G03X724162Y433586I200J0D01*
G01X724163Y433585D01*
G02Y431611I-1131J-987D01*
G01Y431610D01*
X724162D01*
G03X724114Y431480I152J-130D01*
G01Y431216D01*
G03X724162Y431086I200J0D01*
G01X724163Y431085D01*
G02X724533Y430098I-1131J-987D01*
G02X721529I-1502J0D01*
G02X721899Y431085I1501J0D01*
G01Y431086D01*
X721900D01*
G03X721948Y431216I-152J130D01*
G01Y431480D01*
G03X721900Y431610I-200J0D01*
G01X721899Y431611D01*
G02Y433585I1131J987D01*
G01Y433586D01*
X721900D01*
G03X721948Y433716I-152J130D01*
G01Y433980D01*
G03X721900Y434110I-200J0D01*
G01X721899Y434111D01*
G02Y436085I1131J987D01*
G01Y436086D01*
X721900D01*
G03X721948Y436216I-152J130D01*
G01Y436480D01*
G03X721900Y436610I-200J0D01*
G01X721899Y436611D01*
G02Y438585I1131J987D01*
G01Y438586D01*
X721900D01*
G03X721948Y438716I-152J130D01*
G01Y438980D01*
G03X721900Y439110I-200J0D01*
G01X721899Y439111D01*
G02X721529Y440098I1131J987D01*
G37*
G36*
G01X720595Y453881D02*
G02X723599I1502J0D01*
G02X723494Y453330I-1502J1D01*
G01X723477Y453288D01*
X723483Y453201D01*
X723652Y452891D01*
G03X723787Y452791I176J96D01*
G01X723788D01*
G02X724993Y451319I-297J-1472D01*
G02X721989I-1502J0D01*
G02X722094Y451870I1502J-1D01*
G01X722111Y451912D01*
X722105Y451999D01*
X721936Y452309D01*
G03X721801Y452409I-176J-96D01*
G01X721800D01*
G02X720595Y453881I297J1472D01*
G37*
G36*
G01X740021Y454744D02*
G02X743025I1502J0D01*
G02X742547Y453645I-1502J0D01*
G01X742517Y453618D01*
X742484Y453544D01*
X742477Y453175D01*
X742506Y453101D01*
X742535Y453072D01*
G02X742967Y452018I-1070J-1054D01*
G02X739963I-1502J0D01*
G02X740441Y453117I1502J0D01*
G01X740471Y453144D01*
X740504Y453218D01*
X740511Y453587D01*
X740482Y453661D01*
X740453Y453690D01*
G02X740021Y454744I1070J1054D01*
G37*
G36*
G01X739600Y460047D02*
G03X740073Y460400I75J393D01*
G02X741568Y461752I1495J-151D01*
G02Y458748I0J-1502D01*
G01X741567D01*
G02X741284Y458775I1J1502D01*
G03X740811Y458422I-75J-393D01*
G02X739316Y457070I-1495J151D01*
G02Y460074I0J1502D01*
G01X739317D01*
G02X739600Y460047I-1J-1502D01*
G37*
G36*
G01X749402Y463990D02*
G02Y466994I0J1502D01*
G02X750898Y465631I0J-1502D01*
G01X750902Y465584D01*
X750951Y465505D01*
X751263Y465312D01*
G03X751441Y465296I105J170D01*
G02X752097Y465420I657J-1679D01*
G02X753900Y463617I0J-1803D01*
G01Y460217D01*
G02X752097Y458414I-1803J0D01*
G02X751436Y458540I1J1803D01*
G01X751392Y458557D01*
X751301Y458550D01*
X750948Y458341D01*
X750898Y458264D01*
X750892Y458218D01*
G02X749402Y456904I-1490J188D01*
G02Y459908I0J1502D01*
G02X749931Y459812I0J-1503D01*
G03X750120Y459838I71J187D01*
G01X750218Y459911D01*
G03X750299Y460087I-118J161D01*
G02X750294Y460217I1798J134D01*
G01Y463617D01*
G02X750295Y463648I1802J-43D01*
G01Y463649D01*
G03X750218Y463809I-200J2D01*
G01X749967Y464006D01*
G03X749792Y464041I-123J-158D01*
G01X749791D01*
G02X749404Y463990I-388J1451D01*
G01X749402D01*
G37*
G36*
G01X775672Y352642D02*
G02X774419Y351968I-1253J828D01*
G02Y354972I0J1502D01*
G02X775653Y354326I0J-1502D01*
G03X776316Y354334I329J228D01*
G02X777569Y355008I1253J-828D01*
G02Y352004I0J-1502D01*
G02X776335Y352650I0J1502D01*
G03X775672Y352642I-329J-228D01*
G37*
G36*
G01X756386Y396425D02*
G02X756175Y396410I-212J1487D01*
G01X756174D01*
G02X757676Y397912I0J1502D01*
G01Y397911D01*
G02X757620Y397505I-1502J0D01*
G03X758079Y397003I385J-109D01*
G02X758381Y397032I307J-1612D01*
G02X756740Y395391I0J-1641D01*
G02X756823Y395904I1641J-2D01*
G03X756386Y396425I-380J125D01*
G37*
G36*
G01X733430Y468869D02*
G02Y465865I0J-1502D01*
G02X733183Y465886I3J1502D01*
G01X733181D01*
G03X733043Y465858I-32J-197D01*
G01X732818Y465717D01*
G03X732732Y465605I105J-170D01*
G01Y465604D01*
G02X732703Y465514I-1443J415D01*
G01X732686Y465470D01*
X732697Y465376D01*
X732924Y465028D01*
X733006Y464981D01*
X733053Y464978D01*
G02X734461Y463479I-94J-1499D01*
G02X731457I-1502J0D01*
G01Y463481D01*
G02X731547Y463992I1502J-1D01*
G01X731564Y464036D01*
X731553Y464130D01*
X731326Y464478D01*
X731244Y464525D01*
X731197Y464528D01*
G02X729789Y466027I94J1499D01*
G02X731291Y467529I1502J0D01*
G02X731538Y467508I-3J-1502D01*
G01X731540D01*
G03X731678Y467536I32J197D01*
G01X731903Y467677D01*
G03X731989Y467789I-105J170D01*
G01Y467790D01*
G02X733430Y468869I1441J-423D01*
G37*
G36*
G01X740176Y472106D02*
G02X740100Y472577I1426J472D01*
G01Y472579D01*
G02X741602Y471077I1502J0D01*
G01X741600D01*
G02X741236Y471122I1J1502D01*
G03X740759Y470609I-97J-388D01*
G02X740835Y470138I-1426J-472D01*
G01Y470136D01*
G02X739333Y471638I-1502J0D01*
G01X739335D01*
G02X739699Y471593I-1J-1502D01*
G03X740176Y472106I97J388D01*
G37*
G36*
G01X776989Y472316D02*
X777106Y472287D01*
G03X777247Y472304I48J194D01*
G02X778913I833J-1599D01*
G03X779054Y472287I93J177D01*
G01X779171Y472316D01*
G03X779287Y472395I-47J194D01*
G02X780576Y473062I1289J-912D01*
G02Y469906I0J-1578D01*
G02X780342Y469923I-3J1578D01*
G01X780299Y469929D01*
X780215Y469905D01*
X779952Y469679D01*
G03X779882Y469527I130J-152D01*
G01Y468485D01*
G03X779952Y468333I200J0D01*
G01X780215Y468107D01*
X780299Y468083D01*
X780342Y468089D01*
G02X780576Y468106I231J-1561D01*
G02Y464950I0J-1578D01*
G02X779287Y465617I0J1579D01*
G03X779171Y465696I-163J-115D01*
G01X779054Y465725D01*
G03X778913Y465708I-48J-194D01*
G02X778080Y465504I-833J1599D01*
G02X777247Y465707I-2J1802D01*
G03X777107Y465724I-93J-177D01*
G01X776990Y465696D01*
G03X776874Y465617I48J-194D01*
G02X775585Y464950I-1289J912D01*
G02Y468106I0J1578D01*
G02X775818Y468089I2J-1578D01*
G01X775862Y468083D01*
X775945Y468107D01*
X776208Y468333D01*
G03X776278Y468485I-130J152D01*
G01Y469527D01*
G03X776208Y469679I-200J0D01*
G01X775945Y469905D01*
X775861Y469929D01*
X775818Y469923D01*
G02X775584Y469906I-231J1561D01*
G02Y473062I0J1578D01*
G02X776873Y472395I0J-1579D01*
G03X776989Y472316I163J115D01*
G37*
G36*
G01X787391Y479428D02*
X787508Y479399D01*
G03X787649Y479416I48J194D01*
G02X789315I833J-1599D01*
G03X789456Y479399I93J177D01*
G01X789573Y479428D01*
G03X789689Y479507I-47J194D01*
G02X790978Y480174I1289J-912D01*
G02Y477018I0J-1578D01*
G02X790744Y477035I-3J1578D01*
G01X790701Y477041D01*
X790617Y477017D01*
X790354Y476791D01*
G03X790284Y476639I130J-152D01*
G01Y475597D01*
G03X790354Y475445I200J0D01*
G01X790617Y475219D01*
X790701Y475195D01*
X790744Y475201D01*
G02X790978Y475218I231J-1561D01*
G02Y472062I0J-1578D01*
G02X789689Y472729I0J1579D01*
G03X789573Y472808I-163J-115D01*
G01X789456Y472837D01*
G03X789315Y472820I-48J-194D01*
G02X787649I-833J1599D01*
G03X787508Y472837I-93J-177D01*
G01X787391Y472808D01*
G03X787275Y472729I47J-194D01*
G02X785986Y472062I-1289J912D01*
G02Y475218I0J1578D01*
G02X786220Y475201I3J-1578D01*
G01X786263Y475195D01*
X786347Y475219D01*
X786610Y475445D01*
G03X786680Y475597I-130J152D01*
G01Y476639D01*
G03X786610Y476791I-200J0D01*
G01X786347Y477017D01*
X786263Y477041D01*
X786220Y477035D01*
G02X785986Y477018I-231J1561D01*
G02Y480174I0J1578D01*
G02X787275Y479507I0J-1579D01*
G03X787391Y479428I163J115D01*
G37*
G36*
G01X776989Y486489D02*
X777106Y486460D01*
G03X777247Y486477I48J194D01*
G02X778080Y486682I835J-1598D01*
G02X778913Y486477I-2J-1803D01*
G03X779054Y486460I93J177D01*
G01X779171Y486489D01*
G03X779287Y486568I-47J194D01*
G02X780576Y487236I1289J-910D01*
G02Y484078I0J-1579D01*
G02X780342Y484096I4J1579D01*
G01X780299Y484102D01*
X780215Y484078D01*
X779952Y483852D01*
G03X779882Y483700I130J-152D01*
G01Y482658D01*
G03X779952Y482506I200J0D01*
G01X780215Y482280D01*
X780299Y482256D01*
X780342Y482262D01*
G02X780576Y482280I238J-1561D01*
G02Y479122I0J-1579D01*
G02X779287Y479790I0J1578D01*
G03X779171Y479869I-163J-115D01*
G01X779054Y479898D01*
G03X778913Y479881I-48J-194D01*
G02X778080Y479676I-835J1598D01*
G02X777247Y479881I2J1803D01*
G03X777106Y479898I-93J-177D01*
G01X776989Y479869D01*
G03X776873Y479790I47J-194D01*
G02X775584Y479122I-1289J910D01*
G02Y482280I0J1579D01*
G02X775818Y482262I-4J-1579D01*
G01X775861Y482256D01*
X775945Y482280D01*
X776208Y482506D01*
G03X776278Y482658I-130J152D01*
G01Y483700D01*
G03X776208Y483852I-200J0D01*
G01X775945Y484078D01*
X775861Y484102D01*
X775818Y484096D01*
G02X775584Y484078I-238J1561D01*
G02Y487236I0J1579D01*
G02X776873Y486568I0J-1578D01*
G03X776989Y486489I163J115D01*
G37*
G36*
G01X787391Y493601D02*
X787508Y493572D01*
G03X787649Y493589I48J194D01*
G02X788482Y493794I835J-1598D01*
G02X789315Y493589I-2J-1803D01*
G03X789456Y493572I93J177D01*
G01X789573Y493601D01*
G03X789689Y493680I-47J194D01*
G02X790978Y494348I1289J-910D01*
G02Y491190I0J-1579D01*
G02X790744Y491208I4J1579D01*
G01X790701Y491214D01*
X790617Y491190D01*
X790354Y490964D01*
G03X790284Y490812I130J-152D01*
G01Y489770D01*
G03X790354Y489618I200J0D01*
G01X790617Y489392D01*
X790701Y489368D01*
X790744Y489374D01*
G02X790978Y489392I238J-1561D01*
G02Y486234I0J-1579D01*
G02X789689Y486902I0J1578D01*
G03X789573Y486981I-163J-115D01*
G01X789456Y487010D01*
G03X789315Y486993I-48J-194D01*
G02X788482Y486788I-835J1598D01*
G02X787649Y486993I2J1803D01*
G03X787508Y487010I-93J-177D01*
G01X787391Y486981D01*
G03X787275Y486902I47J-194D01*
G02X785986Y486234I-1289J910D01*
G02Y489392I0J1579D01*
G02X786220Y489374I-4J-1579D01*
G01X786263Y489368D01*
X786347Y489392D01*
X786610Y489618D01*
G03X786680Y489770I-130J152D01*
G01Y490812D01*
G03X786610Y490964I-200J0D01*
G01X786347Y491190D01*
X786263Y491214D01*
X786220Y491208D01*
G02X785986Y491190I-238J1561D01*
G02Y494348I0J1579D01*
G02X787275Y493680I0J-1578D01*
G03X787391Y493601I163J115D01*
G37*
G36*
G01X714278Y493770D02*
X714584Y493981D01*
X714627Y494049D01*
X714634Y494090D01*
G02X716192Y495416I1558J-252D01*
G02Y492260I0J-1578D01*
G02X715925Y492282I-4J1578D01*
G03X715763Y492238I-33J-197D01*
G01X715666Y492157D01*
G03X715594Y492003I128J-154D01*
G01Y488597D01*
Y488587D01*
G03X715666Y488433I200J0D01*
G01X715763Y488351D01*
G03X715925Y488307I129J153D01*
G02X716192Y488330I269J-1556D01*
G02X717247Y487925I-1J-1579D01*
G03X717381Y487874I133J149D01*
G01X717503D01*
G03X717637Y487925I1J200D01*
G02X718692Y488330I1056J-1174D01*
G02X720250Y487003I0J-1578D01*
G01X720257Y486962D01*
X720300Y486894D01*
X720606Y486683D01*
X720686Y486667D01*
X720726Y486675D01*
G02X721092Y486712I363J-1765D01*
G02X721518Y486661I0J-1802D01*
G01X721559Y486651D01*
X721641Y486666D01*
X721956Y486876D01*
X722001Y486945D01*
X722008Y486987D01*
G02X723491Y488254I1483J-234D01*
G02Y485250I0J-1502D01*
G02X723224Y485274I0J1502D01*
G03X723058Y485228I-35J-197D01*
G01X722962Y485145D01*
G03X722893Y484986I131J-151D01*
G02X722894Y484910I-1801J-62D01*
G01Y481510D01*
G02X722893Y481432I-1802J-16D01*
G03X722962Y481272I200J-9D01*
G01X723058Y481189D01*
G03X723224Y481143I131J151D01*
G02X723491Y481167I267J-1478D01*
G02Y478163I0J-1502D01*
G02X722007Y479432I0J1502D01*
G01X722001Y479474D01*
X721956Y479544D01*
X721640Y479754D01*
X721559Y479769D01*
X721518Y479758D01*
G02X721092Y479708I-422J1753D01*
G02X720727Y479745I-2J1802D01*
G01X720686Y479753D01*
X720607Y479737D01*
X720301Y479526D01*
X720257Y479457D01*
X720251Y479416D01*
G02X718692Y478086I-1559J249D01*
G02X717636Y478490I-1J1579D01*
G03X717503Y478542I-135J-148D01*
G01X717380D01*
G03X717247Y478490I1J-200D01*
G02X716192Y478086I-1055J1176D01*
G02X715925Y478109I2J1579D01*
G03X715763Y478065I-33J-197D01*
G01X715666Y477984D01*
G03X715594Y477830I128J-154D01*
G01Y474424D01*
Y474414D01*
G03X715666Y474260I200J0D01*
G01X715763Y474178D01*
G03X715925Y474134I129J153D01*
G02X716192Y474156I263J-1556D01*
G02X717247Y473752I1J-1578D01*
G03X717381Y473701I133J149D01*
G01X717503D01*
G03X717637Y473752I1J200D01*
G02X718692Y474156I1054J-1174D01*
G02X720250Y472830I0J-1578D01*
G01X720257Y472789D01*
X720300Y472721D01*
X720606Y472510D01*
X720686Y472494D01*
X720726Y472502D01*
G02X721092Y472540I368J-1765D01*
G02X721518Y472488I-4J-1803D01*
G01X721559Y472478D01*
X721641Y472493D01*
X721956Y472703D01*
X722001Y472772D01*
X722008Y472814D01*
G02X723491Y474081I1483J-234D01*
G02Y471077I0J-1502D01*
G02X723224Y471101I0J1502D01*
G03X723058Y471055I-35J-197D01*
G01X722962Y470972D01*
G03X722893Y470813I131J-151D01*
G02X722894Y470737I-1801J-62D01*
G01Y467337D01*
G02X722893Y467259I-1802J-16D01*
G03X722962Y467099I200J-9D01*
G01X723058Y467016D01*
G03X723224Y466970I131J151D01*
G02X723491Y466994I267J-1478D01*
G02X724993Y465492I0J-1502D01*
G02X724212Y464174I-1503J0D01*
G01X724166Y464149D01*
X724111Y464062D01*
X724087Y463618D01*
X724132Y463525D01*
X724175Y463495D01*
G02X724817Y462264I-859J-1231D01*
G02X721813I-1502J0D01*
G02X722594Y463582I1503J0D01*
G01X722640Y463607D01*
X722695Y463694D01*
X722719Y464138D01*
X722674Y464231D01*
X722631Y464261D01*
G02X722007Y465259I860J1232D01*
G01X722001Y465301D01*
X721956Y465371D01*
X721640Y465581D01*
X721559Y465596D01*
X721518Y465585D01*
G02X721092Y465534I-426J1752D01*
G02X720727Y465572I3J1803D01*
G01X720686Y465580D01*
X720607Y465564D01*
X720301Y465353D01*
X720257Y465284D01*
X720251Y465243D01*
G02X718692Y463912I-1559J248D01*
G02Y467070I0J1579D01*
G02X718959Y467047I-2J-1579D01*
G03X719121Y467091I33J197D01*
G01X719218Y467173D01*
G03X719290Y467327I-128J154D01*
G01Y470737D01*
Y470743D01*
G03X719218Y470897I-200J0D01*
G01X719121Y470978D01*
G03X718959Y471022I-129J-153D01*
G02X718692Y471000I-263J1556D01*
G02X717637Y471404I-1J1578D01*
G03X717503Y471455I-133J-149D01*
G01X717381D01*
G03X717247Y471404I-1J-200D01*
G02X716192Y471000I-1054J1174D01*
G02X714633Y472330I0J1579D01*
G01X714627Y472371D01*
X714583Y472440D01*
X714277Y472651D01*
X714198Y472667D01*
X714157Y472659D01*
G02X713792Y472622I-363J1765D01*
G02X713427Y472659I-2J1802D01*
G01X713386Y472667D01*
X713307Y472651D01*
X713001Y472440D01*
X712957Y472371D01*
X712951Y472330D01*
G02X711392Y471000I-1559J249D01*
G02Y474156I0J1578D01*
G02X711659Y474134I4J-1578D01*
G03X711821Y474178I33J197D01*
G01X711918Y474260D01*
G03X711990Y474414I-128J154D01*
G01Y477824D01*
Y477830D01*
G03X711918Y477984I-200J0D01*
G01X711821Y478065D01*
G03X711659Y478109I-129J-153D01*
G02X711392Y478086I-269J1556D01*
G02Y481244I0J1579D01*
G02X712950Y479917I0J-1578D01*
G01X712957Y479876D01*
X713000Y479808D01*
X713306Y479597D01*
X713386Y479581D01*
X713426Y479589D01*
G02X713792Y479626I363J-1765D01*
G02X714158Y479589I3J-1802D01*
G01X714198Y479581D01*
X714278Y479597D01*
X714584Y479808D01*
X714627Y479876D01*
X714634Y479917D01*
G02X716192Y481244I1558J-251D01*
G02X717248Y480839I0J-1579D01*
G03X717381Y480787I135J148D01*
G01X717504D01*
G03X717637Y480839I-1J200D01*
G02X718692Y481242I1054J-1176D01*
G02X718959Y481220I4J-1578D01*
G03X719121Y481264I33J197D01*
G01X719218Y481346D01*
G03X719290Y481500I-128J154D01*
G01Y484910D01*
Y484916D01*
G03X719218Y485070I-200J0D01*
G01X719121Y485151D01*
G03X718959Y485195I-129J-153D01*
G02X718692Y485172I-269J1556D01*
G02X717637Y485577I1J1579D01*
G03X717503Y485628I-133J-149D01*
G01X717381D01*
G03X717247Y485577I-1J-200D01*
G02X716192Y485172I-1056J1174D01*
G02X714633Y486503I0J1579D01*
G01X714627Y486544D01*
X714583Y486613D01*
X714277Y486824D01*
X714198Y486840D01*
X714157Y486832D01*
G02X713792Y486794I-368J1765D01*
G02X713427Y486832I3J1803D01*
G01X713386Y486840D01*
X713307Y486824D01*
X713001Y486613D01*
X712957Y486544D01*
X712951Y486503D01*
G02X711392Y485172I-1559J248D01*
G02Y488330I0J1579D01*
G02X711659Y488307I-2J-1579D01*
G03X711821Y488351I33J197D01*
G01X711918Y488433D01*
G03X711990Y488587I-128J154D01*
G01Y491997D01*
Y492003D01*
G03X711918Y492157I-200J0D01*
G01X711821Y492238D01*
G03X711659Y492282I-129J-153D01*
G02X711392Y492260I-263J1556D01*
G02Y495416I0J1578D01*
G02X712950Y494090I0J-1578D01*
G01X712957Y494049D01*
X713000Y493981D01*
X713306Y493770D01*
X713386Y493754D01*
X713426Y493762D01*
G02X713792Y493800I368J-1765D01*
G02X714158Y493762I-2J-1803D01*
G01X714198Y493754D01*
X714278Y493770D01*
G37*
G36*
G01X785820Y1427495D02*
G02Y1424491I0J-1502D01*
G02X785414Y1424547I0J1502D01*
G01X785413D01*
X785375Y1424558D01*
X785297Y1424548D01*
X784978Y1424367D01*
X784930Y1424304D01*
X784920Y1424266D01*
G02X783469Y1423153I-1451J389D01*
G02Y1426157I0J1502D01*
G02X783875Y1426101I0J-1502D01*
G01X783876D01*
X783914Y1426090D01*
X783992Y1426100D01*
X784311Y1426281D01*
X784359Y1426344D01*
X784369Y1426382D01*
G02X785820Y1427495I1451J-389D01*
G37*
G36*
G01X793841Y1416621D02*
G02X793794Y1416993I1455J373D01*
G01Y1416995D01*
G02X795296Y1415493I1502J0D01*
G01X795294D01*
G02X794817Y1415571I1J1502D01*
G03X794303Y1415092I-127J-379D01*
G02X794350Y1414720I-1455J-373D01*
G01Y1414718D01*
G02X792848Y1416220I-1502J0D01*
G01X792850D01*
G02X793327Y1416142I-1J-1502D01*
G03X793841Y1416621I127J379D01*
G37*
G36*
G01X787694Y1441247D02*
G02Y1444251I0J1502D01*
G02X789191Y1442871I0J-1502D01*
G01Y1442870D01*
G03X789310Y1442704I199J17D01*
G01X789631Y1442562D01*
G03X789834Y1442586I81J183D01*
G01X789835Y1442587D01*
G02X790754Y1442901I919J-1188D01*
G02X792009Y1442225I0J-1503D01*
G01Y1442223D01*
G03X792182Y1442134I167J111D01*
G01X792575Y1442146D01*
X792665Y1442200D01*
X792690Y1442245D01*
G02X793994Y1443001I1304J-747D01*
G02Y1439997I0J-1502D01*
G02X792739Y1440673I0J1503D01*
G01Y1440675D01*
G03X792566Y1440764I-167J-111D01*
G01X792173Y1440752D01*
X792083Y1440698D01*
X792058Y1440653D01*
G02X790754Y1439897I-1304J747D01*
G02X789257Y1441277I0J1502D01*
G01Y1441278D01*
G03X789138Y1441444I-199J-17D01*
G01X788817Y1441586D01*
G03X788614Y1441562I-81J-183D01*
G01X788613Y1441561D01*
G02X787694Y1441247I-919J1188D01*
G37*
G36*
G01X795816Y1471242D02*
G02X798820I1502J0D01*
G02X797922Y1469867I-1502J0D01*
G01X797870Y1469844D01*
X797807Y1469754D01*
X797775Y1469289D01*
X797825Y1469190D01*
X797873Y1469161D01*
G02X798585Y1467883I-791J-1278D01*
G02X797083Y1466381I-1502J0D01*
G02X795717Y1467258I0J1502D01*
G01X795694Y1467309D01*
X795602Y1467372D01*
X795137Y1467397D01*
X795040Y1467346D01*
X795011Y1467298D01*
G02X793723Y1466569I-1288J773D01*
G02Y1469573I0J1502D01*
G02X795089Y1468696I0J-1502D01*
G01X795112Y1468645D01*
X795204Y1468582D01*
X795669Y1468557D01*
X795766Y1468608D01*
X795795Y1468656D01*
G02X796479Y1469258I1288J-773D01*
G01X796531Y1469281D01*
X796594Y1469371D01*
X796626Y1469836D01*
X796576Y1469935D01*
X796528Y1469964D01*
G02X795816Y1471242I791J1278D01*
G37*
G54D47*
X241850Y678462D03*
X191125Y614400D03*
X147925Y615600D03*
X147893Y607588D03*
X248984Y638125D03*
X246102Y656321D03*
X246583Y665140D03*
X250102Y656321D03*
X247278Y618288D03*
X157090Y562003D03*
X157375Y555234D03*
X212460Y560500D03*
X223500Y568000D03*
X240194Y643113D03*
X240249Y628328D03*
X810453Y453330D03*
X802136Y452334D03*
X824650Y455034D03*
X749402Y493839D03*
X741602D03*
X731433Y489435D03*
X723491Y493839D03*
X731249Y495088D03*
X772165Y314890D03*
X776943Y321649D03*
X772990Y336324D03*
X772162Y332584D03*
X778502Y348015D03*
X772859Y347937D03*
X756086Y386500D03*
X766344Y393924D03*
Y389912D03*
Y385912D03*
X755086Y391496D03*
X735599Y449961D03*
X741602Y465492D03*
X749444Y393858D03*
X749586Y403307D03*
X753086Y403500D03*
X751086Y398583D03*
X722097Y446595D03*
Y410394D03*
Y403307D03*
X723440Y398583D03*
X723491Y458406D03*
X717105Y410964D03*
X717420Y404334D03*
X709781Y442956D03*
X720996Y442856D03*
X711598Y438323D03*
X711764Y449873D03*
X719051Y458455D03*
X719612Y451108D03*
X710643Y456335D03*
X706211Y465874D03*
X685353Y412718D03*
Y408718D03*
Y400718D03*
Y404718D03*
X731433Y482666D03*
Y475262D03*
X741072Y478958D03*
X741602Y486752D03*
X749402Y479665D03*
Y486752D03*
Y472579D03*
X793459Y1429165D03*
X789647Y1427518D03*
X799314Y1475693D03*
X778685Y1416198D03*
X777114Y1442270D03*
X777725Y1450193D03*
X790989Y1455695D03*
X790361Y1447895D03*
X786591Y1452803D03*
X790296Y1463459D03*
X794005Y1464178D03*
X787038Y1460533D03*
X783620Y1460108D03*
X800607Y1440760D03*
X836704Y1448849D03*
Y1440849D03*
X836744Y1444849D03*
X845306Y1438269D03*
X846044Y1451459D03*
X850544Y1447559D03*
X889244Y1444859D03*
X892244Y1449636D03*
Y1440859D03*
X881244Y1456859D03*
X889336Y1452554D03*
X788648Y1422044D03*
X786787Y1433800D03*
X777260Y1446237D03*
X780162Y1412848D03*
X944238Y360828D03*
G54D56*
X723927Y421555D03*
G54D54*
X713162Y434493D03*
X758038Y381143D03*
G54D60*
X820079Y388583D03*
X1020866D03*
%LPD*%
G75*
G36*
G01X713801Y434493D02*
G03I-639J0D01*
G37*
G36*
G01X716769Y472578D02*
G03I-577J0D01*
G37*
G36*
G01X711969D02*
G03I-577J0D01*
G37*
G36*
G01X716769Y479665D02*
G03I-577J0D01*
G37*
G36*
G01X711969D02*
G03I-577J0D01*
G37*
G36*
G01Y486751D02*
G03I-577J0D01*
G37*
G36*
G01X716769D02*
G03I-577J0D01*
G37*
G36*
G01X711969Y493838D02*
G03I-577J0D01*
G37*
G36*
G01X716769D02*
G03I-577J0D01*
G37*
G36*
G01X719269Y472578D02*
G03I-577J0D01*
G37*
G36*
G01Y465491D02*
G03I-577J0D01*
G37*
G36*
G01Y479664D02*
G03I-577J0D01*
G37*
G36*
G01Y486751D02*
G03I-577J0D01*
G37*
G36*
G01X758677Y381143D02*
G03I-639J0D01*
G37*
G36*
G01X759020Y395391D02*
G03I-639J0D01*
G37*
G36*
G01X781153Y471484D02*
G03I-577J0D01*
G37*
G36*
G01X776162Y466528D02*
G03I-577J0D01*
G37*
G36*
G01X781153D02*
G03I-577J0D01*
G37*
G36*
G01X776161Y471484D02*
G03I-577J0D01*
G37*
G36*
G01X781153Y480701D02*
G03I-577J0D01*
G37*
G36*
G01X776161D02*
G03I-577J0D01*
G37*
G36*
G01Y485657D02*
G03I-577J0D01*
G37*
G36*
G01X781153D02*
G03I-577J0D01*
G37*
G36*
G01X786563Y473640D02*
G03I-577J0D01*
G37*
G36*
G01X791555D02*
G03I-577J0D01*
G37*
G36*
G01X786563Y487813D02*
G03I-577J0D01*
G37*
G36*
G01X791555D02*
G03I-577J0D01*
G37*
G36*
G01X786563Y478596D02*
G03I-577J0D01*
G37*
G36*
G01X791555D02*
G03I-577J0D01*
G37*
G36*
G01X786563Y492769D02*
G03I-577J0D01*
G37*
G36*
G01X791555D02*
G03I-577J0D01*
G37*
G54D10*
G01X163191Y1065313D02*
Y1063961D01*
X161278Y1062048D01*
X144878D01*
X125925Y1043095D01*
X99725D01*
X88392Y1054428D01*
Y1085018D01*
X77734Y1095676D01*
G01X71006Y1228684D02*
X79573D01*
X93113Y1215144D01*
X97025Y1205699D01*
Y1092158D01*
X99025Y1090158D01*
X124309D01*
X145701Y1068766D01*
X163973D01*
X166188Y1066551D01*
G01X86367Y848086D02*
X110873D01*
X242979Y793366D01*
X354034D01*
X375126Y772274D01*
X385259D01*
X396968Y760565D01*
Y743901D01*
X405150Y735719D01*
X487867D01*
X518042Y765894D01*
X523747D01*
X534781Y754860D01*
X550319D01*
X556624Y761165D01*
X566382D01*
X568859Y758688D01*
X582595D01*
X611343Y787436D01*
X704944D01*
X708547Y783833D01*
Y772950D01*
X726712Y754785D01*
X778242D01*
X783046Y749981D01*
X817428D01*
X818458Y748951D01*
X822699D01*
X827315Y753567D01*
Y757685D01*
X824500Y760500D01*
G01X97609Y1018469D02*
X100071Y1020931D01*
X112179D01*
X116818Y1025570D01*
X122892D01*
X134307Y1036985D01*
Y1046375D01*
X147165Y1059233D01*
X177139D01*
X206316Y1030056D01*
X388443D01*
X438719Y979780D01*
X481888D01*
X485611Y979763D01*
X493055D01*
X496471Y976347D01*
X532247D01*
X540193Y984293D01*
Y1006674D01*
X543641Y1010122D01*
X546349D01*
X554696Y1018469D01*
G01X552238Y959102D02*
X561336Y968200D01*
X591007D01*
X592280Y969473D01*
X680673D01*
X706605Y995405D01*
X743694D01*
X748874Y990225D01*
X863925D01*
X871031Y997331D01*
X911951D01*
X916034Y1001414D01*
X985867D01*
X1000237Y1015784D01*
X1001430Y1016278D01*
X1003485D01*
X1004056Y1015707D01*
X1007946D01*
X1008830Y1016591D01*
X1011782D01*
G01X865830Y961600D02*
X864566Y960336D01*
X824069D01*
X818327Y966078D01*
X704032D01*
X673961Y936007D01*
X591403D01*
G01X1170465Y677836D02*
Y682320D01*
X1167697Y685088D01*
X1153193D01*
X1125680Y657575D01*
X1113703D01*
X1102981Y646853D01*
X1089013D01*
X1073069Y630909D01*
X1051855D01*
X1022072Y660692D01*
X906361D01*
X900382Y666671D01*
X892461D01*
G01X1059649Y622870D02*
X1047915D01*
X1015188Y655597D01*
X902081D01*
X900753Y656925D01*
G01X979498Y907500D02*
Y906433D01*
X967693Y894628D01*
X935428D01*
X933500Y892700D01*
Y891400D01*
X932300Y890200D01*
X3704Y5374D03*
X3017Y24773D03*
Y44773D03*
Y64773D03*
Y84773D03*
Y104773D03*
Y124773D03*
Y144773D03*
Y164773D03*
Y184773D03*
Y204773D03*
Y224773D03*
Y244773D03*
Y264773D03*
Y284773D03*
Y304773D03*
X3221Y324773D03*
X3035Y978036D03*
Y998036D03*
Y1018036D03*
Y1038036D03*
Y1058036D03*
Y1078036D03*
Y1098036D03*
Y1118036D03*
Y1138036D03*
Y1158036D03*
Y1178036D03*
Y1198036D03*
Y1238036D03*
Y1258036D03*
Y1278036D03*
Y1298036D03*
Y1318036D03*
Y1338036D03*
Y1358036D03*
Y1378036D03*
Y1398036D03*
Y1418036D03*
Y1438036D03*
Y1458036D03*
Y1478036D03*
Y1498036D03*
Y1538036D03*
Y1558036D03*
Y1578036D03*
X3017Y1639466D03*
X15972Y3000D03*
X20408Y51296D03*
Y55296D03*
X14751Y62381D03*
X12601Y92110D03*
X9364Y107501D03*
X16728Y107910D03*
X12652Y116894D03*
X9057Y138939D03*
X19184Y144728D03*
X15184D03*
X13615Y153263D03*
X10966Y155873D03*
Y152873D03*
X12709Y175777D03*
X15139Y198883D03*
X15520Y195176D03*
X18320D03*
X13020D03*
X10520D03*
X15139Y201683D03*
X12880Y203393D03*
X10380D03*
X19068Y206838D03*
X16568D03*
X18564Y238589D03*
X9745Y245784D03*
X19075Y278429D03*
X7036Y268371D03*
X10971Y333342D03*
X17964Y349298D03*
Y369298D03*
Y389298D03*
Y409298D03*
Y429298D03*
Y449298D03*
Y469298D03*
Y489298D03*
Y509298D03*
Y529298D03*
Y549298D03*
Y569298D03*
Y589298D03*
Y609298D03*
Y629298D03*
Y649298D03*
Y669298D03*
Y689298D03*
Y709298D03*
Y729298D03*
Y749298D03*
Y769298D03*
Y789298D03*
Y809298D03*
Y829298D03*
Y849298D03*
Y869298D03*
Y889298D03*
Y909298D03*
Y929298D03*
X9554Y961954D03*
X17964Y949298D03*
X6161Y1075991D03*
X6108Y1070611D03*
Y1065318D03*
X6059Y1091964D03*
X6055Y1086546D03*
X6053Y1081305D03*
X14252Y1121333D03*
X11552D03*
X16752D03*
X8952D03*
X14152Y1111633D03*
X11452D03*
X8852D03*
X16652D03*
X14252Y1130333D03*
X16752D03*
X14306Y1138705D03*
X16806D03*
X20079Y1429347D03*
X13606Y1476707D03*
X6690Y1496782D03*
X19365Y1494298D03*
X8042Y1522199D03*
X12327Y1519202D03*
X7922Y1532494D03*
X11995Y1535134D03*
X6567Y1554215D03*
X14375Y1553121D03*
X18409Y1554202D03*
X12000Y1644980D03*
X26956Y4469D03*
X28317Y24773D03*
Y44773D03*
X24316Y67527D03*
Y63527D03*
Y59527D03*
X35638Y53597D03*
X33288Y109410D03*
Y116497D03*
X30788D03*
X25988D03*
X22439Y106495D03*
X30788Y123584D03*
X33288Y123583D03*
X25988Y123584D03*
X33288Y130670D03*
X30788D03*
X25988D03*
X30788Y137757D03*
X25988D03*
X23184Y144728D03*
X29201Y151651D03*
X26201D03*
X20709Y175777D03*
X34520Y213539D03*
X36201Y238714D03*
X21530Y236121D03*
X27966Y238689D03*
X28740Y247292D03*
X21449Y253198D03*
X28740Y267292D03*
X21386Y273198D03*
X23479Y295619D03*
X35650Y487982D03*
Y478982D03*
Y483982D03*
Y499982D03*
X25819Y531726D03*
Y536726D03*
Y552726D03*
Y540726D03*
X32452Y581222D03*
X29652D03*
X35252D03*
Y591215D03*
X29652D03*
X32452D03*
X34254Y611091D03*
X29451Y633560D03*
X36692Y641817D03*
X30369Y663048D03*
X27625Y663094D03*
X25818Y682139D03*
X27854Y671553D03*
X30414Y671508D03*
X28818Y682139D03*
X34565Y699082D03*
X26596Y874520D03*
X26844Y920354D03*
X24132Y958151D03*
X25371Y980696D03*
X27934Y1204311D03*
X30934D03*
X30410Y1218497D03*
Y1220997D03*
X27934Y1215511D03*
X30934D03*
X34314Y1215403D03*
X27934Y1212711D03*
Y1209911D03*
Y1207111D03*
X30934Y1212711D03*
Y1209911D03*
Y1207111D03*
X30410Y1234797D03*
Y1232297D03*
Y1227897D03*
Y1225397D03*
Y1241697D03*
Y1239197D03*
X22284Y1464612D03*
X21544Y1479662D03*
X33536Y1467485D03*
X21544Y1489648D03*
X25674Y1486291D03*
X32195Y1511279D03*
X32079Y1525641D03*
Y1521641D03*
Y1517641D03*
X35237Y1532096D03*
X31237D03*
X35850Y1556096D03*
X32000Y1644980D03*
X46450Y82984D03*
Y77784D03*
Y75184D03*
Y80384D03*
X48364Y92473D03*
X46450Y85584D03*
X37988Y109410D03*
X46240D03*
X45988Y102323D03*
X46240Y116496D03*
X37988Y102323D03*
Y116496D03*
X46931Y130670D03*
X49236Y121658D03*
X37988Y130670D03*
Y123583D03*
X46932Y137756D03*
X52437D03*
X37988D03*
X45984Y163264D03*
X37284Y285272D03*
X42690Y451466D03*
X48596Y458466D03*
X39643Y555194D03*
X36843D03*
X49839Y546830D03*
X39643Y563194D03*
X36843D03*
X39643Y571194D03*
X36843D03*
X42192Y641817D03*
X51449Y822718D03*
X47949D03*
X49265Y886660D03*
X52922Y900295D03*
X48429Y916430D03*
X47916Y947622D03*
X50366Y1082388D03*
X38200Y1089721D03*
X38216Y1093757D03*
X46166D03*
X44960Y1190619D03*
X49500Y1199066D03*
X49638Y1203884D03*
X51197Y1218206D03*
X39452Y1250932D03*
X40996Y1467703D03*
X44195Y1511279D03*
X48195D03*
X40195D03*
X48079Y1525641D03*
Y1529641D03*
Y1521641D03*
X39237Y1532096D03*
X52048Y1556062D03*
X52000Y1644980D03*
X55638Y53597D03*
X56098Y109410D03*
Y116496D03*
X55964Y103037D03*
X64098Y102323D03*
Y109410D03*
Y116496D03*
X66856Y104249D03*
Y107649D03*
X56098Y123583D03*
Y130670D03*
X64098Y123583D03*
Y130670D03*
Y137756D03*
X65189Y228961D03*
Y231461D03*
Y223661D03*
Y226461D03*
X68896Y226141D03*
X54733Y231226D03*
Y228726D03*
Y223726D03*
Y226226D03*
X69139Y236611D03*
X68841Y248891D03*
X58279Y293796D03*
X66293Y285690D03*
X68793D03*
X66293Y288190D03*
X68793D03*
X60779Y293796D03*
X65759Y437508D03*
X61759D03*
X57759D03*
X54936Y449352D03*
X59522Y448874D03*
X68619Y447269D03*
X68497Y450201D03*
X66224Y473045D03*
X58224D03*
X53643Y472905D03*
X66371Y482134D03*
Y484634D03*
X59670Y500086D03*
X64550Y504699D03*
X62050D03*
X59550D03*
X68236Y519458D03*
X61752Y516979D03*
X64252D03*
X59252D03*
X60233Y521804D03*
X68202Y522129D03*
X64495Y527449D03*
X60233Y524304D03*
X56540Y531378D03*
Y528878D03*
X61695Y527449D03*
X68202Y527129D03*
Y524629D03*
Y529629D03*
X67622Y572842D03*
X64408Y572975D03*
X62789Y608311D03*
X66510Y628242D03*
X55318Y629362D03*
X53129Y627948D03*
X55307Y688473D03*
X60849Y826818D03*
X64649D03*
X58949Y821018D03*
X56049Y827218D03*
X64849Y840418D03*
X60249D03*
X66342Y880067D03*
X67316Y865869D03*
X64175Y897500D03*
X67461Y912983D03*
X63303Y912835D03*
X57178Y981386D03*
X55049Y1082343D03*
X62109Y1087656D03*
X58981Y1105100D03*
X56381D03*
X61581D03*
X64281D03*
X61681Y1114800D03*
X56481D03*
X59081D03*
X64381D03*
X57218Y1123867D03*
X55397Y1133688D03*
X57897D03*
X58250Y1220896D03*
X65940Y1209382D03*
X58250Y1227796D03*
Y1230296D03*
Y1237196D03*
Y1234696D03*
Y1223396D03*
X57185Y1480808D03*
X57144Y1491047D03*
X56114Y1556061D03*
X68743Y1583498D03*
X60554Y1612002D03*
X66291Y1633801D03*
X74432Y5374D03*
X73745Y24773D03*
Y44773D03*
X73381Y94017D03*
X69381D03*
X73110Y101701D03*
X73509Y110445D03*
X78501D03*
X73509Y115401D03*
X78501D03*
X83911Y117557D03*
X80660Y103783D03*
X73509Y129574D03*
Y124618D03*
X78501Y129574D03*
Y124618D03*
X83911Y122513D03*
Y131731D03*
Y136687D03*
X71422Y151540D03*
X75072Y191941D03*
X81572Y184619D03*
X74939Y188727D03*
X83552Y206760D03*
X73158Y229286D03*
X76851Y222212D03*
X71696Y226141D03*
X76851Y224712D03*
X74139Y236611D03*
X71639D03*
X73158Y231786D03*
X71341Y248891D03*
X73841D03*
X76766Y256535D03*
X84766D03*
X71593Y285690D03*
Y288190D03*
X75819Y290755D03*
X79819D03*
X83819D03*
X71826Y480705D03*
X74326D03*
X69816Y475946D03*
Y478446D03*
X78033Y478586D03*
Y481086D03*
Y476086D03*
Y483586D03*
X75736Y519458D03*
X73236D03*
X70736D03*
X71995Y532749D03*
X74795D03*
X75777Y585507D03*
X71184D03*
X71730Y579475D03*
X71228Y590145D03*
X75822Y590190D03*
X75684Y605443D03*
X83684D03*
X81740Y636250D03*
X69670Y633205D03*
Y636005D03*
X81740Y633450D03*
X69670Y638805D03*
X81740Y639050D03*
X78129Y656900D03*
X72314Y680207D03*
Y683407D03*
X82714Y674707D03*
X74414Y681907D03*
X72549Y838818D03*
X71928Y873683D03*
X84367Y878286D03*
X76528Y878533D03*
X72035Y898346D03*
X80339Y897943D03*
X70059Y1075656D03*
X70302Y1067656D03*
X77734Y1095676D03*
X71006Y1228684D03*
X87000Y1597855D03*
X76005Y1580680D03*
X82433Y1580590D03*
X74291Y1633801D03*
X72000Y1644980D03*
X93334Y3000D03*
X88080Y103603D03*
X88903Y117557D03*
Y122513D03*
Y131731D03*
X87002Y146461D03*
X88903Y136687D03*
X85904Y152367D03*
X87604Y180572D03*
X92287Y180527D03*
X96010Y192421D03*
X92242Y185121D03*
X87604Y185165D03*
X85796Y279208D03*
X89900Y281307D03*
X94390Y293645D03*
Y290845D03*
Y288345D03*
X91890Y293645D03*
Y290845D03*
Y288345D03*
X95943Y377953D03*
X90257Y445506D03*
X93456Y649838D03*
X89432Y668293D03*
X92134D03*
X85614Y674707D03*
X87714Y684607D03*
X88875Y840940D03*
X86367Y848086D03*
X100058Y977651D03*
X99836Y980330D03*
X94586Y1023900D03*
X97609Y1018469D03*
X90450Y1033542D03*
X86291Y1633801D03*
X92000Y1644980D03*
X113334Y3000D03*
X119582Y102249D03*
X107364Y113394D03*
Y110394D03*
X111582Y102249D03*
X110013Y110784D03*
X115582Y102249D03*
X110152Y130898D03*
X117607Y133298D03*
X111754Y134579D03*
X107540Y172665D03*
Y180665D03*
X117501Y198883D03*
X115382Y195176D03*
X112882D03*
X117882D03*
X117501Y201683D03*
X115242Y203393D03*
X112742D03*
X107572Y200864D03*
Y212864D03*
Y216864D03*
Y221864D03*
X109329Y252371D03*
X112474Y716315D03*
X111993Y710102D03*
X114397Y727974D03*
X120250Y758841D03*
X113601Y881266D03*
X103972Y977609D03*
X103836Y980330D03*
X107669Y1456451D03*
Y1465913D03*
X116330Y1465513D03*
X107669Y1461182D03*
X116330Y1460782D03*
X107669Y1481267D03*
X116330Y1480867D03*
X107669Y1476536D03*
X116330Y1476136D03*
Y1470244D03*
X107669Y1471805D03*
X116330Y1491490D03*
Y1485598D03*
X107669Y1487159D03*
Y1496621D03*
X116330Y1496221D03*
X107669Y1491890D03*
X116330Y1506845D03*
Y1500952D03*
X107669Y1502514D03*
X116330Y1511576D03*
X107669Y1511976D03*
Y1507245D03*
X116330Y1516307D03*
X107669Y1563544D03*
X116330Y1563144D03*
X107669Y1558813D03*
Y1568275D03*
X116330Y1567875D03*
X107669Y1578898D03*
X116330Y1578498D03*
Y1572606D03*
X107669Y1574167D03*
Y1583629D03*
X116330Y1583229D03*
X107669Y1594253D03*
X116330Y1593853D03*
Y1587960D03*
X107669Y1589522D03*
Y1609607D03*
X116330Y1609207D03*
X107669Y1598984D03*
X116330Y1598584D03*
Y1603315D03*
X107669Y1604876D03*
X116330Y1613938D03*
Y1618669D03*
X107669Y1614338D03*
X112000Y1644980D03*
X129318Y4469D03*
X130679Y24773D03*
Y44773D03*
X128350Y116497D03*
X133150D03*
X124606Y106495D03*
X125599Y109172D03*
X122599D03*
X133150Y123584D03*
X128350D03*
X133150Y130670D03*
X128350D03*
Y137757D03*
X133150D03*
X126246Y141228D03*
X124340Y146012D03*
X129134Y150847D03*
X120682Y195176D03*
X118930Y206838D03*
X121430D03*
X131102Y247292D03*
X130328Y238689D03*
X123892Y236121D03*
X120926Y238589D03*
X123811Y253198D03*
X125125Y362403D03*
X118122Y747565D03*
X119099Y755052D03*
X122437Y860775D03*
X125698Y857515D03*
X129666Y857514D03*
X122887Y884000D03*
X127067Y891495D03*
X124880Y1117691D03*
X130380D03*
X124880Y1130291D03*
X124992Y1465913D03*
Y1456451D03*
Y1461182D03*
X133653Y1465513D03*
Y1460782D03*
X124992Y1471805D03*
Y1476536D03*
Y1481267D03*
X133653Y1476136D03*
Y1470244D03*
Y1480867D03*
Y1496221D03*
X124992Y1487159D03*
Y1491890D03*
Y1496621D03*
X133653Y1491490D03*
Y1485598D03*
Y1506845D03*
Y1500952D03*
Y1511576D03*
X124992Y1511976D03*
Y1507245D03*
Y1502514D03*
X133653Y1516307D03*
X124992Y1558813D03*
Y1563544D03*
X133653Y1563144D03*
Y1567875D03*
X124992Y1574167D03*
Y1578898D03*
X133653Y1578498D03*
Y1572606D03*
X124992Y1568275D03*
Y1589522D03*
Y1594253D03*
X133653Y1593853D03*
Y1587960D03*
X124992Y1583629D03*
X133653Y1583229D03*
X124992Y1609607D03*
Y1604876D03*
Y1598984D03*
X133653Y1609207D03*
Y1598584D03*
Y1603315D03*
X124992Y1614338D03*
X133653Y1613938D03*
Y1618669D03*
X132000Y1644980D03*
X138000Y53597D03*
X148812Y80384D03*
Y82984D03*
Y75184D03*
Y77784D03*
Y85584D03*
X135650Y109410D03*
X148602D03*
Y116496D03*
X148350Y102323D03*
X140350Y116496D03*
Y109410D03*
Y102323D03*
X135650Y116497D03*
X148774Y124576D03*
X149827Y130670D03*
X135650Y123583D03*
Y130670D03*
X140350D03*
Y123583D03*
X149822Y137756D03*
X140350D03*
X136882Y213539D03*
X138563Y238714D03*
X146196Y390223D03*
X143186Y402291D03*
X138194Y397335D03*
X143186D03*
X146196Y395179D03*
Y404396D03*
Y409352D03*
X138194Y402291D03*
X140786Y416465D03*
Y411509D03*
X135794Y416465D03*
Y411509D03*
X146196Y418569D03*
Y423525D03*
X140786Y425682D03*
X135794D03*
X140786Y430638D03*
X135794D03*
X146196Y432743D03*
Y437699D03*
X140786Y439855D03*
X135794D03*
X140786Y444811D03*
X135794D03*
X136604Y450750D03*
X135794Y468609D03*
X140786D03*
X135794Y473565D03*
X140786D03*
X146196Y489895D03*
X135794Y487738D03*
X140786D03*
X146196Y480677D03*
Y475721D03*
X135794Y482782D03*
X140786D03*
X146196Y494851D03*
X135794Y512743D03*
X140786D03*
X135794Y517699D03*
X140786D03*
X146196Y519855D03*
X135794Y526916D03*
X140786Y531872D03*
X135794D03*
X146196Y524811D03*
Y538984D03*
Y534028D03*
X140786Y526916D03*
X140703Y536382D03*
X147925Y603600D03*
Y619600D03*
Y623600D03*
X142315Y1456451D03*
Y1461182D03*
Y1465913D03*
Y1471805D03*
Y1476536D03*
Y1481267D03*
Y1487159D03*
Y1491890D03*
Y1496621D03*
Y1507245D03*
Y1502514D03*
Y1511976D03*
Y1558813D03*
Y1563544D03*
Y1574167D03*
Y1578898D03*
Y1568275D03*
Y1589522D03*
Y1594253D03*
Y1583629D03*
Y1609607D03*
Y1604876D03*
Y1598984D03*
Y1614338D03*
X158000Y53597D03*
X151366Y92849D03*
X158460Y116496D03*
X158326Y103037D03*
X158460Y109410D03*
X166460Y116496D03*
Y109410D03*
Y102323D03*
X158460Y130670D03*
Y123583D03*
X166460D03*
Y130670D03*
X155051Y137756D03*
X166460D03*
X157095Y228726D03*
Y231226D03*
X167551Y223661D03*
X157095Y226226D03*
Y223726D03*
X163141Y293796D03*
X160641D03*
X166528Y312392D03*
X151188Y390223D03*
Y395179D03*
Y404396D03*
Y409352D03*
Y423525D03*
Y418569D03*
Y432743D03*
Y437699D03*
Y489895D03*
Y480677D03*
Y475721D03*
Y494851D03*
Y519855D03*
Y538984D03*
Y534028D03*
Y524811D03*
X152386Y634946D03*
X160733Y1056594D03*
X160627Y1053561D03*
X166188Y1066551D03*
X163191Y1065313D03*
X159637Y1461182D03*
X150976Y1465513D03*
Y1460782D03*
X159637Y1465913D03*
Y1456451D03*
X150976Y1476136D03*
Y1470244D03*
Y1480867D03*
X159637Y1471805D03*
Y1476536D03*
Y1481267D03*
Y1496621D03*
X150976Y1491490D03*
Y1485598D03*
Y1496221D03*
X159637Y1487159D03*
Y1491890D03*
X150976Y1500952D03*
Y1511576D03*
X159637Y1507245D03*
Y1502514D03*
Y1511976D03*
X150976Y1506845D03*
Y1516307D03*
X159637Y1558813D03*
Y1563544D03*
X150976Y1563144D03*
X159637Y1578898D03*
X150976Y1567875D03*
Y1578498D03*
Y1572606D03*
X159637Y1568275D03*
Y1574167D03*
X150976Y1583229D03*
Y1593853D03*
Y1587960D03*
X159637Y1583629D03*
Y1589522D03*
Y1594253D03*
X150976Y1609207D03*
Y1598584D03*
Y1603315D03*
X159637Y1609607D03*
Y1604876D03*
Y1598984D03*
X150976Y1613938D03*
Y1618669D03*
X159637Y1614338D03*
X152000Y1644980D03*
X176794Y5374D03*
X176107Y24773D03*
Y44773D03*
X179743Y94017D03*
X175743D03*
X171743D03*
X175472Y101701D03*
X175871Y110445D03*
X180863Y115401D03*
X175871D03*
X169218Y107649D03*
Y104249D03*
X180863Y129574D03*
Y124618D03*
X175871Y129574D03*
Y124618D03*
X173784Y151540D03*
X177434Y191941D03*
X177301Y188727D03*
X175520Y229286D03*
X179213Y224712D03*
Y222212D03*
X171258Y226141D03*
X167551Y231461D03*
Y228961D03*
Y226461D03*
X174058Y226141D03*
X174001Y236611D03*
X176501D03*
X175520Y231786D03*
X171501Y236611D03*
X176203Y248891D03*
X173703D03*
X171203D03*
X179128Y256535D03*
X173955Y285690D03*
Y288190D03*
X171155Y285690D03*
X168655Y288190D03*
X171155D03*
X168655Y285690D03*
X182181Y290755D03*
X178181D03*
X177369Y389154D03*
Y396240D03*
Y403327D03*
Y410413D03*
Y417500D03*
Y424587D03*
Y431673D03*
Y438760D03*
Y445847D03*
Y467539D03*
Y474626D03*
Y488799D03*
Y481713D03*
Y495886D03*
Y511673D03*
Y518760D03*
Y525847D03*
Y532933D03*
Y540020D03*
Y547106D03*
X175615Y550907D03*
X173115D03*
X175615Y553407D03*
X173115D03*
X176650Y602197D03*
X177114Y595108D03*
X168299Y1465513D03*
Y1460782D03*
X176960Y1465914D03*
Y1456452D03*
Y1461183D03*
X168299Y1476136D03*
Y1470244D03*
Y1480867D03*
Y1491490D03*
Y1485598D03*
Y1496221D03*
X176960Y1491891D03*
Y1487160D03*
Y1496622D03*
Y1507246D03*
Y1502515D03*
X168299Y1506845D03*
Y1500952D03*
Y1511576D03*
X176960Y1511977D03*
X168299Y1516307D03*
Y1563144D03*
X176960Y1563544D03*
Y1558813D03*
Y1568275D03*
X168299Y1578498D03*
Y1572606D03*
Y1567875D03*
Y1583229D03*
X176960Y1583629D03*
X168299Y1593853D03*
Y1587960D03*
X176960Y1594253D03*
Y1589522D03*
X168299Y1609207D03*
Y1598584D03*
Y1603315D03*
X176960Y1609607D03*
Y1598984D03*
Y1604876D03*
X168299Y1613938D03*
Y1618669D03*
X176960Y1614338D03*
X172000Y1644980D03*
X195697Y3000D03*
X188820Y80140D03*
Y84140D03*
Y76140D03*
X183752Y94017D03*
X186273Y117557D03*
X191265D03*
X183022Y103783D03*
X194189Y103621D03*
X186273Y131731D03*
Y122513D03*
X191265D03*
Y131731D03*
X189364Y146461D03*
X186273Y136687D03*
X191265D03*
X188266Y152367D03*
X194649Y180527D03*
X189966Y180572D03*
X198372Y192421D03*
X189966Y185165D03*
X194604Y185121D03*
X183934Y184619D03*
X185914Y206760D03*
X187128Y256535D03*
X188158Y279208D03*
X192262Y281307D03*
X196752Y293645D03*
Y290845D03*
Y288345D03*
X194252Y293645D03*
Y290845D03*
Y288345D03*
X186181Y290755D03*
X191988Y389154D03*
X185169D03*
Y396240D03*
X186448Y404911D03*
X190518Y396240D03*
X194603Y422864D03*
X186589Y426299D03*
X185402Y412571D03*
X195295Y414823D03*
X194673Y429832D03*
X194278Y436447D03*
X186900Y445847D03*
X196313Y447953D03*
X185169Y467539D03*
X195480D03*
X185169Y474626D03*
X194222Y472772D03*
X194956Y487711D03*
X195069Y479104D03*
X185430Y480828D03*
X187380Y498834D03*
X195480Y495886D03*
X190829Y516841D03*
X194080Y510565D03*
X185169Y518760D03*
Y511673D03*
Y525847D03*
X185776Y550123D03*
X187408Y572334D03*
X185640Y574102D03*
X191125Y602400D03*
Y598400D03*
Y594400D03*
Y606400D03*
Y610400D03*
X193723Y656942D03*
X192000Y1644980D03*
X211262Y60922D03*
X206398Y55513D03*
X208463Y96472D03*
X203591Y91951D03*
X202195Y117261D03*
X209726Y113394D03*
Y110394D03*
X213944Y102249D03*
X212375Y110784D03*
X211969Y133298D03*
X214116Y134579D03*
X209902Y172665D03*
Y180665D03*
X215244Y195176D03*
X209934Y200864D03*
X215104Y203393D03*
X209934Y212864D03*
Y216864D03*
Y221864D03*
X211691Y252371D03*
X215380Y389153D03*
X210580D03*
X203280Y389154D03*
X215380Y396240D03*
X208080Y403327D03*
X215380Y403326D03*
X210580D03*
X208080Y410413D03*
X210580D03*
X215380D03*
X203280Y396240D03*
Y403327D03*
Y410413D03*
X208080Y396240D03*
X210580D03*
X208080Y417500D03*
X215380Y417499D03*
X210580D03*
X208080Y424586D03*
X210580D03*
X215380D03*
X203280Y417500D03*
Y424586D03*
X208080Y431673D03*
Y438760D03*
X210580D03*
X215380D03*
Y431673D03*
X210580D03*
X203280D03*
Y438760D03*
Y445847D03*
X208080D03*
X215380Y467539D03*
X210580D03*
X203280D03*
X208080Y474626D03*
X210580D03*
X215380D03*
X203280D03*
X215380Y488799D03*
X203280D03*
X208080D03*
X210580D03*
X203280Y481713D03*
X210580Y481712D03*
X208080D03*
X215380D03*
X208080Y495886D03*
X203280D03*
X215380Y518760D03*
X210580D03*
X208080D03*
X210580Y511673D03*
X215380D03*
X203280D03*
Y518760D03*
X210580Y532933D03*
X208080D03*
Y540020D03*
Y525846D03*
X210580D03*
X215380D03*
Y532933D03*
X203280Y525847D03*
Y532933D03*
Y540020D03*
Y547106D03*
X203740Y567914D03*
Y565414D03*
Y570414D03*
Y575414D03*
Y572914D03*
X203280Y602205D03*
Y595118D03*
X209429Y625300D03*
X215697Y3000D03*
X231681Y4469D03*
X221944Y102249D03*
X224961Y109172D03*
X226968Y106495D03*
X230712Y116497D03*
X217944Y102249D03*
X227961Y109172D03*
X230712Y123584D03*
Y130670D03*
X219969Y133298D03*
X228608Y141228D03*
X230712Y137757D03*
X226702Y146012D03*
X231496Y150847D03*
X220244Y195176D03*
X219863Y198883D03*
X217744Y195176D03*
X223044D03*
X223792Y206838D03*
X219863Y201683D03*
X221292Y206838D03*
X217604Y203393D03*
X226254Y236121D03*
X223288Y238589D03*
X226173Y253198D03*
X228760Y316122D03*
X228267Y392718D03*
Y408718D03*
Y400718D03*
Y404718D03*
Y412718D03*
X223925Y543925D03*
X224500Y555000D03*
X224104Y562800D03*
X224040Y558800D03*
X222646Y607542D03*
X227249Y1447453D03*
Y1450853D03*
Y1458453D03*
Y1461853D03*
X218171Y1474460D03*
X216342Y1515642D03*
X217519Y1537172D03*
X233042Y24773D03*
Y44773D03*
X240363Y53597D03*
X242712Y116496D03*
Y109410D03*
Y102323D03*
X238012Y116497D03*
X235512D03*
X238012Y109410D03*
Y123583D03*
Y130670D03*
X235512D03*
X242712D03*
Y123583D03*
X235512Y123584D03*
Y137757D03*
X242712Y137756D03*
X239244Y213539D03*
X232690Y238689D03*
X240925Y238714D03*
X233464Y247292D03*
X236349Y339428D03*
X242102Y656321D03*
X245000Y678462D03*
X241204Y814841D03*
X248556Y824003D03*
X247600Y848500D03*
X237700Y1531600D03*
X260363Y53597D03*
X251174Y77784D03*
Y80384D03*
Y82984D03*
Y75184D03*
Y85584D03*
X253728Y92849D03*
X260688Y103037D03*
X250964Y109410D03*
X250712Y102323D03*
X250964Y116496D03*
X260822D03*
Y109410D03*
X251136Y124576D03*
X260822Y130670D03*
Y123583D03*
X252189Y130670D03*
X257413Y137756D03*
X252184D03*
X259457Y228726D03*
Y231226D03*
Y226226D03*
Y223726D03*
X257226Y312081D03*
X265011Y403307D03*
X255000Y427017D03*
X254692Y431029D03*
X253758Y435029D03*
X254678Y449873D03*
X261605Y465492D03*
Y472579D03*
X259105D03*
X254305D03*
X261605Y486752D03*
X254305D03*
X259105Y479666D03*
X261605D03*
X254305D03*
X259105Y486752D03*
X254305Y493839D03*
X259105D03*
X261605Y516713D03*
X259105D03*
Y523800D03*
X261605D03*
X254305D03*
Y516713D03*
X261605Y509626D03*
Y530886D03*
X259105D03*
Y537973D03*
X254305Y530886D03*
Y537973D03*
Y566752D03*
X261605Y559665D03*
Y566752D03*
X259105D03*
X261605Y588012D03*
X259105Y588013D03*
X254305Y573839D03*
X261605D03*
X259105D03*
X261605Y580926D03*
X259105D03*
X254305D03*
Y588013D03*
X259105Y602186D03*
X254305D03*
Y595099D03*
X259105D03*
X261605D03*
Y602185D03*
X254305Y609272D03*
X259105D03*
X261605D03*
X259105Y616359D03*
X254305D03*
X258867Y680499D03*
X248690Y678519D03*
X254058Y819851D03*
X255289Y824340D03*
X279156Y5374D03*
X278469Y24773D03*
Y44773D03*
X274105Y94017D03*
X278105D03*
X277834Y101701D03*
X268822Y116496D03*
Y109410D03*
X278233Y115401D03*
Y110445D03*
X268822Y102323D03*
X271580Y107649D03*
Y104249D03*
X268822Y130670D03*
Y123583D03*
X278233Y129574D03*
Y124618D03*
X268822Y137756D03*
X276146Y151540D03*
X279796Y191941D03*
X279663Y188727D03*
X269913Y228961D03*
Y226461D03*
X276420Y226141D03*
X269913Y223661D03*
X277882Y229286D03*
X273620Y226141D03*
X269913Y231461D03*
X276363Y236611D03*
X278863D03*
X277882Y231786D03*
X273863Y236611D03*
X276065Y248891D03*
X273565D03*
X278565D03*
X276317Y288190D03*
X273517Y285690D03*
X271017Y288190D03*
X273517D03*
X271017Y285690D03*
X276317D03*
X274425Y390500D03*
X265011Y410394D03*
X265945Y440098D03*
Y437598D03*
Y435098D03*
Y432598D03*
Y430098D03*
X266405Y451319D03*
Y458406D03*
X274205Y466027D03*
X266405Y465492D03*
X266229Y462264D03*
X274347Y475262D03*
X266405Y472579D03*
X274347Y489435D03*
Y482666D03*
X266405Y479665D03*
Y486752D03*
Y493839D03*
X274163Y495088D03*
X266405Y523799D03*
Y516713D03*
Y509626D03*
X274205D03*
X274820Y522134D03*
X274898Y514608D03*
X266405Y530886D03*
Y537973D03*
X275463Y529136D03*
X275302Y535677D03*
X266405Y566752D03*
Y559665D03*
X274586Y565574D03*
X274205Y559665D03*
X266405Y580926D03*
Y588012D03*
Y573839D03*
X274233Y574338D03*
X266405Y602185D03*
Y595099D03*
Y609272D03*
Y616358D03*
X274332D03*
X274096Y820725D03*
X269700Y884600D03*
X269900Y914200D03*
X272000Y1644980D03*
X286129Y36971D03*
X291182Y84140D03*
Y80140D03*
Y76140D03*
X282105Y94017D03*
X286114D03*
X288635Y117557D03*
X283225Y115401D03*
X285384Y103783D03*
X296551Y103621D03*
X293627Y117557D03*
X288635Y131731D03*
Y122513D03*
X283225Y129574D03*
Y124618D03*
X293627Y122513D03*
Y131731D03*
X291726Y146461D03*
X293627Y136687D03*
X288635D03*
X290628Y152367D03*
X292328Y180572D03*
Y185165D03*
X286296Y184619D03*
X288276Y206760D03*
X281575Y224712D03*
Y222212D03*
X281490Y256535D03*
X289490D03*
X290520Y279208D03*
X294624Y281307D03*
X296614Y290845D03*
Y288345D03*
X284543Y290755D03*
X280543D03*
X288543D03*
X284075Y381500D03*
X292500Y410394D03*
Y403307D03*
X284295Y430760D03*
X284316Y433570D03*
X284132Y437072D03*
X284173Y439963D03*
X284417Y443180D03*
X284437Y454744D03*
X284379Y452018D03*
X292316Y458406D03*
X284482Y460250D03*
X284516Y465492D03*
X282247Y470136D03*
X292316Y465492D03*
X284516Y472579D03*
X292316D03*
X284516Y479665D03*
Y486752D03*
X292316Y479665D03*
Y486752D03*
Y493839D03*
X284516D03*
X292316Y523799D03*
Y516713D03*
Y509626D03*
X284516Y516713D03*
Y509626D03*
X292316Y537973D03*
Y530886D03*
X283377Y532756D03*
X283456Y525483D03*
X280976Y537973D03*
X284516Y559665D03*
Y566752D03*
X292316Y559665D03*
Y566752D03*
X284366Y579978D03*
X292316Y573839D03*
Y588012D03*
Y580925D03*
X284516Y573839D03*
X292316Y595099D03*
Y602185D03*
X284580Y608117D03*
X292316Y616358D03*
Y609272D03*
X281980Y953926D03*
X292000Y1644980D03*
X298059Y3000D03*
X309106Y37543D03*
X308760Y55513D03*
X310882Y96613D03*
X305953Y91951D03*
X312088Y113394D03*
X304557Y117261D03*
X297011Y180527D03*
X312264Y172665D03*
Y180665D03*
X299759Y190285D03*
X296966Y185121D03*
X312296Y212864D03*
Y200864D03*
Y221864D03*
Y216864D03*
X299114Y290845D03*
Y288345D03*
X302966Y324139D03*
X310013Y316731D03*
X306812Y342319D03*
X301943Y332017D03*
X301158Y380307D03*
X309258Y389912D03*
Y393924D03*
Y385912D03*
X301308Y395346D03*
X301393Y400039D03*
X309258Y409924D03*
Y405924D03*
Y401924D03*
X306673Y418838D03*
X298507Y445908D03*
X302457Y445787D03*
X312000Y1644980D03*
X318059Y3000D03*
X313624Y60922D03*
X324306Y102249D03*
X320306D03*
X327323Y109172D03*
X316306Y102249D03*
X314737Y110784D03*
X314854Y130898D03*
X322331Y133298D03*
X329064Y146012D03*
X316478Y134579D03*
X322225Y198883D03*
X322606Y195176D03*
X325406D03*
X320106D03*
X317606D03*
X323654Y206838D03*
X319966Y203393D03*
X322225Y201683D03*
X317466Y203393D03*
X326154Y206838D03*
X325650Y238589D03*
X328616Y236121D03*
X328535Y253198D03*
X314053Y252371D03*
X323882Y303839D03*
X319857Y321649D03*
X315904Y336324D03*
X320483Y353506D03*
X321549Y445315D03*
Y448115D03*
X323489Y471484D03*
X318497Y466528D03*
X323489D03*
X318497Y471484D03*
X328899Y473640D03*
Y487813D03*
X323489Y480701D03*
X328899Y478596D03*
X318497Y480701D03*
Y485657D03*
X323489D03*
X328899Y492769D03*
X323489Y515617D03*
X328899Y517774D03*
X318497Y510661D03*
X323489D03*
X318497Y515617D03*
X328899Y522730D03*
X318497Y524835D03*
X328899Y536903D03*
Y531947D03*
X323489Y529791D03*
Y524835D03*
X318497Y529791D03*
X324291Y556775D03*
X328899Y572769D03*
X318497Y565657D03*
Y560701D03*
X328899Y567813D03*
X323489Y565657D03*
Y560701D03*
X318497Y579830D03*
X323489Y574874D03*
X318497D03*
X323489Y579830D03*
X328899Y581987D03*
X323489Y589047D03*
X318497D03*
X328899Y586943D03*
X318497Y594003D03*
X328899Y596160D03*
X323489Y594003D03*
Y603221D03*
X318497D03*
X328899Y601116D03*
Y610333D03*
X323489Y608177D03*
X318497D03*
X328899Y615289D03*
X334043Y4469D03*
X335404Y24773D03*
X330905Y23806D03*
Y31806D03*
X335404Y44773D03*
X342725Y53597D03*
X329330Y106495D03*
X345074Y116496D03*
X337874Y116497D03*
X340374D03*
X345074Y109410D03*
Y102323D03*
X340374Y109410D03*
X333074Y116497D03*
X330323Y109172D03*
X337874Y130670D03*
X345074D03*
Y123583D03*
X340374D03*
X337874Y123584D03*
X333074D03*
Y130670D03*
X340374D03*
X333074Y137757D03*
X337874D03*
X330970Y141228D03*
X345074Y137756D03*
X333858Y150847D03*
X341606Y213539D03*
X335052Y238689D03*
X335826Y247292D03*
X343287Y238714D03*
X345050Y458334D03*
X333891Y473640D03*
Y487813D03*
Y478596D03*
Y492769D03*
Y522730D03*
Y517774D03*
Y531947D03*
Y536903D03*
X338358Y554861D03*
X333891Y572769D03*
Y567813D03*
Y586943D03*
Y581987D03*
Y596160D03*
Y601116D03*
Y610333D03*
Y615289D03*
X337564Y1018294D03*
X333985Y1017945D03*
X341077Y1018056D03*
X332000Y1644980D03*
X353536Y82984D03*
Y80384D03*
Y77784D03*
Y75184D03*
X356090Y92849D03*
X353536Y85584D03*
X353074Y102323D03*
X353326Y109410D03*
Y116496D03*
X353498Y124576D03*
X354551Y130670D03*
X359525Y137756D03*
X354546D03*
X348375Y322284D03*
X348968Y333138D03*
X348737Y375386D03*
X354486Y377173D03*
X357173Y392183D03*
X357218Y396866D03*
X358042Y442518D03*
Y439718D03*
X347450Y447486D03*
X353670Y488618D03*
Y491118D03*
Y493618D03*
X356778Y491870D03*
X353670Y496118D03*
X358207Y836462D03*
X358096Y867459D03*
X358086Y884616D03*
X357962Y898800D03*
X358024Y912085D03*
X358085Y923327D03*
X355929Y1132042D03*
X351563Y1132410D03*
X358850Y1511576D03*
Y1506845D03*
Y1516307D03*
X352000Y1644980D03*
X362725Y53597D03*
X376467Y94017D03*
X363050Y103037D03*
X363184Y116496D03*
Y109410D03*
X371184Y116496D03*
Y109410D03*
Y102323D03*
X373942Y104249D03*
Y107649D03*
X363184Y130670D03*
Y123583D03*
X371184Y130670D03*
Y123583D03*
Y137756D03*
X372275Y226461D03*
X375982Y226141D03*
X361819Y231226D03*
Y228726D03*
Y223726D03*
Y226226D03*
X372275Y228961D03*
Y231461D03*
Y223661D03*
X378782Y226141D03*
X376225Y236611D03*
X375927Y248891D03*
X365365Y293796D03*
X367865D03*
X373379Y288190D03*
X375879Y285690D03*
X373379D03*
X375879Y288190D03*
X364933Y374232D03*
X363015Y710365D03*
X365887Y710329D03*
X365691Y815127D03*
X371507Y815303D03*
X362042Y814772D03*
X368273Y928100D03*
X375040Y932959D03*
X367944Y946082D03*
X372000Y1644980D03*
X388059Y3000D03*
X381518Y5374D03*
X388487Y24069D03*
X380831Y24773D03*
X383612Y30618D03*
X380831Y44773D03*
X393544Y76140D03*
Y84140D03*
Y80140D03*
X384467Y94017D03*
X388476D03*
X380467D03*
X380196Y101701D03*
X390997Y117557D03*
X385587Y115401D03*
X380595D03*
X385587Y110445D03*
X380595D03*
X387746Y103783D03*
X390997Y131731D03*
Y122513D03*
X385587Y129574D03*
X380595D03*
X385587Y124618D03*
X380595D03*
X390997Y136687D03*
X382158Y191941D03*
X388658Y184619D03*
X382025Y188727D03*
X390638Y206760D03*
X380244Y229286D03*
X383937Y222212D03*
Y224712D03*
X381225Y236611D03*
X378725D03*
X380244Y231786D03*
X378427Y248891D03*
X380927D03*
X391852Y256535D03*
X383852D03*
X392882Y279208D03*
X378679Y285690D03*
Y288190D03*
X386905Y290755D03*
X382905D03*
X390905D03*
X387958Y813700D03*
X386614Y868286D03*
X391614Y938651D03*
X378119Y953696D03*
X392910Y948536D03*
X381377Y1003008D03*
X381045Y1009444D03*
X383710Y1007283D03*
X382465Y1012430D03*
X386415Y1321645D03*
X391691Y1326715D03*
X389985Y1405762D03*
X394000Y1508100D03*
X382017Y1555700D03*
Y1547700D03*
Y1551700D03*
X392000Y1644980D03*
X408059Y3000D03*
X408493Y117577D03*
X395989Y117557D03*
X398913Y103621D03*
X395989Y131731D03*
Y122513D03*
Y136687D03*
X399373Y180527D03*
X394690Y180572D03*
X403096Y192421D03*
X394690Y185165D03*
X399328Y185121D03*
X406725Y186629D03*
X396986Y281307D03*
X398976Y293645D03*
X401476D03*
Y288345D03*
Y290845D03*
X398976Y288345D03*
Y290845D03*
X405843Y315158D03*
X403343D03*
X407493Y354142D03*
X405603Y668060D03*
X408103D03*
X403103D03*
X400603D03*
Y678060D03*
X405603D03*
X408103D03*
X403103D03*
X402376Y842677D03*
X399876D03*
X402376Y850677D03*
X399876D03*
X406967Y878764D03*
X406415Y874840D03*
X407193Y883566D03*
X401121Y936686D03*
X409121Y939186D03*
X401121D03*
X409121Y936686D03*
X402682Y948536D03*
X402815Y951750D03*
X404176Y977684D03*
Y975084D03*
Y969984D03*
Y972484D03*
X406954Y982970D03*
X409554D03*
X404354D03*
X399285Y1081599D03*
X398915Y1097278D03*
X396415D03*
X409231Y1123101D03*
X406105Y1139435D03*
X410131Y1129301D03*
X407631D03*
X409231Y1125801D03*
X406105Y1131935D03*
Y1134435D03*
Y1136935D03*
Y1141935D03*
Y1146935D03*
Y1144435D03*
X403263Y1152684D03*
X408961Y1162384D03*
Y1164884D03*
Y1167384D03*
Y1169884D03*
Y1172384D03*
X403263Y1160834D03*
X408961Y1174884D03*
X406319Y1186709D03*
Y1184209D03*
Y1181709D03*
Y1179209D03*
X404004Y1192621D03*
Y1190121D03*
X397063Y1221428D03*
X401063D03*
X405063D03*
X409063D03*
X397063Y1233428D03*
Y1229428D03*
Y1225428D03*
X401063Y1237428D03*
Y1233428D03*
Y1229428D03*
Y1225428D03*
X405063Y1237428D03*
Y1233428D03*
Y1229428D03*
Y1225428D03*
X409063Y1237428D03*
Y1233428D03*
Y1229428D03*
Y1225428D03*
X401063Y1241428D03*
X405063Y1245428D03*
Y1241428D03*
X409063Y1245428D03*
Y1241428D03*
X398584Y1313443D03*
X399959Y1352153D03*
X398112Y1403741D03*
X401711Y1419771D03*
X406667D03*
X401990Y1446807D03*
X399731Y1442755D03*
X407469Y1495035D03*
X407854Y1492118D03*
X406377Y1499142D03*
X397245Y1511640D03*
X404053Y1513673D03*
X397220Y1521207D03*
X400911Y1537902D03*
X407048D03*
X400911Y1544424D03*
X407048Y1549936D03*
X400911D03*
X409461Y1569560D03*
X405461D03*
X420050Y33425D03*
X426147Y151540D03*
X414626Y180665D03*
Y172665D03*
X414658Y212864D03*
Y200864D03*
Y204864D03*
Y216864D03*
Y221864D03*
X423651Y307470D03*
X419177Y304470D03*
X415777D03*
X412318Y367903D03*
X420422Y367859D03*
X414275Y492469D03*
X424731Y492704D03*
X414275Y497469D03*
Y499969D03*
X427693Y498943D03*
X424731Y497704D03*
Y495204D03*
Y500204D03*
X414275Y494969D03*
X419040Y533690D03*
Y528390D03*
Y530990D03*
Y536290D03*
Y538890D03*
X423266Y631438D03*
X420266D03*
X417666D03*
X420266Y637038D03*
Y634238D03*
X417666Y637038D03*
Y634238D03*
X423266Y637038D03*
Y634238D03*
X418226Y653288D03*
X423266Y642638D03*
X420266D03*
X417666D03*
X423266Y639838D03*
X420266D03*
X418226Y646480D03*
Y648980D03*
X417666Y639838D03*
X418226Y655788D03*
X410603Y668060D03*
Y678060D03*
X424993Y728291D03*
X423700Y795500D03*
X424649Y842644D03*
X422149D03*
Y850644D03*
X424649D03*
X422149Y858644D03*
X424649D03*
X425759Y869921D03*
Y872721D03*
Y875521D03*
Y867121D03*
X422379Y867229D03*
X425759Y878321D03*
X411214Y892109D03*
X425121Y936686D03*
Y939186D03*
X417121Y936686D03*
Y939186D03*
X411960Y962261D03*
X414560D03*
X417160D03*
X411276Y978109D03*
X416476D03*
X413876D03*
X417677Y1052215D03*
X425175Y1098767D03*
X417171Y1098887D03*
X419987Y1098518D03*
X419731Y1123101D03*
X417231D03*
X422631Y1125801D03*
X425131Y1129301D03*
X422631D03*
X420131D03*
X417631D03*
X415131D03*
X412631D03*
X420131Y1125801D03*
X417631D03*
X425131D03*
X422495Y1152713D03*
Y1155213D03*
X412095Y1152713D03*
Y1155213D03*
X411461Y1162384D03*
Y1164884D03*
Y1167384D03*
Y1169884D03*
Y1172384D03*
X420619Y1179421D03*
Y1181921D03*
Y1184421D03*
Y1186921D03*
X411461Y1174884D03*
X422934Y1192621D03*
Y1190121D03*
X417469Y1192621D03*
Y1190121D03*
X413063Y1221428D03*
X417063D03*
X421063D03*
X425063D03*
X413063Y1237428D03*
Y1233428D03*
Y1229428D03*
Y1225428D03*
X417063Y1237428D03*
Y1233428D03*
Y1229428D03*
Y1225428D03*
X421063Y1237428D03*
Y1233428D03*
Y1229428D03*
Y1225428D03*
X425063Y1237428D03*
Y1233428D03*
Y1229428D03*
Y1225428D03*
X413063Y1245428D03*
Y1241428D03*
X417063Y1245428D03*
Y1241428D03*
X421063Y1245428D03*
Y1241428D03*
X425063Y1245428D03*
Y1241428D03*
X425283Y1364023D03*
X416029Y1371572D03*
X421300Y1415400D03*
X419100Y1402200D03*
X421200Y1417900D03*
X411147Y1474993D03*
X415241Y1492990D03*
X415095Y1502750D03*
X411353Y1519440D03*
X419467Y1519706D03*
X420279Y1525978D03*
X410626Y1525991D03*
X413012Y1537902D03*
Y1544098D03*
X426196Y1534087D03*
X413012Y1549936D03*
X421616Y1549885D03*
X413461Y1569560D03*
X412000Y1644980D03*
X428059Y3000D03*
X441727Y146461D03*
X440629Y152367D03*
X431525Y304470D03*
X434925D03*
X427051Y307470D03*
X430439Y358115D03*
X431524Y370309D03*
X434924D03*
X435789Y501525D03*
X427568Y502003D03*
X435831Y498923D03*
X438644Y500461D03*
X428740Y533690D03*
X442704Y533790D03*
X428740Y528390D03*
Y530990D03*
X442704Y528490D03*
Y531090D03*
X428740Y536290D03*
X431804Y536682D03*
X428740Y538890D03*
X431804Y539182D03*
X442704Y536390D03*
X439804Y536682D03*
X442704Y538990D03*
X439804Y539182D03*
X436369Y622883D03*
X441832Y626193D03*
X441612Y631011D03*
X430600Y797400D03*
X428759Y869921D03*
Y867121D03*
Y872721D03*
Y875521D03*
Y878321D03*
X432332Y892049D03*
Y897649D03*
Y894849D03*
Y900449D03*
X433206Y1055498D03*
X430706D03*
Y1057998D03*
X433206D03*
Y1060498D03*
Y1062998D03*
X430706D03*
Y1060498D03*
X441359Y1123101D03*
X438233Y1139435D03*
X441359Y1125801D03*
X439759Y1129301D03*
X442259D03*
X429331Y1136935D03*
Y1134435D03*
Y1139435D03*
Y1131935D03*
X435733D03*
Y1134435D03*
Y1136935D03*
Y1139435D03*
X438233Y1131935D03*
Y1134435D03*
Y1136935D03*
X429331Y1141935D03*
X435733D03*
Y1146935D03*
Y1144435D03*
X438233Y1141935D03*
Y1146935D03*
Y1144435D03*
X437231Y1154902D03*
Y1152402D03*
X429331Y1146935D03*
Y1144435D03*
X436789Y1167384D03*
Y1164884D03*
Y1162384D03*
Y1172384D03*
Y1169884D03*
X439289Y1167384D03*
Y1164884D03*
Y1162384D03*
X427231D03*
X429731D03*
Y1164884D03*
Y1167384D03*
Y1169884D03*
Y1172384D03*
X427231D03*
Y1169884D03*
Y1167384D03*
Y1164884D03*
X439289Y1172384D03*
Y1169884D03*
X437132Y1158266D03*
X433249Y1186709D03*
Y1184209D03*
Y1181709D03*
Y1179209D03*
X429731Y1174884D03*
X427231D03*
X436789D03*
X439289D03*
X430934Y1190121D03*
Y1192621D03*
X429063Y1221428D03*
X433063D03*
X429063Y1237428D03*
Y1233428D03*
Y1229428D03*
Y1225428D03*
X433063Y1237428D03*
Y1233428D03*
Y1229428D03*
Y1225428D03*
X429063Y1245428D03*
Y1241428D03*
X433063Y1245428D03*
Y1241428D03*
X431885Y1313115D03*
X437675Y1550158D03*
X430657Y1563562D03*
X429784Y1548222D03*
X432000Y1644980D03*
X448059Y3000D03*
X448092Y375770D03*
X452404Y533690D03*
Y528390D03*
Y530990D03*
X455104Y536582D03*
X452404Y536290D03*
X455104Y539082D03*
X452404Y538890D03*
X447279Y633881D03*
X448726Y653288D03*
Y646480D03*
Y648980D03*
Y655788D03*
X447836Y711199D03*
X458120Y974701D03*
X451460Y974695D03*
X448999Y994483D03*
X456210Y1004680D03*
X452319Y1000828D03*
X449731Y1000855D03*
X453710Y1018825D03*
X443091Y1022766D03*
Y1030266D03*
X450063Y1043140D03*
X449767Y1047047D03*
X450244Y1090268D03*
X457303Y1098767D03*
X452115Y1098518D03*
X446863Y1098428D03*
X450244Y1093068D03*
X449359Y1123101D03*
X451859D03*
X457259Y1129301D03*
X449759Y1125801D03*
X452259D03*
X444759Y1129301D03*
X447259D03*
X449759D03*
X452259D03*
X454759Y1125801D03*
X457259D03*
X454759Y1129301D03*
X443223Y1155213D03*
Y1152713D03*
X452623D03*
Y1155213D03*
X457559Y1169884D03*
Y1167384D03*
Y1164884D03*
Y1162384D03*
X455059D03*
Y1164884D03*
Y1167384D03*
Y1169884D03*
Y1172384D03*
X457559D03*
X455059Y1174884D03*
X457559D03*
X447549Y1179421D03*
Y1181921D03*
Y1184421D03*
Y1186921D03*
X449864Y1190121D03*
Y1192621D03*
X452000Y1644980D03*
X468059Y3000D03*
X474307Y102249D03*
X464738Y110784D03*
X462089Y113394D03*
X470307Y102249D03*
X466307D03*
X472332Y133298D03*
X464332D03*
X466479Y134579D03*
X470107Y195176D03*
X467607D03*
X472607D03*
X472226Y198883D03*
X475407Y195176D03*
X473655Y206838D03*
X467467Y203393D03*
X469967D03*
X472226Y201683D03*
X460950Y328185D03*
Y324785D03*
X463950Y332659D03*
Y336059D03*
X460950Y343933D03*
Y340533D03*
X463950Y351807D03*
Y348407D03*
X466375Y366365D03*
X470389Y389553D03*
X467848Y476535D03*
X464848D03*
X468558Y495669D03*
X463104Y536582D03*
X468850Y537507D03*
X463104Y539082D03*
X461849Y668016D03*
X459349D03*
X466849D03*
X469349D03*
X464349D03*
X469349Y678016D03*
X466849D03*
X459349D03*
X461849D03*
X464349D03*
X462242Y809792D03*
X459245Y807152D03*
X475032Y843252D03*
X474678Y857919D03*
X463134Y859203D03*
X465492Y861970D03*
X460455Y867050D03*
X475046Y885952D03*
X467494Y924532D03*
X471876Y937236D03*
X469495Y1011303D03*
Y1023303D03*
Y1017303D03*
X462427Y1030218D03*
X460277Y1090268D03*
Y1093068D03*
X474818Y1123101D03*
X469192Y1131935D03*
X474818Y1125801D03*
X473218Y1129301D03*
X461459Y1136935D03*
Y1134435D03*
Y1139435D03*
Y1131935D03*
X471692Y1139435D03*
Y1136935D03*
Y1134435D03*
Y1131935D03*
X469192Y1139435D03*
Y1136935D03*
Y1134435D03*
X471692Y1146935D03*
Y1141935D03*
X469192Y1144435D03*
Y1146935D03*
Y1141935D03*
X471692Y1144435D03*
X461459D03*
X462687Y1152684D03*
X468850D03*
X461459Y1141935D03*
Y1146935D03*
X462687Y1160834D03*
X474548Y1172384D03*
Y1169884D03*
Y1167384D03*
Y1164884D03*
Y1162384D03*
X468850Y1160834D03*
X474548Y1174884D03*
X472000Y1644980D03*
X484043Y4469D03*
X485404Y24773D03*
Y44773D03*
X480324Y109172D03*
X477324D03*
X479331Y106495D03*
X483075Y116497D03*
X487875D03*
X490375Y109410D03*
Y116497D03*
X483075Y130670D03*
X487875Y123584D03*
Y130670D03*
X490375Y123583D03*
Y130670D03*
X483075Y123584D03*
X479065Y146012D03*
X480971Y141228D03*
X483075Y137757D03*
X487875D03*
X483859Y150847D03*
X476155Y206838D03*
X491607Y213539D03*
X485827Y247292D03*
X478617Y236121D03*
X475651Y238589D03*
X485053Y238689D03*
X478536Y253198D03*
X485485Y439903D03*
X489485D03*
X492736Y478982D03*
X486738Y581222D03*
X489538D03*
Y591215D03*
X486738D03*
X491340Y611091D03*
X481165Y646036D03*
X485005Y659771D03*
X488765Y667224D03*
X485824Y819787D03*
X481593Y826387D03*
X479448Y828594D03*
X491453Y834546D03*
X488469Y857013D03*
X490706Y859339D03*
X483636Y952152D03*
X487091Y989550D03*
X481495Y1011303D03*
X475495D03*
X481495Y1023303D03*
Y1017303D03*
X475495Y1023303D03*
X476148Y1057998D03*
Y1055498D03*
X478648D03*
Y1057998D03*
X476148Y1060498D03*
Y1062998D03*
X478648D03*
Y1060498D03*
X490762Y1098767D03*
X485574Y1098518D03*
X480322Y1098428D03*
X485318Y1123101D03*
X482818D03*
X490718Y1129301D03*
X483218Y1125801D03*
X485718D03*
X475718Y1129301D03*
X478218D03*
X480718D03*
X483218D03*
X485718D03*
X488218Y1125801D03*
X490718D03*
X488218Y1129301D03*
X477682Y1152713D03*
Y1155213D03*
X488082D03*
Y1152713D03*
X477048Y1172384D03*
Y1169884D03*
Y1167384D03*
Y1164884D03*
Y1162384D03*
X479521Y1179209D03*
Y1181709D03*
Y1184209D03*
Y1186709D03*
X477048Y1174884D03*
X490671Y1192621D03*
Y1190121D03*
X477206Y1192621D03*
Y1190121D03*
X492725Y53597D03*
X503537Y77784D03*
Y75184D03*
Y80384D03*
Y82984D03*
X506091Y92849D03*
X503537Y85584D03*
X503075Y102323D03*
X503327Y109410D03*
Y116496D03*
X495075D03*
Y102323D03*
Y109410D03*
Y130670D03*
Y123583D03*
X506653Y121652D03*
X504552Y130670D03*
X504547Y137756D03*
X495075D03*
X493288Y238714D03*
X503682Y455466D03*
X497776Y448466D03*
X492736Y487982D03*
Y483982D03*
Y499982D03*
X506925Y546830D03*
X493929Y555194D03*
X496729D03*
X493929Y563194D03*
X496729D03*
X493929Y571194D03*
X496729D03*
X492338Y581222D03*
Y591215D03*
X499278Y641817D03*
X493778D03*
X502755Y657694D03*
X504966Y678098D03*
X500714Y708755D03*
X502832Y720491D03*
X504341Y812040D03*
X491655Y829173D03*
X506246Y824689D03*
X509665Y824512D03*
X492799Y846488D03*
X499640Y861538D03*
X509791Y881932D03*
X503144Y957934D03*
X499595Y963963D03*
X506702Y978947D03*
X493091Y989550D03*
X503933Y981392D03*
X506566Y1000766D03*
Y1004766D03*
Y1016266D03*
Y1030766D03*
X505981Y1052487D03*
X506946Y1123101D03*
Y1125801D03*
X505346Y1129301D03*
X507846D03*
X503820Y1139435D03*
Y1136935D03*
Y1134435D03*
Y1131935D03*
X501320Y1139435D03*
Y1136935D03*
Y1134435D03*
Y1131935D03*
X494918Y1136935D03*
Y1134435D03*
Y1139435D03*
Y1131935D03*
X503820Y1144435D03*
Y1146935D03*
Y1141935D03*
X501320Y1144435D03*
Y1146935D03*
Y1141935D03*
X494918Y1146935D03*
Y1144435D03*
Y1141935D03*
X502562Y1152713D03*
Y1155213D03*
X502376Y1172384D03*
Y1169884D03*
Y1167384D03*
Y1164884D03*
Y1162384D03*
X504876Y1172384D03*
Y1169884D03*
Y1167384D03*
Y1164884D03*
Y1162384D03*
X492818D03*
Y1164884D03*
Y1167384D03*
Y1169884D03*
Y1172384D03*
X495318D03*
Y1169884D03*
Y1167384D03*
Y1164884D03*
Y1162384D03*
X502562Y1158200D03*
X506451Y1179209D03*
Y1181709D03*
Y1184209D03*
Y1186709D03*
X504876Y1174884D03*
X493821Y1186921D03*
Y1184421D03*
Y1181921D03*
Y1179421D03*
X492818Y1174884D03*
X495318D03*
X502376D03*
X504136Y1190121D03*
Y1192621D03*
X496136Y1190121D03*
Y1192621D03*
X506562Y1222194D03*
X502562D03*
X498562D03*
X494562D03*
X506562Y1226194D03*
Y1230194D03*
Y1234194D03*
Y1238194D03*
X502562Y1226194D03*
Y1230194D03*
Y1234194D03*
Y1238194D03*
X498562Y1226194D03*
Y1230194D03*
Y1234194D03*
Y1238194D03*
X494562Y1226194D03*
Y1230194D03*
Y1234194D03*
Y1238194D03*
Y1246194D03*
Y1242194D03*
X506562D03*
Y1246194D03*
X502562Y1242194D03*
Y1246194D03*
X498562Y1242194D03*
Y1246194D03*
X492000Y1644980D03*
X512725Y53597D03*
X513051Y103037D03*
X513185Y116496D03*
Y109410D03*
X521185Y116496D03*
Y109410D03*
Y102323D03*
X523943Y107649D03*
Y104249D03*
X513185Y130670D03*
Y123583D03*
X521185Y130670D03*
Y123583D03*
X509251Y137756D03*
X521185D03*
X522276Y223661D03*
Y226461D03*
Y228961D03*
Y231461D03*
X511820Y231226D03*
Y228726D03*
Y223726D03*
Y226226D03*
X517866Y293796D03*
X515366D03*
X523380Y285690D03*
Y288190D03*
X514608Y445874D03*
X510022Y446352D03*
X523705Y444269D03*
X523583Y447201D03*
X508729Y469905D03*
X521310Y470045D03*
X513310D03*
X523457Y482134D03*
Y484634D03*
X521636Y504699D03*
X516636D03*
X519136D03*
X516756Y500086D03*
X517319Y521804D03*
X516338Y516979D03*
X521338D03*
X518838D03*
X513626Y528578D03*
Y531378D03*
X518781Y527449D03*
X517319Y524304D03*
X521581Y527449D03*
X521494Y572975D03*
X519875Y608311D03*
X523596Y628242D03*
X512404Y629362D03*
X510215Y627948D03*
X510425Y683246D03*
X521540Y686319D03*
X518001Y694940D03*
X522410Y694881D03*
X518067Y699378D03*
X518530Y703584D03*
X522628Y703884D03*
X515422Y753455D03*
X509063Y782867D03*
X508130Y787488D03*
X517702Y826600D03*
X508049Y877789D03*
X509428Y888390D03*
X511025Y911443D03*
X516256Y939157D03*
X520146Y939241D03*
X523289Y939195D03*
X514886Y952189D03*
X521353Y952266D03*
X514566Y1016266D03*
X519792Y1031271D03*
X515831Y1090568D03*
X517702Y1098518D03*
X512450Y1098428D03*
X515831Y1093068D03*
X522890Y1098767D03*
X514946Y1123101D03*
X517446D03*
X522846Y1129301D03*
X515346Y1125801D03*
X517846D03*
X510346Y1129301D03*
X512846D03*
X515346D03*
X517846D03*
X520346Y1125801D03*
X522846D03*
X520346Y1129301D03*
X518210Y1155213D03*
Y1152713D03*
X508810D03*
Y1155213D03*
X520646Y1169884D03*
Y1167384D03*
Y1164884D03*
Y1162384D03*
X523146D03*
Y1164884D03*
Y1167384D03*
Y1169884D03*
Y1172384D03*
X520646D03*
X520751Y1186921D03*
Y1184421D03*
Y1181921D03*
Y1179421D03*
X523146Y1174884D03*
X520646D03*
X523066Y1190121D03*
Y1192621D03*
X522562Y1222194D03*
X518562D03*
X514562D03*
X510562D03*
X522562Y1226194D03*
X518562D03*
Y1230194D03*
Y1234194D03*
X514562Y1226194D03*
Y1230194D03*
Y1234194D03*
Y1238194D03*
X510562Y1226194D03*
Y1230194D03*
Y1234194D03*
Y1238194D03*
X514562Y1242194D03*
Y1246194D03*
X510562Y1242194D03*
Y1246194D03*
X512000Y1644980D03*
X531518Y5374D03*
X530831Y24773D03*
Y44773D03*
X526468Y94017D03*
X530197Y101701D03*
X534468Y94017D03*
X538477D03*
X530468D03*
X530596Y115401D03*
X535588Y110445D03*
Y115401D03*
X530596Y110445D03*
X537747Y103783D03*
X530596Y124618D03*
Y129574D03*
X535588Y124618D03*
Y129574D03*
X528509Y151540D03*
X538659Y184619D03*
X532159Y191941D03*
X532026Y188727D03*
X530245Y229286D03*
X528783Y226141D03*
X525983D03*
X533938Y222212D03*
Y224712D03*
X526226Y236611D03*
X531226D03*
X528726D03*
X530245Y231786D03*
X528428Y248891D03*
X530928D03*
X533853Y256535D03*
X525928Y248891D03*
X525880Y285690D03*
X528680D03*
X525880Y288190D03*
X528680D03*
X532906Y290755D03*
X536906D03*
X540906D03*
X535119Y483886D03*
Y481086D03*
Y478586D03*
X526902Y478446D03*
Y475946D03*
X531412Y480705D03*
X535119Y476086D03*
X528612Y480705D03*
X532936Y519544D03*
X525288Y522129D03*
X527936Y519544D03*
X525436D03*
X530436D03*
X525288Y524629D03*
Y527129D03*
Y529929D03*
X529481Y532849D03*
X532281D03*
X524708Y572842D03*
X532863Y585507D03*
X528270D03*
X528816Y579475D03*
X532908Y590190D03*
X528314Y590145D03*
X532770Y605443D03*
X538826Y633450D03*
X526756Y636005D03*
Y633205D03*
X538826Y636250D03*
Y639050D03*
X526756Y638805D03*
X524653Y643595D03*
X526956Y694959D03*
X526951Y699443D03*
X526933Y703820D03*
X542275Y760782D03*
X527733Y847026D03*
X527879Y952189D03*
X527046Y1131935D03*
Y1139435D03*
Y1134435D03*
Y1136935D03*
X528274Y1152684D03*
X527046Y1146935D03*
Y1144435D03*
Y1141935D03*
X528274Y1160834D03*
X532000Y1644980D03*
X550421Y3000D03*
X543545Y84140D03*
Y80140D03*
Y76140D03*
X540998Y117557D03*
X545990D03*
X548914Y103621D03*
X545990Y122513D03*
Y131731D03*
X540998Y122513D03*
Y131731D03*
X544089Y146461D03*
X545990Y136687D03*
X540998D03*
X542991Y152367D03*
X549374Y180527D03*
X544691Y180572D03*
X553097Y192421D03*
X549329Y185121D03*
X544691Y185165D03*
X540639Y206760D03*
X541853Y256535D03*
X542883Y279208D03*
X546987Y281307D03*
X551477Y288345D03*
Y290845D03*
X548977Y288345D03*
Y290845D03*
Y293645D03*
X551477D03*
X540770Y605443D03*
X550274Y658676D03*
X551475Y661504D03*
X547227Y678299D03*
X547276Y675521D03*
X543101Y698772D03*
X540379Y719785D03*
X553871Y811298D03*
X548464Y823156D03*
X540807Y816556D03*
X545144Y909025D03*
X552238Y959102D03*
X548215Y1006560D03*
X552923Y997860D03*
X551673Y1023900D03*
X554696Y1018469D03*
X557681Y1035088D03*
X552000Y1644980D03*
X570421Y3000D03*
X566287Y60922D03*
X561123Y55513D03*
X563224Y96813D03*
X558316Y91951D03*
X556920Y117261D03*
X567100Y110784D03*
X564451Y113394D03*
X572669Y102249D03*
X568669D03*
X567290Y130898D03*
X568841Y134579D03*
X564627Y180665D03*
Y172665D03*
X569969Y195176D03*
X572469D03*
X572329Y203393D03*
X574588Y201683D03*
X564659Y212864D03*
Y200864D03*
X569829Y203393D03*
X564659Y221864D03*
Y216864D03*
X566416Y252371D03*
X561886Y728138D03*
X562001Y732834D03*
X562374Y721593D03*
X559625Y739609D03*
X563200Y739600D03*
X570695Y767052D03*
X571493Y763090D03*
X570038Y752339D03*
X564276Y776701D03*
X569186Y787332D03*
X561401Y811242D03*
X569577Y886913D03*
X560814Y901022D03*
X564923Y997860D03*
X560923D03*
X568923D03*
X556923D03*
X568362Y1008262D03*
X571857Y1009354D03*
X568362Y1011762D03*
X565451Y1035102D03*
X569520Y1102091D03*
X560211D03*
X566020D03*
X569520Y1114691D03*
X566020D03*
X560211D03*
X566020Y1127291D03*
X560211D03*
X569520D03*
X565600Y1530800D03*
X569349Y1541947D03*
X560635Y1543531D03*
X566800Y1541800D03*
X586405Y4469D03*
X587766Y24773D03*
Y44773D03*
X576669Y102249D03*
X582686Y109172D03*
X579686D03*
X581693Y106495D03*
X585437Y116497D03*
X574694Y133298D03*
X585437Y123584D03*
Y130670D03*
X581427Y146012D03*
X583333Y141228D03*
X585437Y137757D03*
X586221Y150847D03*
X574969Y195176D03*
X577769D03*
X574588Y198883D03*
X578517Y206838D03*
X576017D03*
X587415Y238689D03*
X588189Y247292D03*
X580979Y236121D03*
X578013Y238589D03*
X580898Y253198D03*
X573805Y728301D03*
X576556Y728219D03*
X575979Y732517D03*
X577638Y769772D03*
X574620Y772724D03*
X584624Y781850D03*
X587183Y785008D03*
X578204Y775137D03*
X582100Y787600D03*
X579758Y817753D03*
X573103Y941307D03*
X580923Y997860D03*
X576923D03*
X588923D03*
X577666Y1009354D03*
X581166D03*
X572923Y997860D03*
X584923D03*
X581166Y1021954D03*
X577666D03*
X587689Y1505724D03*
X583661Y1529142D03*
X573784Y1530646D03*
X575332Y1523740D03*
X583800Y1518000D03*
X583740Y1520640D03*
X587858Y1517942D03*
X577645Y1540982D03*
X580700Y1544100D03*
X595087Y53597D03*
X592737Y109410D03*
X590237Y116497D03*
X592737D03*
X597437Y102323D03*
Y109410D03*
Y116496D03*
Y123583D03*
Y130670D03*
X592737Y123583D03*
X590237Y123584D03*
Y130670D03*
X592737D03*
X597437Y137756D03*
X590237Y137757D03*
X593969Y213539D03*
X595650Y238714D03*
X603282Y390223D03*
X600272Y397335D03*
X603282Y395179D03*
Y404396D03*
Y409352D03*
X595280Y402291D03*
X600272D03*
X595280Y397335D03*
X592880Y416465D03*
Y411509D03*
X603282Y418569D03*
Y423525D03*
X597872Y425682D03*
X592880D03*
X597872Y416465D03*
Y411509D03*
X603282Y432743D03*
Y437699D03*
X597872Y439855D03*
X592880D03*
X597872Y430638D03*
X592880D03*
X597872Y444811D03*
X592880D03*
Y468609D03*
X597872D03*
X592880Y473565D03*
X597872D03*
X603282Y489895D03*
X592880Y487738D03*
X597872D03*
X603282Y480677D03*
Y475721D03*
X592880Y482782D03*
X597872D03*
X603282Y494851D03*
X592880Y517699D03*
X597872D03*
X603282Y519855D03*
X592880Y526916D03*
X597872Y531872D03*
X592880D03*
X603282Y524811D03*
Y538984D03*
Y534028D03*
X597872Y526916D03*
X605011Y603600D03*
Y619600D03*
Y623600D03*
X592238Y880612D03*
X592110Y895611D03*
X602385Y940920D03*
X591403Y936007D03*
X596923Y997860D03*
X592923D03*
X604923D03*
X600923D03*
X602603Y1012354D03*
Y1024954D03*
X604405Y1034870D03*
X591898Y1035011D03*
X590957Y1105091D03*
Y1117691D03*
X592978Y1514812D03*
X591858Y1523542D03*
X598800Y1546400D03*
X615087Y53597D03*
X605899Y80384D03*
Y82984D03*
Y77784D03*
Y75184D03*
X608453Y92849D03*
X605899Y85584D03*
X615413Y103037D03*
X605437Y102323D03*
X605689Y109410D03*
Y116496D03*
X615547D03*
Y109410D03*
X605861Y124576D03*
X615547Y130670D03*
Y123583D03*
X606914Y130670D03*
X606909Y137756D03*
X612138D03*
X614182Y223726D03*
Y226226D03*
Y231226D03*
Y228726D03*
X617728Y293796D03*
X620228D03*
X608274Y390223D03*
Y395179D03*
Y404396D03*
Y409352D03*
Y418569D03*
Y423525D03*
Y432743D03*
Y437699D03*
Y489895D03*
Y480677D03*
Y475721D03*
Y494851D03*
Y519855D03*
Y538984D03*
Y534028D03*
Y524811D03*
X612489Y941024D03*
X616923Y997860D03*
X608923D03*
X620151Y1040363D03*
X621479Y1030482D03*
X619086Y1056453D03*
X620715Y1046785D03*
X612000Y1644980D03*
X633248Y44884D03*
X636830Y94017D03*
X628830D03*
X632830D03*
X632559Y101701D03*
X632958Y110445D03*
X623547Y109410D03*
Y116496D03*
X632958Y115401D03*
X623547Y102323D03*
X626305Y104249D03*
Y107649D03*
X632958Y124618D03*
X623547Y123583D03*
Y130670D03*
X632958Y129574D03*
X623547Y137756D03*
X630871Y151540D03*
X634521Y191941D03*
X634388Y188727D03*
X624638Y231461D03*
X636300Y222212D03*
Y224712D03*
X632607Y229286D03*
X624638Y223661D03*
X631145Y226141D03*
X624638Y226461D03*
X628345Y226141D03*
X624638Y228961D03*
X633588Y236611D03*
X631088D03*
X632607Y231786D03*
X628588Y236611D03*
X630790Y248891D03*
X633290D03*
X628290D03*
X636215Y256535D03*
X631042Y288190D03*
Y285690D03*
X625742Y288190D03*
X628242Y285690D03*
X625742D03*
X628242Y288190D03*
X635268Y290755D03*
X630201Y553407D03*
X632701D03*
X630201Y550907D03*
X632701D03*
X621592Y1033862D03*
X636015Y1460782D03*
X627354Y1461182D03*
X636015Y1465513D03*
X627354Y1465913D03*
Y1456451D03*
X636015Y1476136D03*
X627354Y1476536D03*
X636015Y1480867D03*
X627354Y1481267D03*
Y1471805D03*
X636015Y1470244D03*
X627354Y1487159D03*
X636015Y1485598D03*
Y1491490D03*
X627354Y1491890D03*
X636015Y1496221D03*
X627354Y1496621D03*
Y1507245D03*
Y1511976D03*
X636015Y1511576D03*
X627354Y1502514D03*
X636015Y1500952D03*
Y1506845D03*
Y1516307D03*
X627354Y1558813D03*
X636015Y1563144D03*
X627354Y1563544D03*
X636015Y1567875D03*
X627354Y1568275D03*
Y1574167D03*
X636015Y1572606D03*
Y1578498D03*
X627354Y1578898D03*
X636015Y1593853D03*
X627354Y1594253D03*
X636015Y1583229D03*
X627354Y1583629D03*
Y1589522D03*
X636015Y1587960D03*
X627354Y1604876D03*
X636015Y1603315D03*
Y1598584D03*
X627354Y1598984D03*
X636015Y1609207D03*
X627354Y1609607D03*
X636015Y1618669D03*
Y1613938D03*
X627354Y1614338D03*
X632000Y1644980D03*
X645907Y76140D03*
Y84140D03*
Y80140D03*
X640839Y94017D03*
X643360Y117557D03*
X637950Y110445D03*
Y115401D03*
X648352Y117557D03*
X651276Y103621D03*
X640109Y103783D03*
X643360Y122513D03*
Y131731D03*
X637950Y124618D03*
Y129574D03*
X648352Y122513D03*
Y131731D03*
X646451Y146461D03*
X643360Y136687D03*
X648352D03*
X645353Y152367D03*
X647053Y180572D03*
X651736Y180527D03*
X651691Y185121D03*
X647053Y185165D03*
X641021Y184619D03*
X643001Y206760D03*
X644215Y256535D03*
X645245Y279208D03*
X649349Y281307D03*
X651339Y290845D03*
Y293645D03*
X653839D03*
X639268Y290755D03*
X643268D03*
X653839Y288345D03*
Y290845D03*
X651339Y288345D03*
X648211Y610400D03*
X653338Y1465513D03*
X644677Y1461182D03*
Y1456451D03*
Y1465913D03*
X653338Y1460782D03*
X644677Y1476536D03*
Y1471805D03*
X653338Y1480867D03*
Y1470244D03*
Y1476136D03*
X644677Y1481267D03*
X653338Y1491490D03*
X644677Y1496621D03*
Y1491890D03*
Y1487159D03*
X653338Y1496221D03*
Y1485598D03*
X644677Y1511976D03*
X653338Y1511576D03*
Y1500952D03*
Y1506845D03*
X644677Y1502514D03*
Y1507245D03*
X653338Y1516307D03*
X644677Y1558813D03*
X653338Y1563144D03*
X644677Y1563544D03*
X653338Y1572606D03*
Y1578498D03*
X644677Y1578898D03*
Y1574167D03*
X653338Y1567875D03*
X644677Y1568275D03*
X653338Y1587960D03*
Y1593853D03*
X644677Y1594253D03*
Y1589522D03*
X653338Y1583229D03*
X644677Y1583629D03*
X653338Y1609207D03*
X644677Y1598984D03*
Y1604876D03*
Y1609607D03*
X653338Y1603315D03*
Y1598584D03*
Y1613938D03*
X644677Y1614338D03*
X653338Y1618669D03*
X652000Y1644980D03*
X668649Y60922D03*
X666209Y57297D03*
X665423Y96853D03*
X660678Y91951D03*
X659282Y117261D03*
X666813Y113394D03*
X669462Y110784D03*
X669056Y133298D03*
X666989Y172665D03*
Y180665D03*
X655459Y192421D03*
X667021Y200864D03*
Y212864D03*
Y221864D03*
Y216864D03*
X668778Y252371D03*
X667666Y389153D03*
X665166Y396240D03*
X667666D03*
X665166Y403327D03*
X667666Y403326D03*
X665166Y410413D03*
X667666D03*
Y417499D03*
X665166Y424586D03*
X667666D03*
X665166Y417500D03*
Y431673D03*
Y438760D03*
X667666D03*
Y431673D03*
X665166Y445847D03*
X667666Y467539D03*
X665166Y474626D03*
X667666D03*
X665166Y488799D03*
X667666D03*
Y481712D03*
X665166D03*
Y495886D03*
X667666Y518760D03*
X665166D03*
X667666Y511673D03*
Y532933D03*
X665166D03*
Y540020D03*
Y525846D03*
X667666D03*
X659209Y691851D03*
X662000Y1456451D03*
Y1465913D03*
Y1461182D03*
Y1481267D03*
Y1476536D03*
Y1471805D03*
Y1496621D03*
Y1491890D03*
Y1487159D03*
Y1511976D03*
Y1502514D03*
Y1507245D03*
Y1563544D03*
Y1558813D03*
Y1568275D03*
Y1578898D03*
Y1574167D03*
Y1594253D03*
Y1589522D03*
Y1583629D03*
Y1598984D03*
Y1604876D03*
Y1609607D03*
Y1614338D03*
X679031Y102249D03*
X682048Y109172D03*
X685048D03*
X684055Y106495D03*
X677056Y133298D03*
X671203Y134579D03*
X683789Y146012D03*
X685695Y141228D03*
X672331Y195176D03*
X674831D03*
X677331D03*
X676950Y198883D03*
X680131Y195176D03*
X672191Y203393D03*
X676950Y201683D03*
X674691Y203393D03*
X678379Y206838D03*
X680879D03*
X680375Y238589D03*
X683341Y236121D03*
X683260Y253198D03*
X672466Y389153D03*
Y410413D03*
Y396240D03*
Y403326D03*
X685353Y396718D03*
X672466Y424586D03*
Y417499D03*
Y438760D03*
Y431673D03*
Y467539D03*
Y474626D03*
Y488799D03*
Y481712D03*
Y518760D03*
Y511673D03*
Y525846D03*
Y532933D03*
X681126Y558800D03*
X681190Y562800D03*
X679322Y1461182D03*
Y1456451D03*
Y1465913D03*
X670661Y1460782D03*
Y1465513D03*
Y1470244D03*
Y1476136D03*
X679322Y1481267D03*
Y1476536D03*
Y1471805D03*
X670661Y1480867D03*
X679322Y1487159D03*
X670661Y1496221D03*
Y1485598D03*
Y1491490D03*
X679322Y1496621D03*
Y1491890D03*
X670661Y1500952D03*
Y1506845D03*
X679322Y1511976D03*
Y1502514D03*
Y1507245D03*
X670661Y1511576D03*
Y1516307D03*
X679322Y1558813D03*
X670661Y1563144D03*
X679322Y1563544D03*
Y1578898D03*
Y1574167D03*
Y1568275D03*
X670661Y1572606D03*
Y1578498D03*
Y1567875D03*
X679322Y1583629D03*
X670661Y1587960D03*
Y1593853D03*
Y1583229D03*
X679322Y1594253D03*
Y1589522D03*
Y1604876D03*
Y1609607D03*
X670661Y1603315D03*
Y1598584D03*
Y1609207D03*
X679322Y1598984D03*
Y1614338D03*
X670661Y1618669D03*
Y1613938D03*
X672000Y1644980D03*
X690073Y44662D03*
X697387Y53619D03*
X695099Y109410D03*
X687799Y116497D03*
X692599D03*
X695099D03*
X699799Y116496D03*
Y109410D03*
Y102323D03*
X687799Y123584D03*
X695099Y123583D03*
X692599Y123584D03*
X687799Y130670D03*
X692599D03*
X695099D03*
X699799Y123583D03*
Y130670D03*
X687799Y137757D03*
X692599D03*
X699799Y137756D03*
X688583Y150847D03*
X696331Y213539D03*
X698012Y238714D03*
X689777Y238689D03*
X690551Y247292D03*
X699188Y656321D03*
X702086Y678462D03*
X690449Y814406D03*
X696645Y1461183D03*
Y1456452D03*
Y1465914D03*
X687984Y1460782D03*
Y1465513D03*
Y1470244D03*
Y1476136D03*
X696645Y1481268D03*
Y1471806D03*
Y1476537D03*
X687984Y1480867D03*
X696645Y1491891D03*
X687984Y1496221D03*
Y1485598D03*
Y1491490D03*
X696645Y1496622D03*
Y1487160D03*
Y1511977D03*
Y1502515D03*
Y1507246D03*
X687984Y1511576D03*
Y1500952D03*
Y1506845D03*
Y1516307D03*
X696645Y1558813D03*
Y1563544D03*
X687984Y1563144D03*
X696645Y1574167D03*
Y1578898D03*
X687984Y1572606D03*
Y1578498D03*
X696645Y1568275D03*
X687984Y1567875D03*
Y1583229D03*
X696645Y1589522D03*
Y1594253D03*
X687984Y1587960D03*
Y1593853D03*
X696645Y1583629D03*
Y1598984D03*
Y1609607D03*
X687984Y1603315D03*
Y1598584D03*
Y1609207D03*
X696645Y1604876D03*
X687984Y1613938D03*
X696645Y1614338D03*
X687984Y1618669D03*
X692000Y1644980D03*
X717387Y53619D03*
X708261Y82984D03*
Y80384D03*
Y77784D03*
Y75184D03*
X710815Y92849D03*
X708261Y85584D03*
X717775Y103037D03*
X707799Y102323D03*
X708051Y109410D03*
Y116496D03*
X717909D03*
Y109410D03*
X708223Y124576D03*
X717909Y130670D03*
Y123583D03*
X709276Y130670D03*
X714500Y137756D03*
X709271D03*
X716544Y228726D03*
Y231226D03*
Y226226D03*
Y223726D03*
X713162Y434493D03*
X711764Y445873D03*
X718691Y465492D03*
Y472579D03*
X716191D03*
X711391D03*
X716191Y479666D03*
X718691D03*
X711391D03*
Y486752D03*
X716191D03*
X718691D03*
X711391Y493839D03*
X716191D03*
Y516713D03*
Y523800D03*
X718691D03*
X711391D03*
Y516713D03*
X718691D03*
Y509626D03*
Y530886D03*
X716191D03*
Y537973D03*
X711391Y530886D03*
Y537973D03*
Y566752D03*
X718691Y559665D03*
Y566752D03*
X716191D03*
X711391Y573839D03*
X718691D03*
X716191D03*
X711391Y588013D03*
X718691Y588012D03*
X716191Y588013D03*
X718691Y580926D03*
X716191D03*
X711391D03*
X716191Y602186D03*
X711391D03*
X718691Y602185D03*
Y595099D03*
X711391D03*
X716191D03*
X711391Y609272D03*
X716191D03*
X718691D03*
X716191Y616359D03*
X711391D03*
X711328Y653821D03*
X705776Y678519D03*
X716623Y702463D03*
X703600Y702212D03*
X703680Y697094D03*
X710196Y707562D03*
X712901Y821600D03*
X712000Y1644980D03*
X735192Y94017D03*
X731192D03*
X734921Y101701D03*
X725909Y102323D03*
Y116496D03*
Y109410D03*
X728667Y104249D03*
Y107649D03*
X725909Y130670D03*
Y123583D03*
Y137756D03*
X733233Y151540D03*
X736750Y188727D03*
X727000Y228961D03*
X730707Y226141D03*
X727000Y226461D03*
X733507Y226141D03*
X727000Y223661D03*
X734969Y229286D03*
X727000Y231461D03*
X733450Y236611D03*
X730950D03*
X734969Y231786D03*
X733152Y248891D03*
X730652D03*
X733404Y285690D03*
X720090Y293796D03*
X722590D03*
X728104Y288190D03*
X730604Y285690D03*
X728104D03*
X730604Y288190D03*
X733404D03*
X734606Y379562D03*
X732035Y442606D03*
X731952Y446606D03*
X724362Y504731D03*
X722473Y693718D03*
X723177Y728219D03*
X721163Y738981D03*
X733000Y816000D03*
X732713Y853890D03*
X722600Y869600D03*
X728503Y891692D03*
X736452Y890548D03*
X728692Y886653D03*
X724707Y893143D03*
X722400Y942500D03*
X728846Y948331D03*
X732000Y1644980D03*
X736242Y5374D03*
X735555Y24773D03*
Y44773D03*
X748269Y84140D03*
Y76140D03*
Y80140D03*
X743201Y94017D03*
X739192D03*
X750714Y117557D03*
X745722D03*
X740312Y115401D03*
Y110445D03*
X735320D03*
Y115401D03*
X742471Y103783D03*
X745722Y131731D03*
Y122513D03*
X740312Y129574D03*
Y124618D03*
X735320D03*
Y129574D03*
X750714Y131731D03*
Y122513D03*
Y136687D03*
X745722D03*
X748813Y146461D03*
X747715Y152367D03*
X749415Y180572D03*
Y185165D03*
X743383Y184619D03*
X736883Y191941D03*
X745363Y206760D03*
X738662Y224712D03*
Y222212D03*
X735950Y236611D03*
X735652Y248891D03*
X738577Y256535D03*
X746577D03*
X747607Y279208D03*
X751711Y281307D03*
X741630Y290755D03*
X737630D03*
X745630D03*
X750393Y451677D03*
Y454177D03*
X741992Y763480D03*
X742000Y768137D03*
X743428Y772418D03*
X741993Y775909D03*
X738707Y987952D03*
X742407Y988452D03*
X745673Y1007009D03*
X743062Y1004460D03*
X742655Y1445733D03*
X751140Y1581335D03*
X740640Y1586885D03*
X748924Y1617709D03*
X735878Y1617010D03*
X747590Y1627871D03*
X755145Y3000D03*
X765847Y55513D03*
X763040Y91951D03*
X762065Y117040D03*
X753638Y103621D03*
X754098Y180527D03*
X757821Y192421D03*
X754053Y185121D03*
X756201Y288345D03*
Y290845D03*
X753701Y288345D03*
Y290845D03*
Y293645D03*
X756201D03*
X766344Y377912D03*
X758038Y381143D03*
X766344Y381912D03*
X752341Y407148D03*
X756800Y403824D03*
X758381Y395391D03*
X766344Y397912D03*
X752893Y451677D03*
Y454177D03*
X766433Y1583713D03*
X767310Y1599164D03*
X756358Y1616917D03*
X752150Y1627871D03*
X762776Y1629415D03*
X752000Y1644980D03*
X775145Y3000D03*
X771011Y60922D03*
X781393Y102249D03*
X767929Y96890D03*
X771824Y110784D03*
X777393Y102249D03*
X773393D03*
X769175Y113394D03*
X779418Y133298D03*
X771960Y130898D03*
X773565Y134579D03*
X769351Y172665D03*
Y180665D03*
X779693Y195176D03*
X779312Y198883D03*
X777193Y195176D03*
X782493D03*
X774693D03*
X780741Y206838D03*
X783241D03*
X777053Y203393D03*
X779312Y201683D03*
X774553Y203393D03*
X769383Y200864D03*
Y212864D03*
Y221864D03*
Y216864D03*
X782737Y238589D03*
X771140Y252371D03*
X784118Y303962D03*
X771941Y311740D03*
X780575Y471484D03*
X775584Y466528D03*
X780575D03*
X775583Y471484D03*
X780575Y480701D03*
X775583D03*
Y485657D03*
X780575D03*
Y510661D03*
X775583Y515617D03*
X780575D03*
X775583Y510661D03*
X780575Y524835D03*
Y529791D03*
X775583Y524835D03*
Y529791D03*
X780575Y560701D03*
Y565657D03*
X775583Y560701D03*
Y565657D03*
Y579830D03*
X780575D03*
X775583Y574874D03*
X780575D03*
X775583Y589047D03*
X780575D03*
Y594003D03*
X775583D03*
Y603221D03*
X780575D03*
X775583Y608177D03*
X780575D03*
X777749Y1431432D03*
Y1435432D03*
Y1439432D03*
X778428Y1455156D03*
X777033Y1595215D03*
X781545Y1602835D03*
X774658Y1601012D03*
X778045Y1622545D03*
X782289Y1620109D03*
X773822Y1627418D03*
X772000Y1644980D03*
X791129Y4469D03*
X792490Y24773D03*
Y44773D03*
X799811Y53597D03*
X784410Y109172D03*
X787410D03*
X794961Y116497D03*
X797461D03*
X790161D03*
X786417Y106495D03*
X797461Y109410D03*
Y123583D03*
X794961Y123584D03*
X790161D03*
X794961Y130670D03*
X797461D03*
X790161D03*
X794961Y137757D03*
X790161D03*
X788057Y141228D03*
X786151Y146012D03*
X793221Y140296D03*
X790945Y150847D03*
X798693Y213539D03*
X792913Y247292D03*
X792139Y238689D03*
X785703Y236121D03*
X785622Y253198D03*
X785985Y473640D03*
X790977D03*
X785985Y487813D03*
X790977D03*
X785985Y478596D03*
X790977D03*
X785985Y492769D03*
X790977D03*
Y517774D03*
Y522730D03*
X785985Y517774D03*
Y522730D03*
Y531947D03*
Y536903D03*
X790977Y531947D03*
Y536903D03*
Y567813D03*
X785985Y572769D03*
X790977D03*
X785985Y567813D03*
X790977Y581987D03*
Y586943D03*
X785985Y581987D03*
Y586943D03*
X790977Y601116D03*
X785985D03*
Y596160D03*
X790977D03*
Y615289D03*
Y610333D03*
X785985Y615289D03*
Y610333D03*
X792183Y1334030D03*
Y1331230D03*
X789383Y1334030D03*
Y1331230D03*
X798601Y1431673D03*
X793288Y1450918D03*
X793744Y1437159D03*
X799057Y1456016D03*
X787447Y1593586D03*
X791610Y1593708D03*
X793564Y1642682D03*
X810623Y77784D03*
Y82984D03*
Y80384D03*
Y75184D03*
X813177Y92849D03*
X810623Y85584D03*
X810161Y102323D03*
X810413Y109410D03*
Y116496D03*
X802161D03*
Y109410D03*
Y102323D03*
X810585Y124576D03*
X811638Y130670D03*
X802161D03*
Y123583D03*
X811633Y137756D03*
X802161D03*
X800374Y238714D03*
X815840Y456060D03*
X812661Y810032D03*
X813000Y805000D03*
X813548Y814000D03*
X815500Y824000D03*
X816016Y838036D03*
X814299Y840877D03*
X813887Y835146D03*
X812440Y862306D03*
X812575Y880834D03*
X812219Y883586D03*
X812811Y908162D03*
X809682Y1133284D03*
X800627Y1392748D03*
X806318Y1401661D03*
X812901Y1432804D03*
X815901D03*
X810059Y1432778D03*
X809986Y1438785D03*
X812986D03*
X815986D03*
X809986Y1441485D03*
X812986D03*
X815986D03*
X812901Y1435504D03*
X815901D03*
X810001D03*
X806874Y1447457D03*
X812474D03*
X806874Y1452587D03*
Y1457717D03*
X812474D03*
X815096Y1464387D03*
X803057Y1456016D03*
X801057Y1458016D03*
X812009Y1473432D03*
Y1470432D03*
X815096Y1467387D03*
X812096Y1479587D03*
Y1476587D03*
X815096Y1473387D03*
Y1479587D03*
Y1476587D03*
Y1470387D03*
X801354Y1478681D03*
X811457Y1639797D03*
X819811Y53597D03*
X820137Y103037D03*
X820271Y116496D03*
Y109410D03*
X828271Y116496D03*
Y109410D03*
Y102323D03*
X831029Y104249D03*
Y107649D03*
X820271Y130670D03*
Y123583D03*
X828271Y130670D03*
Y123583D03*
X816637Y137756D03*
X828271D03*
X829362Y231461D03*
Y228961D03*
Y226461D03*
Y223661D03*
X818906Y228726D03*
Y231226D03*
Y226226D03*
Y223726D03*
X829381Y348036D03*
X818840Y456060D03*
X829496Y676793D03*
X829784Y705489D03*
X823670Y710542D03*
X824500Y760500D03*
X830014Y833046D03*
X817139Y890330D03*
X825508Y913869D03*
X818031Y907747D03*
X822462Y915095D03*
X818347Y939610D03*
X828193Y949324D03*
X828964Y977780D03*
X828385Y1120599D03*
X817006Y1133027D03*
X822006Y1130208D03*
X816648Y1377608D03*
X824901Y1427404D03*
X827901D03*
X821901D03*
X818901Y1430104D03*
X821901D03*
X830901D03*
X827901D03*
X824901D03*
Y1432804D03*
X827901D03*
X830901D03*
X821901D03*
X818901D03*
X824901Y1435504D03*
X827901D03*
X821901D03*
X818901D03*
X821986Y1441485D03*
X818986D03*
Y1438785D03*
X821986D03*
X817974Y1447457D03*
Y1452587D03*
Y1457717D03*
X818096Y1464387D03*
X821096D03*
X818096Y1473387D03*
X821096D03*
X824096D03*
X818096Y1479587D03*
X821096D03*
X824096D03*
X818096Y1476587D03*
X821096D03*
X824096D03*
X818096Y1467387D03*
Y1470387D03*
X821096D03*
Y1467387D03*
X824096D03*
Y1470387D03*
X831457Y1639797D03*
X838606Y5374D03*
X837919Y24773D03*
Y44773D03*
X841554Y94017D03*
X837554D03*
X845563D03*
X833554D03*
X837283Y101701D03*
X837682Y110445D03*
Y115401D03*
X848084Y117557D03*
X842674Y115401D03*
Y110445D03*
X844833Y103783D03*
X842674Y129574D03*
Y124618D03*
X837682D03*
Y129574D03*
X848084Y131731D03*
Y122513D03*
Y136687D03*
X839112Y188727D03*
X839245Y191941D03*
X845745Y184619D03*
X847725Y206760D03*
X837331Y229286D03*
X841024Y224712D03*
Y222212D03*
X833069Y226141D03*
X835869D03*
X835812Y236611D03*
X838312D03*
X833312D03*
X837331Y231786D03*
X833014Y248891D03*
X848939Y256535D03*
X840939D03*
X838014Y248891D03*
X835514D03*
X839573Y325327D03*
X833269Y506683D03*
X838152Y700215D03*
X836078Y709619D03*
X845654Y895437D03*
X848792Y896472D03*
X836066Y894955D03*
X841274Y914060D03*
X843315Y916612D03*
X839122Y939655D03*
X835431Y977775D03*
X839744Y1444959D03*
Y1440859D03*
Y1448959D03*
X846844Y1454334D03*
X837685Y1453196D03*
X839744Y1457959D03*
Y1461959D03*
X850145Y3000D03*
X850631Y84140D03*
Y80140D03*
Y76140D03*
X864006Y117261D03*
X853076Y117557D03*
X856000Y103621D03*
X853076Y131731D03*
Y122513D03*
Y136687D03*
X851777Y180572D03*
X856460Y180527D03*
X860183Y192421D03*
X851777Y185165D03*
X856415Y185121D03*
X858169Y495032D03*
X861663Y646653D03*
X855300Y646819D03*
X859199Y744517D03*
X849088Y951081D03*
X850686Y1006923D03*
X853449Y1007048D03*
X863944Y1432359D03*
Y1429359D03*
X860944Y1432359D03*
X857944Y1429359D03*
X860944D03*
Y1426359D03*
X857944D03*
X863944D03*
X857944Y1432359D03*
X863944Y1435359D03*
Y1441359D03*
Y1438359D03*
X860944Y1441359D03*
X857944Y1435359D03*
X860944D03*
X857944Y1441359D03*
Y1438359D03*
X860944D03*
X859071Y1447459D03*
X864671D03*
X859071Y1452589D03*
Y1457719D03*
X864671D03*
X864644Y1464759D03*
X861644D03*
X855644D03*
X858644D03*
Y1467759D03*
X855644Y1470759D03*
X858644D03*
X864644Y1467759D03*
Y1470759D03*
X861644Y1467759D03*
Y1470759D03*
X855644Y1467759D03*
Y1473759D03*
X858644D03*
X864644D03*
X861644D03*
X855644Y1476759D03*
X858644D03*
X864644D03*
X861644D03*
X851457Y1639797D03*
X873373Y60922D03*
X868209Y55513D03*
X870395Y96738D03*
X865402Y91951D03*
X871713Y172665D03*
Y180665D03*
Y176665D03*
X871745Y200864D03*
Y212864D03*
Y204864D03*
Y216864D03*
Y221864D03*
X873733Y357844D03*
X867093Y554703D03*
X866938Y549771D03*
X867093Y586828D03*
Y574703D03*
X876351Y605023D03*
Y608523D03*
X879135Y632552D03*
X876286Y698970D03*
X877616Y749484D03*
X869325Y761259D03*
X871600Y898584D03*
X876628Y918042D03*
X868908Y933640D03*
X867199Y949372D03*
X865830Y961600D03*
X865973Y978187D03*
X873824Y1071604D03*
X871224D03*
X876424D03*
Y1074104D03*
X871224D03*
X873824D03*
X868624Y1071604D03*
Y1074104D03*
X870057Y1091604D03*
X875257D03*
Y1089104D03*
X870057D03*
X872657D03*
X880115Y1084666D03*
X867457Y1091604D03*
Y1089104D03*
X872657Y1091604D03*
X871624Y1213314D03*
X874624D03*
X871624Y1221714D03*
Y1218914D03*
Y1216114D03*
X874624Y1221714D03*
Y1218914D03*
Y1216114D03*
X872440Y1230083D03*
Y1227583D03*
X871624Y1224514D03*
X874624D03*
X872440Y1234483D03*
Y1236983D03*
X878004Y1224406D03*
X872440Y1243883D03*
Y1241383D03*
Y1248283D03*
Y1250783D03*
X883142Y1259935D03*
X875700Y1299700D03*
X872944Y1432359D03*
Y1429359D03*
Y1426359D03*
X869944Y1432359D03*
Y1429359D03*
Y1426359D03*
X866944Y1432359D03*
Y1429359D03*
Y1426359D03*
X872944Y1435359D03*
Y1441359D03*
Y1438359D03*
X869944Y1435359D03*
X866944D03*
X869944Y1441359D03*
Y1438359D03*
X866944Y1441359D03*
Y1438359D03*
X870171Y1447459D03*
X881244Y1448859D03*
Y1440859D03*
X870171Y1452589D03*
Y1457719D03*
X867644Y1464759D03*
X870644D03*
X881244Y1464859D03*
Y1453059D03*
X867644Y1467759D03*
X870644D03*
X867644Y1470759D03*
X870644D03*
X867644Y1473759D03*
X870644D03*
X867644Y1476759D03*
X870644D03*
X881244Y1476859D03*
X871457Y1639797D03*
X886011Y154100D03*
X895780Y237517D03*
Y232634D03*
X886261Y252090D03*
X885741Y261150D03*
X886026Y346584D03*
X892931Y534093D03*
X891449Y547363D03*
X893949D03*
X891933Y618143D03*
X883309Y666608D03*
X892461Y666671D03*
X886304Y666650D03*
X889525Y722060D03*
X883126Y766124D03*
X883413Y759855D03*
X888545Y785528D03*
X888514Y797602D03*
X889763Y788159D03*
X889178Y905619D03*
X882779Y1074104D03*
Y1071604D03*
X887979Y1074104D03*
X885379D03*
X890579D03*
Y1071604D03*
X885379D03*
X887979D03*
X882615Y1084666D03*
X892856Y1102760D03*
X888650Y1199622D03*
X893190Y1208069D03*
X893328Y1212887D03*
X894887Y1227209D03*
X891003Y1292765D03*
X890738Y1311132D03*
X889944Y1457959D03*
X889244Y1460859D03*
Y1472859D03*
Y1468859D03*
X891457Y1639797D03*
X898813Y146461D03*
X897715Y152367D03*
X898851Y231496D03*
Y238583D03*
Y245669D03*
X910977Y238583D03*
X898851Y259843D03*
X898576Y253056D03*
X910977Y252756D03*
Y257480D03*
X898851Y274016D03*
X910977Y266929D03*
X898851D03*
X912786Y306697D03*
X901848Y307782D03*
X910076Y304843D03*
X905120D03*
X913206Y336489D03*
X906996Y530707D03*
X899931Y534093D03*
X911630Y543998D03*
X908730Y619120D03*
X913686D03*
X899898Y619040D03*
X904854D03*
X900753Y656925D03*
X910753Y715864D03*
X908699Y709387D03*
X913247Y714204D03*
X902841Y703665D03*
X908920Y905630D03*
X911355Y944909D03*
X909811Y962400D03*
X913005Y969605D03*
X912690Y994350D03*
X908422Y1023103D03*
X908856Y1017677D03*
X908799Y1096659D03*
X901940Y1236799D03*
Y1229899D03*
Y1232399D03*
Y1246199D03*
Y1243699D03*
Y1239299D03*
X899944Y1432359D03*
X908944Y1426359D03*
Y1429359D03*
Y1432359D03*
X911944Y1426359D03*
Y1429359D03*
Y1432359D03*
X905944Y1426359D03*
X899944D03*
X902944D03*
Y1429359D03*
X899944D03*
X902944Y1432359D03*
X905944Y1429359D03*
Y1432359D03*
X902944Y1438359D03*
X899944D03*
Y1441359D03*
X902944Y1435359D03*
X899944D03*
X908944Y1438359D03*
Y1441359D03*
X911944Y1438359D03*
Y1441359D03*
X902944D03*
X905944Y1438359D03*
Y1441359D03*
X908944Y1435359D03*
X911944D03*
X905944D03*
X912171Y1447459D03*
X906671D03*
X901071D03*
X912171Y1457719D03*
Y1452589D03*
X906671Y1457719D03*
X901071D03*
Y1452589D03*
X908370Y1464583D03*
X905370D03*
X899370D03*
X902370D03*
X911370D03*
X905370Y1476583D03*
X908370D03*
X902370D03*
X899370D03*
X905370Y1473583D03*
X908370D03*
X902370D03*
X899370D03*
X902370Y1467583D03*
X899370Y1470583D03*
X902370D03*
X908370Y1467583D03*
Y1470583D03*
X905370Y1467583D03*
Y1470583D03*
X899370Y1467583D03*
X911370Y1476583D03*
Y1473583D03*
Y1467583D03*
Y1470583D03*
X911457Y1639797D03*
X930145Y3000D03*
X931393Y102249D03*
X919175Y113394D03*
X921824Y110784D03*
X923393Y102249D03*
X927393D03*
X921418Y133298D03*
X929418D03*
X923565Y134579D03*
X925359Y180347D03*
X927859D03*
X925219Y188564D03*
X929978Y186854D03*
X927719Y188564D03*
X929978Y184054D03*
X919606Y231000D03*
X919577Y245669D03*
Y233858D03*
X919682Y236921D03*
X919577Y259843D03*
Y255118D03*
X919729Y274580D03*
X917906Y321670D03*
X922629Y336609D03*
X922198Y342051D03*
X917858Y331453D03*
X924999Y477948D03*
X924600Y533706D03*
X925949Y612363D03*
Y608863D03*
X915800Y629700D03*
X918300D03*
X915194Y666671D03*
X920090Y666714D03*
X917286Y679625D03*
X928353Y686342D03*
X929181Y895029D03*
X914193Y945318D03*
X924487Y951244D03*
X928227Y951125D03*
X921364Y951251D03*
X918265Y969745D03*
X923289Y965780D03*
X926796Y966297D03*
X916749Y1084659D03*
X916992Y1076659D03*
X914944Y1426359D03*
Y1429359D03*
Y1432359D03*
Y1438359D03*
Y1441359D03*
Y1435359D03*
X914370Y1464583D03*
X925697Y1460109D03*
X914370Y1476583D03*
Y1473583D03*
Y1467583D03*
Y1470583D03*
X924803Y1474743D03*
X925435Y1478114D03*
X926044Y1545370D03*
Y1542370D03*
X929094Y1542353D03*
Y1545353D03*
X926041Y1554503D03*
Y1551503D03*
Y1548503D03*
Y1557503D03*
Y1560503D03*
X941129Y4469D03*
X942490Y24773D03*
Y44773D03*
X944961Y116497D03*
X934410Y109172D03*
X936417Y106495D03*
X937410Y109172D03*
X940161Y116497D03*
Y123584D03*
X944961D03*
X940161Y130670D03*
X944961D03*
X940161Y137757D03*
X944961D03*
X936151Y146012D03*
X938057Y141228D03*
X940945Y150847D03*
X930359Y180347D03*
X933159D03*
X931407Y192009D03*
X933907D03*
X938125Y230891D03*
X942805Y223860D03*
X936369Y221292D03*
X940158Y245707D03*
X946064Y252998D03*
X939606Y310521D03*
X939653Y317474D03*
X940924Y328959D03*
X936608Y326058D03*
X945120Y326441D03*
X930398Y342050D03*
X936453Y345336D03*
X945599Y345383D03*
X940972Y338238D03*
X943663Y355674D03*
X944900Y363700D03*
X940600Y370600D03*
X931627Y557641D03*
Y569578D03*
X931620Y584417D03*
X931627Y581578D03*
Y577578D03*
Y573578D03*
X931594Y599420D03*
X931647Y593271D03*
X931578Y590669D03*
X945626Y789761D03*
X941916Y808965D03*
X936450Y858327D03*
X937551Y860801D03*
X942634Y886520D03*
X932300Y890200D03*
X936371Y951484D03*
X940716Y951733D03*
X946363Y951179D03*
X935255Y962725D03*
X935601Y1221714D03*
Y1218914D03*
Y1216114D03*
Y1213314D03*
X938601Y1221714D03*
Y1218914D03*
Y1216114D03*
Y1213314D03*
X936417Y1234483D03*
Y1236983D03*
Y1230083D03*
Y1227583D03*
X935601Y1224514D03*
X938601D03*
X941981Y1224406D03*
X936417Y1243883D03*
Y1241383D03*
Y1248283D03*
Y1250783D03*
X947119Y1259935D03*
X943725Y1430744D03*
Y1427744D03*
X934725Y1430744D03*
X940725Y1427744D03*
Y1430744D03*
X934725Y1427744D03*
X937725D03*
Y1430744D03*
X943725Y1433744D03*
Y1439744D03*
Y1436744D03*
X940725Y1433744D03*
Y1439744D03*
Y1436744D03*
X934725Y1433744D03*
X937725D03*
X934725Y1439744D03*
X937725D03*
X934725Y1436744D03*
X937725D03*
X930441Y1455039D03*
Y1458039D03*
Y1464039D03*
Y1461039D03*
Y1467039D03*
X938670Y1510528D03*
X941270D03*
Y1505328D03*
X938670D03*
X940170Y1507928D03*
X943870Y1510528D03*
Y1505328D03*
X945370Y1507928D03*
X942770D03*
X935094Y1542353D03*
X932094D03*
X935094Y1545353D03*
X932094D03*
X938094Y1542353D03*
Y1545353D03*
X941094Y1542353D03*
X944094D03*
X941094Y1545353D03*
X944094D03*
X931457Y1639797D03*
X949811Y53597D03*
X960623Y82984D03*
Y77784D03*
Y80384D03*
Y75184D03*
Y85584D03*
X960161Y102323D03*
X960413Y109410D03*
Y116496D03*
X947461Y116497D03*
X952161Y116496D03*
Y109410D03*
Y102323D03*
X947461Y109410D03*
X961638Y130670D03*
X947461D03*
X952161D03*
Y123583D03*
X947461D03*
X961633Y137756D03*
X952161D03*
X949359Y198710D03*
X949443Y208206D03*
X951040Y223885D03*
X956348Y356371D03*
X952170Y356131D03*
X958823Y362802D03*
X954888Y369513D03*
X948400Y370045D03*
X955816Y473419D03*
X958736Y482165D03*
X949823Y491982D03*
X951195Y727165D03*
X952681Y735256D03*
X951151Y730111D03*
X956323Y748412D03*
X957474Y764426D03*
X953837Y763025D03*
X955086Y779798D03*
X956051Y793937D03*
X955225Y788984D03*
X957379Y826586D03*
X954760Y826734D03*
X952738Y886624D03*
X964280Y927777D03*
X958567Y927654D03*
X946642Y991361D03*
X956833Y1102760D03*
X952627Y1199622D03*
X957305Y1212887D03*
X957167Y1208069D03*
X958864Y1227209D03*
X952070Y1367717D03*
X949070D03*
X946725Y1427744D03*
Y1430744D03*
X949725D03*
Y1427744D03*
X960883Y1427997D03*
Y1430997D03*
X946725Y1433744D03*
X949725D03*
X946725Y1439744D03*
X949725D03*
X946725Y1436744D03*
X949725D03*
X960883Y1433997D03*
Y1436997D03*
Y1439997D03*
X956238Y1455139D03*
Y1458139D03*
Y1461139D03*
Y1464139D03*
X952676Y1461039D03*
Y1464039D03*
Y1458039D03*
Y1455039D03*
X956238Y1467139D03*
Y1469902D03*
X952676Y1467039D03*
X946470Y1510528D03*
Y1505328D03*
X956035Y1545333D03*
X959035D03*
X953035D03*
X950035D03*
X959035Y1542333D03*
X956035D03*
X953035D03*
X950035D03*
X947094Y1545353D03*
Y1542353D03*
X951457Y1639797D03*
X969811Y53597D03*
X963177Y92849D03*
X978271Y109410D03*
Y102323D03*
X970137Y103037D03*
X970271Y116496D03*
Y109410D03*
X978271Y116496D03*
X970271Y130670D03*
Y123583D03*
X978271Y130670D03*
Y123583D03*
X963360Y121459D03*
X966347Y137756D03*
X978271D03*
X968906Y223726D03*
Y228726D03*
Y231226D03*
X979362Y223661D03*
X968906Y226226D03*
X976763Y307303D03*
X977150Y331972D03*
Y338972D03*
X976397Y473045D03*
X963187Y667620D03*
X973138Y667621D03*
X968589Y722434D03*
X970839Y729923D03*
X965042Y722234D03*
X971081Y722637D03*
X978352Y730766D03*
X978059Y747438D03*
X973450Y747280D03*
X976764Y786563D03*
X977218Y802178D03*
X968319Y826191D03*
X978214Y821224D03*
X967337Y828901D03*
X970040Y842903D03*
X969309Y839334D03*
X975925Y854783D03*
X971443Y938828D03*
X972776Y1096659D03*
X965917Y1236799D03*
Y1229899D03*
Y1232399D03*
Y1246199D03*
Y1243699D03*
Y1239299D03*
X978857Y1360945D03*
X963883Y1430997D03*
Y1427997D03*
X966883Y1430997D03*
Y1427997D03*
X969883D03*
Y1430997D03*
X975883Y1427997D03*
Y1430997D03*
X972883D03*
Y1427997D03*
X963883Y1433997D03*
X966883D03*
X969883D03*
X963883Y1436997D03*
Y1439997D03*
X966883Y1436997D03*
Y1439997D03*
X969883Y1436997D03*
Y1439997D03*
X975883Y1433997D03*
X972883D03*
X975883Y1436997D03*
X972883D03*
X975883Y1439997D03*
X972883D03*
X971467Y1509515D03*
X974067D03*
X972567Y1512115D03*
X969967D03*
X976667Y1509515D03*
X977767Y1506915D03*
X975167D03*
X969967D03*
X972567D03*
X975167Y1512115D03*
X977767D03*
X971140Y1514693D03*
X968540D03*
X973740D03*
X976340D03*
X977547Y1546081D03*
X974547D03*
X971547D03*
X971457Y1639797D03*
X988606Y5374D03*
X987919Y24773D03*
Y44773D03*
X983554Y94017D03*
X987554D03*
X991554D03*
X987283Y101701D03*
X987682Y115401D03*
X992674D03*
X987682Y110445D03*
X994833Y103783D03*
X981029Y104249D03*
Y107649D03*
X992674Y124618D03*
X987682D03*
Y129574D03*
X992674D03*
X985595Y151540D03*
X989245Y191941D03*
X989112Y188727D03*
X987331Y229286D03*
X991024Y224712D03*
Y222212D03*
X983069Y226141D03*
X985869D03*
X979362Y231461D03*
Y228961D03*
Y226461D03*
X987331Y231786D03*
X985812Y236611D03*
X988312D03*
X983312D03*
X983014Y248891D03*
X988014D03*
X985514D03*
X990939Y256535D03*
X987055Y320273D03*
X990420Y340454D03*
Y337954D03*
X980045Y366559D03*
X984307Y748432D03*
X987461Y745796D03*
X981876Y745179D03*
X987394Y787490D03*
X984892Y868720D03*
X987790Y896596D03*
X995133Y888503D03*
X979498Y907500D03*
X988461Y1013841D03*
X988240Y1020015D03*
Y1016923D03*
Y1023968D03*
X984909Y1081071D03*
X983751Y1078675D03*
X980969Y1076659D03*
X980726Y1084659D03*
X990613Y1324248D03*
Y1327048D03*
X993413Y1324248D03*
Y1327048D03*
X981857Y1360945D03*
X980501Y1369685D03*
X983501D03*
X978944Y1413859D03*
X981944D03*
X986949Y1430997D03*
Y1427997D03*
X983949D03*
X989949Y1430997D03*
Y1427997D03*
X983949Y1430997D03*
X992949Y1427997D03*
Y1430997D03*
X986949Y1433997D03*
X983949D03*
X989949D03*
X992949D03*
X986949Y1436997D03*
X983949D03*
X986949Y1439997D03*
X983949D03*
X989949Y1436997D03*
Y1439997D03*
X992949Y1436997D03*
Y1439997D03*
X979538Y1464039D03*
Y1461039D03*
Y1458039D03*
Y1455039D03*
Y1467039D03*
Y1469802D03*
X979267Y1509515D03*
X984467D03*
X981867D03*
X985567Y1512115D03*
Y1506915D03*
X980367D03*
X982967D03*
Y1512115D03*
X980367D03*
X989667Y1509515D03*
X992267D03*
X987067D03*
X988167Y1512115D03*
X990767D03*
Y1506915D03*
X988167D03*
X984140Y1514693D03*
X981540D03*
X978940D03*
X986740D03*
X989340D03*
X986773Y1546081D03*
X983773D03*
X980773D03*
X991457Y1639797D03*
X1007508Y3000D03*
X1000631Y84140D03*
Y76140D03*
Y80140D03*
X995563Y94017D03*
X1006000Y103621D03*
X998084Y117557D03*
X1003076Y122513D03*
Y131731D03*
X998084Y122513D03*
Y131731D03*
X1001175Y146461D03*
X1003076Y136687D03*
X998084D03*
X1000077Y152367D03*
X1001777Y180572D03*
X1006460Y180527D03*
X1010183Y192421D03*
X1001777Y185165D03*
X1006415Y185121D03*
X995745Y184619D03*
X997725Y206760D03*
X998939Y256535D03*
X1000698Y300276D03*
X1003900Y628700D03*
X1001605Y627605D03*
X1005800Y637600D03*
X1002883Y622521D03*
X1011185Y724519D03*
X1009562Y722438D03*
X1008342Y761735D03*
X1003539Y762632D03*
X1007990Y765899D03*
X1002834Y777394D03*
X1013319Y785929D03*
X1004953Y923995D03*
X1008935Y924007D03*
X996213Y1324248D03*
Y1327048D03*
X1008312Y1363533D03*
X1008452Y1376752D03*
X1008483Y1372734D03*
X1006211Y1397662D03*
X1009338Y1391597D03*
Y1388597D03*
X1008138Y1407186D03*
Y1409986D03*
X1005338Y1407186D03*
Y1409986D03*
X1008138Y1415586D03*
Y1412786D03*
X1005338Y1415586D03*
Y1412786D03*
X1008138Y1418386D03*
X1005338D03*
X998949Y1427997D03*
Y1430997D03*
X995949D03*
Y1427997D03*
X1009981Y1431097D03*
Y1428097D03*
X1006981D03*
Y1431097D03*
X998949Y1433997D03*
X995949D03*
X998949Y1436997D03*
X995949D03*
X998949Y1439997D03*
X995949D03*
X1009981Y1434097D03*
X1006981D03*
X1009981Y1437097D03*
X1006981D03*
X1009981Y1440097D03*
X1006981D03*
X1002538Y1463939D03*
Y1460939D03*
Y1457939D03*
Y1454939D03*
Y1466939D03*
Y1469702D03*
X1008549Y1509815D03*
X1007049Y1507215D03*
X1011149Y1509815D03*
X1009649Y1507215D03*
Y1512415D03*
X1007049D03*
X1008222Y1514993D03*
X1005622D03*
X1010822D03*
X1010606Y1547824D03*
X1007611Y1561247D03*
Y1558247D03*
Y1555247D03*
Y1552247D03*
X1004611Y1561247D03*
Y1558247D03*
Y1555247D03*
Y1552247D03*
X1010659Y1568771D03*
Y1565771D03*
X1010653Y1571669D03*
X1027508Y3000D03*
X1023373Y60922D03*
X1018209Y55513D03*
X1020254Y97068D03*
X1015402Y91951D03*
X1014006Y117261D03*
X1021537Y113394D03*
X1025755Y102249D03*
X1024186Y110784D03*
X1024289Y130898D03*
X1025927Y134579D03*
X1021713Y180665D03*
Y172665D03*
X1027055Y195176D03*
X1026915Y203393D03*
X1021745Y212864D03*
Y200864D03*
Y221864D03*
Y216864D03*
X1023502Y252371D03*
X1016635Y300276D03*
X1012635D03*
X1025749D03*
X1020635D03*
X1012188Y443421D03*
X1018238Y678647D03*
X1018155Y684132D03*
X1021885Y698974D03*
X1022937Y691421D03*
X1014641Y724436D03*
X1012851Y722417D03*
X1026916Y719769D03*
X1013486Y750773D03*
X1015804Y760454D03*
X1026090Y770943D03*
X1013821Y813520D03*
X1014781Y810319D03*
X1013918Y851306D03*
X1022346Y917669D03*
X1029570Y917718D03*
X1027319Y938322D03*
X1011782Y1016591D03*
X1017297Y1102091D03*
X1026606Y1102591D03*
X1023106Y1102091D03*
X1025434Y1320606D03*
X1011829Y1347471D03*
Y1342515D03*
X1015286Y1344924D03*
X1021623Y1373216D03*
X1012338Y1388597D03*
Y1391597D03*
X1015338D03*
Y1388597D03*
X1021338D03*
Y1391597D03*
X1018338D03*
Y1388597D03*
X1027338D03*
Y1391597D03*
X1024338D03*
Y1388597D03*
X1012981Y1431097D03*
Y1428097D03*
X1015981D03*
Y1431097D03*
X1021981Y1428097D03*
Y1431097D03*
X1018981D03*
Y1428097D03*
X1012981Y1434097D03*
X1015981D03*
X1012981Y1437097D03*
Y1440097D03*
X1015981Y1437097D03*
Y1440097D03*
X1021981Y1434097D03*
X1018981D03*
X1021981Y1437097D03*
X1018981D03*
X1021981Y1440097D03*
X1018981D03*
X1025138Y1463839D03*
Y1460839D03*
Y1457839D03*
Y1454839D03*
Y1466839D03*
Y1469602D03*
X1013749Y1509815D03*
X1016349D03*
X1021549D03*
X1018949D03*
X1024149D03*
X1022649Y1507215D03*
X1025249D03*
X1017449D03*
X1020049D03*
X1014849D03*
X1012249D03*
X1026749Y1509815D03*
X1012249Y1512415D03*
X1014849D03*
X1025249D03*
X1022649D03*
X1020049D03*
X1017449D03*
X1013422Y1514993D03*
X1023822D03*
X1021222D03*
X1018622D03*
X1016022D03*
X1026422D03*
X1013606Y1547824D03*
X1016606D03*
X1019606D03*
X1013659Y1568771D03*
X1016659D03*
X1019659D03*
X1013659Y1565771D03*
X1016659D03*
X1019659D03*
X1013653Y1571669D03*
X1016653D03*
X1019653D03*
X1011457Y1639797D03*
X1043492Y4469D03*
X1033755Y102249D03*
X1036772Y109172D03*
X1039772D03*
X1038779Y106495D03*
X1029755Y102249D03*
X1042523Y116497D03*
X1031780Y133298D03*
X1042523Y130670D03*
Y123584D03*
X1038513Y146012D03*
X1040419Y141228D03*
X1042523Y137757D03*
X1043307Y150847D03*
X1032055Y195176D03*
X1031674Y198883D03*
X1029555Y195176D03*
X1034855D03*
X1033103Y206838D03*
X1035603D03*
X1029415Y203393D03*
X1031674Y201683D03*
X1038065Y236121D03*
X1035099Y238589D03*
X1037984Y253198D03*
X1037290Y296293D03*
X1033890D03*
X1045650Y300093D03*
X1029639Y300141D03*
X1029885Y711762D03*
X1038796Y763272D03*
X1043016Y782161D03*
X1038678Y776750D03*
X1043252Y902501D03*
X1039499Y1098758D03*
X1039053Y1117691D03*
X1044553D03*
X1039053Y1130291D03*
X1044553D03*
Y1142891D03*
X1039053D03*
Y1155491D03*
X1044553D03*
Y1168091D03*
X1039053D03*
X1044553Y1180691D03*
X1039053D03*
X1040600Y1210600D03*
X1035384Y1215195D03*
X1029797Y1220921D03*
X1034513Y1333665D03*
X1042586Y1345824D03*
X1030338Y1391597D03*
Y1388597D03*
X1032867Y1431213D03*
Y1428213D03*
X1029867D03*
X1035867Y1431213D03*
Y1428213D03*
X1029867Y1431213D03*
X1038867Y1428213D03*
Y1431213D03*
X1041867D03*
Y1428213D03*
X1032867Y1434213D03*
X1029867D03*
X1035867D03*
X1038867D03*
X1032867Y1437213D03*
X1029867D03*
X1032867Y1440213D03*
X1029867D03*
X1035867Y1437213D03*
Y1440213D03*
X1038867Y1437213D03*
Y1440213D03*
X1041867Y1434213D03*
Y1437213D03*
Y1440213D03*
X1029349Y1509815D03*
X1027849Y1507215D03*
Y1512415D03*
X1031457Y1639797D03*
X1044853Y24773D03*
Y44773D03*
X1052174Y53597D03*
X1049823Y109410D03*
X1054523Y116496D03*
Y109410D03*
Y102323D03*
X1049823Y116497D03*
X1047323D03*
X1049823Y130670D03*
X1047323D03*
Y123584D03*
X1049823Y123583D03*
X1054523Y130670D03*
Y123583D03*
Y137756D03*
X1047323Y137757D03*
X1051055Y213539D03*
X1044501Y238689D03*
X1045275Y247292D03*
X1052736Y238714D03*
X1048695Y280161D03*
X1050164Y302748D03*
X1050076Y305512D03*
X1061387Y343509D03*
X1060679Y356151D03*
X1052367Y402291D03*
X1057359D03*
X1052367Y397335D03*
X1057359D03*
X1054959Y411509D03*
X1049967Y416465D03*
Y411509D03*
X1054959Y425682D03*
X1049967D03*
X1054959Y416465D03*
X1049967Y439855D03*
X1054959Y430638D03*
X1049967D03*
X1054959Y439855D03*
X1049967Y444811D03*
X1054959D03*
X1049967Y468609D03*
X1054959D03*
X1049967Y473565D03*
X1054959D03*
X1049967Y487738D03*
X1054959D03*
X1049967Y482782D03*
X1054959D03*
Y517699D03*
X1049967Y512743D03*
X1054959D03*
X1049967Y517699D03*
Y526916D03*
X1054959Y531872D03*
X1049967D03*
X1054959Y526916D03*
X1044112Y778835D03*
X1055700Y840900D03*
X1053913Y837718D03*
X1048043Y1105091D03*
X1051249Y1290288D03*
X1052221Y1336984D03*
X1044867Y1428213D03*
Y1431213D03*
Y1434213D03*
Y1437213D03*
Y1440213D03*
X1051457Y1639797D03*
X1072174Y53597D03*
X1062985Y82984D03*
Y75184D03*
Y77784D03*
Y80384D03*
X1065539Y92849D03*
X1062985Y85584D03*
X1072499Y103037D03*
X1062523Y102323D03*
X1062775Y109410D03*
Y116496D03*
X1072633D03*
Y109410D03*
X1062947Y124576D03*
X1072633Y130670D03*
Y123583D03*
X1064000Y130670D03*
X1069224Y137756D03*
X1063995D03*
X1071268Y226226D03*
Y223726D03*
Y228726D03*
Y231226D03*
X1076571Y310574D03*
X1060679Y368276D03*
X1060369Y390223D03*
X1065361D03*
X1060369Y395179D03*
Y404396D03*
Y409352D03*
X1065361Y395179D03*
Y404396D03*
Y409352D03*
X1060369Y418569D03*
Y423525D03*
X1065361D03*
Y418569D03*
X1060369Y432743D03*
Y437699D03*
X1065361Y432743D03*
Y437699D03*
X1063113Y455921D03*
X1065361Y489895D03*
X1060369D03*
Y480677D03*
Y475721D03*
X1065361Y480677D03*
Y475721D03*
X1060369Y494851D03*
X1065361D03*
X1060369Y519855D03*
X1065361D03*
Y524811D03*
X1060369D03*
Y538984D03*
Y534028D03*
X1065361Y538984D03*
Y534028D03*
X1062098Y603600D03*
Y619600D03*
Y623600D03*
X1066931Y645389D03*
X1076110Y1029535D03*
X1071641Y1058029D03*
X1071348Y1050503D03*
X1074650Y1070006D03*
X1071457Y1639797D03*
X1090280Y44773D03*
X1089916Y94017D03*
X1085916D03*
X1089645Y101701D03*
X1090044Y110445D03*
Y115401D03*
X1080633Y102323D03*
Y116496D03*
Y109410D03*
X1083391Y104249D03*
Y107649D03*
X1080633Y130670D03*
Y123583D03*
X1090044Y124618D03*
Y129574D03*
X1080633Y137756D03*
X1087957Y151540D03*
X1091607Y191941D03*
X1091474Y188727D03*
X1085431Y226141D03*
X1081724Y226461D03*
X1088231Y226141D03*
X1081724Y223661D03*
X1089693Y229286D03*
X1081724Y231461D03*
Y228961D03*
X1089693Y231786D03*
X1085674Y236611D03*
X1088174D03*
X1090674D03*
X1090376Y248891D03*
X1087876D03*
X1085376D03*
X1088128Y285690D03*
Y288190D03*
X1085328D03*
X1082828Y285690D03*
X1085328D03*
X1082828Y288190D03*
X1092354Y290755D03*
X1077855Y327478D03*
X1077252Y323521D03*
Y318565D03*
X1077855Y332434D03*
X1079863Y345660D03*
X1091031Y374810D03*
X1089788Y550907D03*
X1087288D03*
X1089788Y553407D03*
X1087288D03*
X1078920Y856700D03*
X1079809Y1034386D03*
X1078755Y1031518D03*
X1076868Y1047293D03*
X1079910Y1045264D03*
X1083283Y1526583D03*
X1090876Y1554183D03*
X1086469Y1588435D03*
X1082176Y1600598D03*
X1090904Y1599047D03*
X1085474Y1629028D03*
X1092000Y1644980D03*
X1102993Y84140D03*
Y76140D03*
Y80140D03*
X1097925Y94017D03*
X1093916D03*
X1100446Y117557D03*
X1095036Y115401D03*
Y110445D03*
X1105438Y117557D03*
X1097195Y103783D03*
X1108362Y103621D03*
X1095036Y129574D03*
Y124618D03*
X1105438Y131731D03*
Y122513D03*
X1100446Y131731D03*
Y122513D03*
X1103537Y146461D03*
X1100446Y136687D03*
X1105438D03*
X1102439Y152367D03*
X1104139Y180572D03*
X1108822Y180527D03*
X1104139Y185165D03*
X1108777Y185121D03*
X1098107Y184619D03*
X1100087Y206760D03*
X1093386Y224712D03*
Y222212D03*
X1101301Y256535D03*
X1093301D03*
X1102331Y279208D03*
X1106435Y281307D03*
X1108425Y293645D03*
Y290845D03*
Y288345D03*
X1096354Y290755D03*
X1100354D03*
X1108779Y327705D03*
X1103432Y340544D03*
X1097976Y340477D03*
X1105012Y353504D03*
X1098845Y353404D03*
X1093841Y371335D03*
X1105298Y610400D03*
X1095080Y1513398D03*
X1095250Y1531600D03*
X1100876Y1554183D03*
X1093682Y1582433D03*
X1098498Y1590435D03*
X1104233Y1587983D03*
X1107620Y1603602D03*
X1101474Y1637820D03*
X1093474Y1638213D03*
X1123052Y57511D03*
X1122613Y97042D03*
X1117764Y91951D03*
X1116368Y117261D03*
X1123899Y113394D03*
X1124075Y180665D03*
Y172665D03*
X1112545Y192421D03*
X1124107Y200864D03*
Y212864D03*
Y216864D03*
Y221864D03*
X1110925Y293645D03*
Y290845D03*
Y288345D03*
X1124753Y389153D03*
X1122253Y396240D03*
X1124753D03*
X1122253Y403327D03*
X1124753Y403326D03*
X1122253Y410413D03*
X1124753D03*
X1122253Y424586D03*
X1124753D03*
X1122253Y417500D03*
X1124753Y417499D03*
X1122253Y438760D03*
X1124753D03*
Y431673D03*
X1122253D03*
Y445847D03*
X1124753Y467539D03*
X1122253Y474626D03*
X1124753D03*
X1122253Y488799D03*
X1124753D03*
Y481712D03*
X1122253D03*
Y495886D03*
X1124753Y518760D03*
X1122253D03*
X1124753Y511673D03*
Y532933D03*
X1122253D03*
Y540020D03*
Y525846D03*
X1124753D03*
X1122718Y598857D03*
X1121191Y612555D03*
X1120512Y617332D03*
X1121022Y607750D03*
X1112000Y1644980D03*
X1125735Y60922D03*
X1136117Y102249D03*
X1139134Y109172D03*
X1141141Y106495D03*
X1132117Y102249D03*
X1128117D03*
X1126548Y110784D03*
X1134142Y133298D03*
X1126142D03*
X1140875Y146012D03*
X1128289Y134579D03*
X1134036Y198883D03*
X1134417Y195176D03*
X1131917D03*
X1137217D03*
X1129417D03*
X1137965Y206838D03*
X1134036Y201683D03*
X1131777Y203393D03*
X1129277D03*
X1135465Y206838D03*
X1137461Y238589D03*
X1140427Y236121D03*
X1140346Y253198D03*
X1125864Y252371D03*
X1129553Y389153D03*
Y396240D03*
Y403326D03*
Y410413D03*
Y424586D03*
Y417499D03*
Y431673D03*
Y438760D03*
Y467539D03*
Y474626D03*
Y488799D03*
Y481712D03*
X1126622Y506256D03*
X1129553Y518760D03*
Y511673D03*
Y532933D03*
Y525846D03*
X1139673Y530000D03*
X1138373Y549800D03*
X1138173Y547075D03*
X1138213Y558800D03*
X1138277Y562800D03*
X1129637Y1465913D03*
Y1461182D03*
Y1456451D03*
X1138298Y1465513D03*
Y1460782D03*
X1129637Y1476536D03*
Y1481267D03*
X1138298Y1476136D03*
Y1470244D03*
Y1480867D03*
X1129637Y1471805D03*
Y1496621D03*
X1138298Y1491490D03*
Y1485598D03*
Y1496221D03*
X1129637Y1491890D03*
Y1487159D03*
X1138298Y1500952D03*
Y1511576D03*
X1129637Y1507245D03*
Y1502514D03*
Y1511976D03*
X1138298Y1506845D03*
Y1516307D03*
X1129637Y1563544D03*
Y1558813D03*
X1138298Y1563144D03*
Y1572606D03*
X1129637Y1568275D03*
Y1578898D03*
Y1574167D03*
X1138298Y1567875D03*
Y1578498D03*
X1129637Y1583629D03*
Y1594253D03*
Y1589522D03*
X1138298Y1583229D03*
Y1593853D03*
Y1587960D03*
Y1598584D03*
Y1603315D03*
X1129637Y1609607D03*
Y1598984D03*
Y1604876D03*
X1138298Y1609207D03*
X1129637Y1614338D03*
X1138298Y1613938D03*
Y1618669D03*
X1132000Y1644980D03*
X1147214Y44773D03*
X1154535Y53597D03*
X1142134Y109172D03*
X1156885Y116496D03*
Y102323D03*
Y109410D03*
X1152185D03*
Y116497D03*
X1149685D03*
X1144885D03*
X1152185Y130670D03*
X1149685D03*
Y123584D03*
X1152185Y123583D03*
X1144885Y130670D03*
Y123584D03*
X1156885Y130670D03*
Y123583D03*
X1142781Y141228D03*
X1156885Y137756D03*
X1149685Y137757D03*
X1144885D03*
X1145669Y150847D03*
X1153417Y213539D03*
X1146863Y238689D03*
X1155098Y238714D03*
X1147637Y247292D03*
X1142440Y396718D03*
X1156275Y656321D03*
X1155146Y699491D03*
X1148962Y747253D03*
X1147468Y766093D03*
X1145910Y803642D03*
X1146960Y1465913D03*
Y1461182D03*
X1155621Y1465513D03*
Y1460782D03*
X1146960Y1456451D03*
X1155621Y1480867D03*
X1146960Y1471805D03*
Y1476536D03*
Y1481267D03*
X1155621Y1476136D03*
Y1470244D03*
Y1491490D03*
Y1485598D03*
Y1496221D03*
X1146960Y1487159D03*
Y1491890D03*
Y1496621D03*
Y1507245D03*
Y1502514D03*
X1155621Y1506845D03*
Y1500952D03*
Y1511576D03*
X1146960Y1511976D03*
X1155621Y1516307D03*
X1146960Y1563544D03*
X1155621Y1563144D03*
X1146960Y1558813D03*
X1155621Y1572606D03*
X1146960Y1568275D03*
X1155621Y1567875D03*
X1146960Y1574167D03*
Y1578898D03*
X1155621Y1578498D03*
X1146960Y1594253D03*
X1155621Y1593853D03*
Y1587960D03*
X1146960Y1583629D03*
X1155621Y1583229D03*
X1146960Y1589522D03*
Y1609607D03*
Y1604876D03*
Y1598984D03*
X1155621Y1609207D03*
Y1598584D03*
Y1603315D03*
X1146960Y1614338D03*
X1155621Y1613938D03*
Y1618669D03*
X1152000Y1644980D03*
X1165347Y82984D03*
Y75184D03*
Y77784D03*
Y80384D03*
X1167756Y92734D03*
X1165347Y85584D03*
X1164885Y102323D03*
X1165137Y109410D03*
Y116496D03*
X1165309Y124576D03*
X1166362Y130670D03*
X1171586Y137756D03*
X1166357D03*
X1173630Y226226D03*
Y223726D03*
Y228726D03*
Y231226D03*
X1168851Y445873D03*
X1173278Y472579D03*
X1168478D03*
X1173278Y479666D03*
X1168478D03*
Y486752D03*
X1173278D03*
X1168478Y493839D03*
X1173278D03*
X1168478Y523800D03*
Y516713D03*
X1173278D03*
Y523800D03*
Y537973D03*
X1168478D03*
X1173278Y530886D03*
X1168478D03*
X1161274Y550462D03*
X1159535Y542712D03*
X1165400Y553300D03*
X1167900D03*
X1173278Y566752D03*
X1168478D03*
Y580926D03*
X1173278D03*
Y588013D03*
X1168478D03*
X1173278Y573839D03*
X1168478D03*
Y602186D03*
X1173278D03*
Y595099D03*
X1168478D03*
X1173278Y609272D03*
X1168478D03*
Y616359D03*
X1173278D03*
X1162863Y678519D03*
X1159173Y678462D03*
X1170465Y677836D03*
X1157646Y699491D03*
X1162646D03*
X1160146D03*
X1169256Y694983D03*
X1163774Y713347D03*
X1166115Y718469D03*
X1173034Y765060D03*
X1169697Y791935D03*
X1164925Y791607D03*
X1159887Y869106D03*
X1174461Y914515D03*
X1164283Y1465913D03*
Y1456451D03*
Y1461182D03*
X1172944Y1465513D03*
Y1460782D03*
Y1470244D03*
Y1480867D03*
X1164283Y1471805D03*
Y1476536D03*
Y1481267D03*
X1172944Y1476136D03*
X1164283Y1487159D03*
Y1491890D03*
Y1496621D03*
X1172944Y1491490D03*
Y1485598D03*
Y1496221D03*
X1164283Y1507245D03*
Y1502514D03*
X1172944Y1506845D03*
Y1500952D03*
Y1511576D03*
X1164283Y1511976D03*
X1172944Y1516307D03*
X1164283Y1558813D03*
Y1563544D03*
X1172944Y1563144D03*
Y1567875D03*
X1164283Y1574167D03*
Y1578898D03*
X1172944Y1578498D03*
Y1572606D03*
X1164283Y1568275D03*
Y1583629D03*
X1172944Y1583229D03*
X1164283Y1589522D03*
Y1594253D03*
X1172944Y1593853D03*
Y1587960D03*
Y1598584D03*
Y1603315D03*
X1164283Y1609607D03*
Y1604876D03*
Y1598984D03*
X1172944Y1609207D03*
X1164283Y1614338D03*
X1172944Y1613938D03*
Y1618669D03*
X1172000Y1644980D03*
X1174535Y53597D03*
X1188278Y94017D03*
X1174861Y103037D03*
X1174995Y116496D03*
Y109410D03*
X1182995Y116496D03*
Y109410D03*
Y102323D03*
X1185753Y107649D03*
Y104249D03*
X1174995Y130670D03*
Y123583D03*
X1182995Y130670D03*
Y123583D03*
Y137756D03*
X1184086Y231461D03*
Y228961D03*
X1187793Y226141D03*
X1184086Y226461D03*
X1190593Y226141D03*
X1184086Y223661D03*
X1188036Y236611D03*
X1187738Y248891D03*
X1179676Y293796D03*
X1187690Y288190D03*
X1185190Y285690D03*
X1187690D03*
X1185190Y288190D03*
X1177176Y293796D03*
X1176858Y306534D03*
X1191748Y392676D03*
X1188598Y381500D03*
X1189122Y442606D03*
X1188739Y446606D03*
X1175778Y465492D03*
Y472579D03*
Y479666D03*
Y486752D03*
Y516713D03*
Y523800D03*
Y530886D03*
Y566752D03*
Y559665D03*
Y580926D03*
Y588012D03*
Y573839D03*
Y602185D03*
Y595099D03*
Y609272D03*
X1176500Y784933D03*
X1190062Y844378D03*
X1180239Y868430D03*
X1181654Y894671D03*
X1185058Y883475D03*
X1189219Y940703D03*
X1181605Y1465913D03*
Y1456451D03*
Y1461182D03*
Y1471805D03*
Y1476536D03*
Y1481267D03*
Y1487159D03*
Y1491890D03*
Y1496621D03*
Y1507245D03*
Y1502514D03*
Y1511976D03*
Y1558813D03*
Y1563544D03*
Y1568275D03*
Y1574167D03*
Y1578898D03*
Y1583629D03*
Y1589522D03*
Y1594253D03*
Y1598984D03*
Y1609607D03*
Y1604876D03*
Y1614338D03*
X1193330Y5374D03*
X1192643Y24773D03*
Y44773D03*
X1205355Y84140D03*
Y76140D03*
Y80140D03*
X1196278Y94017D03*
X1200287D03*
X1192278D03*
X1192007Y101701D03*
X1202808Y117557D03*
X1197398Y115401D03*
X1192406Y110445D03*
Y115401D03*
X1199557Y103783D03*
X1197398Y129574D03*
Y124618D03*
X1192406D03*
Y129574D03*
X1202808Y122513D03*
Y131731D03*
X1205899Y146461D03*
X1202808Y136687D03*
X1204801Y152367D03*
X1190319Y151540D03*
X1200469Y184619D03*
X1193969Y191941D03*
X1193836Y188727D03*
X1202449Y206760D03*
X1192055Y229286D03*
X1195748Y224712D03*
Y222212D03*
X1192055Y231786D03*
X1190536Y236611D03*
X1193036D03*
X1192738Y248891D03*
X1190238D03*
X1203663Y256535D03*
X1195663D03*
X1204693Y279208D03*
X1194716Y290755D03*
X1202716D03*
X1190490Y285690D03*
Y288190D03*
X1198716Y290755D03*
X1192500Y322400D03*
X1198997Y790610D03*
X1192431Y868620D03*
X1192367Y903785D03*
X1190210Y900909D03*
X1197173Y940645D03*
X1195757Y988131D03*
X1203419Y1011161D03*
X1200008D03*
X1196300Y998600D03*
X1202028Y998349D03*
X1199700Y1013661D03*
X1201800Y1019431D03*
X1190267Y1465513D03*
Y1460782D03*
X1198928Y1465914D03*
Y1456452D03*
Y1461183D03*
Y1481268D03*
X1190267Y1476136D03*
Y1470244D03*
Y1480867D03*
X1198928Y1476537D03*
Y1471806D03*
X1190267Y1485598D03*
Y1496221D03*
X1198928Y1491891D03*
Y1487160D03*
Y1496622D03*
X1190267Y1491490D03*
Y1506845D03*
Y1500952D03*
Y1511576D03*
X1198928Y1507246D03*
Y1502515D03*
Y1511977D03*
X1190267Y1516307D03*
X1198928Y1558813D03*
X1190267Y1563144D03*
X1198928Y1563544D03*
X1190267Y1567875D03*
X1198928Y1568275D03*
X1190267Y1578498D03*
Y1572606D03*
X1198928Y1578898D03*
Y1574167D03*
X1190267Y1583229D03*
X1198928Y1583629D03*
X1190267Y1593853D03*
Y1587960D03*
X1198928Y1594253D03*
Y1589522D03*
X1190267Y1609207D03*
Y1598584D03*
Y1603315D03*
X1198928Y1609607D03*
Y1598984D03*
Y1604876D03*
X1190267Y1613938D03*
Y1618669D03*
X1198928Y1614338D03*
X1192000Y1644980D03*
X1212232Y3000D03*
X1220126Y91951D03*
X1218730Y117261D03*
X1207800Y117557D03*
X1210724Y103621D03*
X1207800Y122513D03*
Y131731D03*
Y136687D03*
X1206501Y180572D03*
X1211184Y180527D03*
X1214907Y192421D03*
X1206501Y185165D03*
X1211139Y185121D03*
X1208797Y281307D03*
X1213287Y293645D03*
Y290845D03*
Y288345D03*
X1210787Y293645D03*
Y290845D03*
Y288345D03*
X1209980Y451677D03*
X1207480Y454177D03*
X1209980D03*
X1207480Y451677D03*
X1212000Y1644980D03*
X1232232Y3000D03*
X1222933Y55513D03*
X1228097Y60922D03*
X1225041Y97080D03*
X1238479Y102249D03*
X1230479D03*
X1234479D03*
X1228910Y110784D03*
X1226261Y113394D03*
X1229195Y130898D03*
X1236504Y133298D03*
X1230651Y134579D03*
X1226437Y180665D03*
Y172665D03*
X1236779Y195176D03*
X1236398Y198883D03*
X1234279Y195176D03*
X1239579D03*
X1231779D03*
X1236398Y201683D03*
X1234139Y203393D03*
X1231639D03*
X1226469Y200864D03*
Y212864D03*
X1237827Y206838D03*
X1226469Y216864D03*
Y221864D03*
X1228226Y252371D03*
X1234904Y316942D03*
X1223431Y377912D03*
Y381912D03*
Y397912D03*
X1232670Y466528D03*
X1237662D03*
X1232670Y471484D03*
X1237662D03*
Y480701D03*
X1232670D03*
Y485657D03*
X1237662D03*
X1232670Y515617D03*
X1237662D03*
X1232670Y510661D03*
X1237662D03*
Y524835D03*
Y529791D03*
X1232670Y524835D03*
Y529791D03*
Y565657D03*
Y560701D03*
X1237662Y565657D03*
Y560701D03*
X1232670Y579830D03*
X1237662Y589047D03*
X1232670D03*
X1237662Y574874D03*
X1232670D03*
X1237662Y579830D03*
Y603221D03*
X1232670D03*
Y594003D03*
X1237662D03*
Y608177D03*
X1232670D03*
X1232000Y1644980D03*
X1248216Y4469D03*
X1249577Y24773D03*
Y44773D03*
X1243503Y106495D03*
X1244496Y109172D03*
X1241496D03*
X1247247Y116497D03*
X1254547Y109410D03*
Y116497D03*
X1252047D03*
X1247247Y123584D03*
Y130670D03*
X1252047Y123584D03*
X1254547Y123583D03*
Y130670D03*
X1252047D03*
X1243237Y146012D03*
X1245143Y141228D03*
X1247247Y137757D03*
X1252047D03*
X1250307Y140296D03*
X1248031Y150847D03*
X1240327Y206838D03*
X1249999Y247292D03*
X1239823Y238589D03*
X1242789Y236121D03*
X1242708Y253198D03*
X1243072Y473640D03*
X1248064D03*
X1243072Y487813D03*
X1248064D03*
X1243072Y478596D03*
X1248064D03*
X1243072Y492769D03*
X1248064D03*
X1243072Y522730D03*
X1248064Y517774D03*
Y522730D03*
X1243072Y517774D03*
X1248064Y531947D03*
Y536903D03*
X1243072D03*
Y531947D03*
X1241629Y550065D03*
X1248064Y567813D03*
X1243072D03*
X1248064Y572769D03*
X1243072D03*
X1248064Y581987D03*
Y586943D03*
X1243072D03*
Y581987D03*
Y601116D03*
X1248064D03*
X1243072Y596160D03*
X1248064D03*
X1243072Y610333D03*
Y615289D03*
X1248064D03*
Y610333D03*
X1248106Y1004700D03*
X1245400Y1003700D03*
X1245900Y1528000D03*
X1256898Y53597D03*
X1267709Y82984D03*
Y75184D03*
Y77784D03*
Y80384D03*
X1270263Y92849D03*
X1267709Y85584D03*
X1267499Y116496D03*
X1259247D03*
Y102323D03*
Y109410D03*
X1267247Y102323D03*
X1267499Y109410D03*
X1267671Y124576D03*
X1268724Y130670D03*
X1259247D03*
Y123583D03*
X1268719Y137756D03*
X1259247D03*
X1255779Y213539D03*
X1257460Y238714D03*
X1264481Y300223D03*
X1266616Y322456D03*
X1259500Y330000D03*
X1259991Y340691D03*
X1267843Y473571D03*
Y481071D03*
Y478571D03*
Y476071D03*
X1263242Y1523458D03*
X1262985Y1519459D03*
X1260260Y1546500D03*
X1276898Y53597D03*
X1277223Y103037D03*
X1277357Y116496D03*
Y109410D03*
X1285357Y116496D03*
Y109410D03*
Y102323D03*
Y123583D03*
X1277357Y130670D03*
Y123583D03*
X1285357Y130670D03*
X1273555Y137756D03*
X1285357D03*
X1275992Y223726D03*
Y226226D03*
Y231226D03*
Y228726D03*
X1286448Y223661D03*
Y226461D03*
Y228961D03*
Y231461D03*
X1279538Y293796D03*
X1282038D03*
X1280699Y377173D03*
X1284659D03*
X1272927Y462060D03*
X1275927D03*
X1280631Y480194D03*
Y477694D03*
X1277897Y478876D03*
Y476376D03*
X1274415Y477053D03*
X1271915D03*
X1283400Y715500D03*
X1281777Y823500D03*
X1274417Y861964D03*
X1271438Y861846D03*
X1274396Y866896D03*
X1285302Y877283D03*
Y881783D03*
X1302232Y3000D03*
X1295692Y5374D03*
X1303229Y23274D03*
X1295005Y24773D03*
X1297785Y30618D03*
X1295005Y44773D03*
X1302649Y94017D03*
X1298640D03*
X1290640D03*
X1294369Y101701D03*
X1294640Y94017D03*
X1301919Y103783D03*
X1299760Y115401D03*
X1294768Y110445D03*
Y115401D03*
X1288115Y104249D03*
Y107649D03*
X1294768Y129574D03*
X1299760D03*
Y124618D03*
X1294768D03*
X1296331Y191941D03*
X1302831Y184619D03*
X1296198Y188727D03*
X1292955Y226141D03*
X1290155D03*
X1294417Y229286D03*
X1298110Y222212D03*
Y224712D03*
X1290398Y236611D03*
X1295398D03*
X1292898D03*
X1294417Y231786D03*
X1298025Y256535D03*
X1290100Y248891D03*
X1292600D03*
X1295100D03*
X1290052Y288190D03*
X1292852D03*
Y285690D03*
X1305078Y290755D03*
X1297078D03*
X1301078D03*
X1287552Y288190D03*
X1290052Y285690D03*
X1287552D03*
X1303000Y326692D03*
X1292731Y331820D03*
X1303000Y331000D03*
X1302896Y343797D03*
Y340397D03*
X1294080Y349820D03*
X1300817Y568635D03*
X1301194Y565518D03*
X1293500Y879800D03*
X1296866Y894993D03*
X1293500Y883800D03*
X1300500Y960000D03*
X1299717Y1024136D03*
X1292000Y1644980D03*
X1307717Y84140D03*
Y76140D03*
Y80140D03*
X1310162Y117557D03*
X1305170D03*
X1313086Y103621D03*
X1310162Y122513D03*
Y131731D03*
X1305170Y122513D03*
Y131731D03*
X1310162Y136687D03*
X1305170D03*
X1313546Y180527D03*
X1308863Y180572D03*
Y185165D03*
X1317269Y192421D03*
X1313501Y185121D03*
X1304811Y206760D03*
X1306025Y256535D03*
X1307055Y279208D03*
X1311159Y281307D03*
X1313149Y288345D03*
Y290845D03*
Y293645D03*
X1315649Y288345D03*
Y290845D03*
Y293645D03*
X1318362Y310562D03*
X1310172Y367956D03*
X1307819Y474382D03*
X1307835Y470382D03*
X1311488Y475560D03*
X1319323Y598454D03*
X1305412Y799061D03*
X1305786Y867704D03*
X1309753Y877589D03*
X1305740Y877534D03*
X1308220Y889253D03*
X1319500Y901500D03*
X1305356Y902597D03*
X1316893Y925603D03*
X1311325Y928918D03*
X1321256Y943815D03*
X1307000Y960500D03*
X1304664Y1023462D03*
X1309937Y1037038D03*
X1315606Y1042825D03*
X1315756Y1039344D03*
X1313459Y1081599D03*
X1310589Y1097278D03*
X1313089D03*
X1317437Y1152684D03*
Y1160834D03*
X1318178Y1192621D03*
Y1190121D03*
X1319237Y1221428D03*
X1311237D03*
X1315237D03*
X1311237Y1233428D03*
Y1229428D03*
Y1225428D03*
X1315237Y1237428D03*
Y1233428D03*
Y1229428D03*
Y1225428D03*
X1319237Y1237428D03*
Y1233428D03*
Y1229428D03*
Y1225428D03*
X1315237Y1241428D03*
X1319237D03*
X1312000Y1644980D03*
X1322232Y3000D03*
X1334223Y33425D03*
X1328799Y172665D03*
Y180665D03*
Y176665D03*
X1328831Y212864D03*
Y200864D03*
Y204864D03*
Y221864D03*
Y216864D03*
X1334110Y310562D03*
X1321762D03*
X1329636Y307562D03*
X1326236D03*
X1334109Y373401D03*
X1331096Y549931D03*
X1327000Y609000D03*
X1333224Y615484D03*
X1327000Y621000D03*
X1327003Y623940D03*
X1327011Y646064D03*
X1326970Y736464D03*
X1336661Y737675D03*
X1335803Y826500D03*
X1332500Y961500D03*
X1331890Y1051919D03*
X1331359Y1098898D03*
X1334161Y1098518D03*
X1333905Y1123101D03*
X1331405D03*
X1323405D03*
X1320279Y1131935D03*
Y1134435D03*
Y1136935D03*
Y1139435D03*
X1334305Y1129301D03*
X1331805D03*
X1329305D03*
X1326805D03*
X1324305D03*
X1321805D03*
X1334305Y1125801D03*
X1331805D03*
X1323405D03*
X1320279Y1141935D03*
Y1146935D03*
Y1144435D03*
X1326269Y1152713D03*
Y1155213D03*
X1325635Y1172384D03*
Y1162384D03*
Y1164884D03*
Y1167384D03*
Y1169884D03*
X1323135Y1172384D03*
Y1162384D03*
Y1164884D03*
Y1167384D03*
Y1169884D03*
X1334793Y1179421D03*
Y1181921D03*
Y1184421D03*
Y1186921D03*
X1320493Y1186709D03*
Y1184209D03*
Y1181709D03*
Y1179209D03*
X1325635Y1174884D03*
X1323135D03*
X1331643Y1192621D03*
Y1190121D03*
X1327237Y1221428D03*
X1331237D03*
X1335237D03*
X1323237D03*
X1327237Y1237428D03*
Y1233428D03*
Y1229428D03*
Y1225428D03*
X1331237Y1237428D03*
Y1233428D03*
Y1229428D03*
Y1225428D03*
X1335237Y1237428D03*
Y1233428D03*
Y1229428D03*
Y1225428D03*
X1323237Y1237428D03*
Y1233428D03*
Y1229428D03*
Y1225428D03*
X1335237Y1241428D03*
X1323237Y1245428D03*
Y1241428D03*
X1327237Y1245428D03*
Y1241428D03*
X1331237Y1245428D03*
Y1241428D03*
X1335237Y1245428D03*
X1332000Y1644980D03*
X1342232Y3000D03*
X1340320Y151540D03*
X1337510Y310562D03*
X1337509Y373401D03*
X1343846Y461607D03*
X1344129Y606914D03*
X1344433Y601201D03*
X1344680Y619085D03*
X1346378Y623734D03*
X1350929Y687043D03*
X1340299Y686243D03*
X1336450Y765675D03*
X1347136Y780040D03*
X1348917Y788000D03*
X1347380Y1057998D03*
Y1055498D03*
X1344880D03*
Y1057998D03*
X1347380Y1060498D03*
Y1062998D03*
X1344880D03*
Y1060498D03*
X1339349Y1098767D03*
X1339305Y1129301D03*
X1336805D03*
X1339305Y1125801D03*
X1336805D03*
X1343505Y1136935D03*
Y1134435D03*
Y1139435D03*
Y1131935D03*
X1349907D03*
Y1134435D03*
Y1136935D03*
Y1139435D03*
X1352407Y1131935D03*
Y1134435D03*
Y1136935D03*
Y1139435D03*
X1343505Y1146935D03*
Y1144435D03*
Y1141935D03*
X1349907D03*
Y1146935D03*
Y1144435D03*
X1352407Y1141935D03*
Y1146935D03*
Y1144435D03*
X1336669Y1152713D03*
Y1155213D03*
X1351405Y1154902D03*
Y1152402D03*
X1343905Y1162384D03*
Y1164884D03*
Y1167384D03*
Y1169884D03*
Y1172384D03*
X1341405D03*
Y1169884D03*
Y1167384D03*
Y1164884D03*
Y1162384D03*
X1350963Y1172384D03*
Y1169884D03*
Y1167384D03*
Y1164884D03*
Y1162384D03*
X1351149Y1158200D03*
X1347423Y1186709D03*
Y1184209D03*
Y1181709D03*
Y1179209D03*
X1343905Y1174884D03*
X1341405D03*
X1350963D03*
X1337108Y1192621D03*
Y1190121D03*
X1345108D03*
Y1192621D03*
X1347237Y1221428D03*
X1343237D03*
X1339237D03*
X1347237Y1237428D03*
Y1233428D03*
Y1229428D03*
X1343237D03*
Y1233428D03*
Y1237428D03*
X1339237D03*
Y1233428D03*
Y1229428D03*
Y1225428D03*
X1347237Y1245428D03*
Y1241428D03*
X1343237D03*
Y1245428D03*
X1339237D03*
Y1241428D03*
X1352000Y1644980D03*
X1362232Y3000D03*
X1355900Y146461D03*
X1354802Y152367D03*
X1363535Y327877D03*
X1366535Y335751D03*
Y339151D03*
X1363535Y331277D03*
Y343625D03*
X1366535Y354899D03*
Y351499D03*
X1363535Y347025D03*
X1352817Y788000D03*
X1365000Y804000D03*
X1354185Y906498D03*
X1367000Y904500D03*
Y900500D03*
X1367884Y1018825D03*
X1357265Y1022766D03*
X1364237Y1043140D03*
X1357265Y1030266D03*
X1363941Y1047047D03*
X1364418Y1090568D03*
Y1093068D03*
X1366289Y1098518D03*
X1361037Y1098428D03*
X1355533Y1123101D03*
X1363533D03*
X1366033D03*
X1366433Y1129301D03*
X1355533Y1125801D03*
X1363933D03*
X1366433D03*
X1353933Y1129301D03*
X1356433D03*
X1358933D03*
X1361433D03*
X1363933D03*
X1357397Y1155213D03*
Y1152713D03*
X1366797D03*
Y1155213D03*
X1353463Y1172384D03*
Y1169884D03*
Y1167384D03*
Y1164884D03*
Y1162384D03*
X1361723Y1179421D03*
Y1181921D03*
Y1184421D03*
Y1186921D03*
X1353463Y1174884D03*
X1364038Y1190121D03*
Y1192621D03*
X1382232Y3000D03*
X1376262Y113394D03*
X1378911Y110784D03*
X1380480Y102249D03*
X1384480D03*
X1378505Y133298D03*
X1380652Y134579D03*
X1384280Y195176D03*
X1381780D03*
X1384140Y203393D03*
X1381640D03*
X1386399Y201683D03*
X1378227Y252371D03*
X1375400Y435192D03*
X1375360Y432234D03*
X1383343Y508228D03*
X1383907Y516591D03*
X1383556Y554388D03*
X1383184Y587653D03*
X1378957Y630957D03*
X1384657Y631620D03*
X1378957Y722457D03*
X1385290Y722400D03*
X1371000Y811620D03*
X1381428Y812287D03*
X1376708Y901000D03*
X1383669Y1011303D03*
Y1017303D03*
Y1023303D03*
X1376601Y1030218D03*
X1374451Y1090568D03*
Y1093068D03*
X1371477Y1098767D03*
X1375633Y1136935D03*
Y1134435D03*
Y1139435D03*
Y1131935D03*
X1383366D03*
Y1134435D03*
Y1136935D03*
Y1139435D03*
X1368933Y1125801D03*
X1371433D03*
X1368933Y1129301D03*
X1371433D03*
X1383024Y1152684D03*
X1376861D03*
X1375633Y1146935D03*
Y1144435D03*
Y1141935D03*
X1383366D03*
Y1146935D03*
Y1144435D03*
X1369233Y1169884D03*
Y1172384D03*
X1371733D03*
Y1169884D03*
Y1167384D03*
Y1164884D03*
Y1162384D03*
X1369233D03*
Y1164884D03*
Y1167384D03*
X1376861Y1160834D03*
X1383024D03*
X1369233Y1174884D03*
X1371733D03*
X1372000Y1644980D03*
X1398216Y4469D03*
X1399577Y24773D03*
Y44773D03*
X1388480Y102249D03*
X1391497Y109172D03*
X1394497D03*
X1393504Y106495D03*
X1397248Y116497D03*
X1386505Y133298D03*
X1397248Y130670D03*
Y123584D03*
X1393238Y146012D03*
X1395144Y141228D03*
X1397248Y137757D03*
X1398032Y150847D03*
X1389580Y195176D03*
X1386399Y198883D03*
X1386780Y195176D03*
X1390328Y206838D03*
X1387828D03*
X1400000Y247292D03*
X1399226Y238689D03*
X1392790Y236121D03*
X1389824Y238589D03*
X1392709Y253198D03*
X1391623Y409900D03*
X1387125Y417312D03*
X1393177Y424804D03*
X1389557Y424678D03*
X1389431Y421593D03*
X1390271Y417578D03*
X1393208Y428109D03*
X1393336Y431100D03*
X1403085Y460565D03*
X1393944Y507856D03*
X1394044Y510990D03*
X1395605Y556217D03*
X1390741Y561000D03*
Y569000D03*
Y565000D03*
Y611500D03*
Y607500D03*
Y615500D03*
X1397000Y652000D03*
Y656000D03*
Y660000D03*
Y699000D03*
Y707000D03*
Y703000D03*
X1399872Y845109D03*
X1398247Y926261D03*
X1396869Y958707D03*
X1395669Y1011303D03*
X1389669D03*
X1395669Y1017303D03*
Y1023303D03*
X1389669D03*
X1390322Y1057998D03*
Y1055498D03*
X1392822D03*
Y1057998D03*
X1390322Y1060498D03*
Y1062998D03*
X1392822D03*
Y1060498D03*
X1399748Y1098518D03*
X1394496Y1098428D03*
X1388992Y1123101D03*
X1396992D03*
X1399492D03*
X1385866Y1131935D03*
Y1134435D03*
Y1136935D03*
Y1139435D03*
X1388992Y1125801D03*
X1397392D03*
X1399892D03*
X1387392Y1129301D03*
X1389892D03*
X1392392D03*
X1394892D03*
X1397392D03*
X1399892D03*
X1391856Y1155213D03*
Y1152713D03*
X1385866Y1141935D03*
Y1146935D03*
Y1144435D03*
X1388722Y1162384D03*
Y1164884D03*
Y1167384D03*
Y1169884D03*
Y1172384D03*
X1391222Y1162384D03*
Y1164884D03*
Y1167384D03*
Y1169884D03*
Y1172384D03*
X1388722Y1174884D03*
X1391222D03*
X1393695Y1186709D03*
Y1184209D03*
Y1181709D03*
Y1179209D03*
X1391380Y1190121D03*
Y1192621D03*
X1392000Y1644980D03*
X1406898Y53597D03*
X1417248Y102323D03*
X1409248Y109410D03*
Y102323D03*
X1404548Y116497D03*
X1402048D03*
X1404548Y109410D03*
X1409248Y116496D03*
X1402048Y130670D03*
Y123584D03*
X1404548Y123583D03*
X1409248Y130670D03*
Y123583D03*
X1404548Y130670D03*
X1409248Y137756D03*
X1402048Y137757D03*
X1405780Y213539D03*
X1407461Y238714D03*
X1407844Y411033D03*
X1415610Y417644D03*
X1404249Y735858D03*
X1417284Y911009D03*
X1419446Y977192D03*
X1404317Y989436D03*
X1411038Y985379D03*
X1404936Y1098767D03*
X1415494Y1139435D03*
Y1136935D03*
Y1134435D03*
Y1131935D03*
X1409092Y1136935D03*
Y1134435D03*
Y1139435D03*
Y1131935D03*
X1402392Y1125801D03*
X1404892D03*
X1402392Y1129301D03*
X1404892D03*
X1409092Y1141935D03*
X1416736Y1152713D03*
Y1155213D03*
X1402256D03*
Y1152713D03*
X1415494Y1144435D03*
Y1146935D03*
Y1141935D03*
X1409092Y1146935D03*
Y1144435D03*
X1409492Y1167384D03*
Y1169884D03*
Y1172384D03*
X1406992D03*
Y1169884D03*
X1416550Y1162384D03*
Y1164884D03*
Y1167384D03*
Y1169884D03*
Y1172384D03*
X1406992Y1167384D03*
Y1164884D03*
Y1162384D03*
X1409492D03*
Y1164884D03*
X1416736Y1158200D03*
X1416550Y1174884D03*
X1409492D03*
X1406992D03*
X1407995Y1179421D03*
Y1181921D03*
Y1184421D03*
Y1186921D03*
X1410310Y1192621D03*
Y1190121D03*
X1404845D03*
Y1192621D03*
X1408736Y1222194D03*
X1412736D03*
X1416736D03*
X1408736Y1238194D03*
Y1234194D03*
Y1230194D03*
Y1226194D03*
X1412736Y1238194D03*
Y1234194D03*
Y1230194D03*
Y1226194D03*
X1416736Y1238194D03*
Y1234194D03*
Y1230194D03*
Y1226194D03*
X1412736Y1246194D03*
Y1242194D03*
X1416736Y1246194D03*
Y1242194D03*
X1408736D03*
Y1246194D03*
X1404239Y1547755D03*
X1403747Y1570433D03*
X1412000Y1644980D03*
X1426898Y53597D03*
X1417710Y82984D03*
Y75184D03*
Y77784D03*
Y80384D03*
X1420264Y92849D03*
X1417710Y85584D03*
X1427224Y103037D03*
X1417500Y109410D03*
Y116496D03*
X1427358D03*
Y109410D03*
X1421700Y122900D03*
X1427358Y130670D03*
Y123583D03*
X1418725Y130670D03*
X1423515Y137756D03*
X1418720D03*
X1425993Y231226D03*
Y228726D03*
Y226226D03*
Y223726D03*
X1429539Y293796D03*
X1432039D03*
X1431484Y470045D03*
X1431000Y591000D03*
X1430481Y658153D03*
X1433529Y660564D03*
X1418000Y685000D03*
Y681000D03*
X1425909Y691120D03*
X1418000Y689000D03*
Y733000D03*
X1417969Y720894D03*
X1418023Y765343D03*
X1435000Y814500D03*
Y809500D03*
X1434975Y830500D03*
X1435000Y825500D03*
X1429059Y908579D03*
X1426085Y910281D03*
X1420740Y1004766D03*
Y1000766D03*
Y1016266D03*
Y1030766D03*
X1420107Y1052514D03*
X1430005Y1090568D03*
Y1093068D03*
X1431876Y1098518D03*
X1426624Y1098428D03*
X1421120Y1123101D03*
X1429120D03*
X1431620D03*
X1422020Y1129301D03*
X1424520D03*
X1427020D03*
X1429520D03*
X1432020D03*
X1417994Y1139435D03*
Y1136935D03*
Y1134435D03*
Y1131935D03*
X1421120Y1125801D03*
X1429520D03*
X1432020D03*
X1419520Y1129301D03*
X1432384Y1155213D03*
Y1152713D03*
X1422984D03*
Y1155213D03*
X1417994Y1144435D03*
Y1146935D03*
Y1141935D03*
X1419050Y1162384D03*
Y1164884D03*
Y1167384D03*
Y1169884D03*
Y1172384D03*
Y1174884D03*
X1420625Y1186709D03*
Y1184209D03*
Y1181709D03*
Y1179209D03*
X1418310Y1192621D03*
Y1190121D03*
X1420736Y1222194D03*
X1424736D03*
X1428736D03*
X1432736D03*
X1420736Y1238194D03*
Y1234194D03*
Y1230194D03*
Y1226194D03*
X1424736Y1238194D03*
Y1234194D03*
Y1230194D03*
Y1226194D03*
X1428736Y1238194D03*
Y1234194D03*
Y1230194D03*
Y1226194D03*
X1432736Y1234194D03*
Y1230194D03*
Y1226194D03*
X1420736Y1246194D03*
Y1242194D03*
X1424736Y1246194D03*
Y1242194D03*
X1428736Y1246194D03*
Y1242194D03*
X1422176Y1491198D03*
X1423065Y1508327D03*
X1432499Y1512175D03*
X1423806Y1524252D03*
X1424245Y1543338D03*
X1425558Y1537432D03*
X1425260Y1558072D03*
X1433558Y1555366D03*
X1423701Y1563978D03*
X1432000Y1644980D03*
X1445692Y5374D03*
X1445005Y24773D03*
Y44773D03*
X1444641Y94017D03*
X1448641D03*
X1440641D03*
X1444370Y101701D03*
X1435358Y116496D03*
Y109410D03*
X1449761Y115401D03*
Y110445D03*
X1444769D03*
Y115401D03*
X1435358Y102323D03*
X1438116Y107649D03*
Y104249D03*
X1449761Y124618D03*
X1444769D03*
Y129574D03*
X1435358Y130670D03*
Y123583D03*
X1449761Y129574D03*
X1435358Y137756D03*
X1442682Y151540D03*
X1446332Y191941D03*
X1446199Y188727D03*
X1436449Y228961D03*
X1444418Y229286D03*
X1442956Y226141D03*
X1436449Y226461D03*
X1440156Y226141D03*
X1436449Y223661D03*
X1448111Y222212D03*
Y224712D03*
X1436449Y231461D03*
X1440399Y236611D03*
X1442899D03*
X1444418Y231786D03*
X1445399Y236611D03*
X1448026Y256535D03*
X1440101Y248891D03*
X1442601D03*
X1445101D03*
X1440053Y285690D03*
X1437553D03*
X1440053Y288190D03*
X1442853D03*
Y285690D03*
X1447079Y290755D03*
X1437553Y288190D03*
X1440568Y369566D03*
X1449619Y363290D03*
X1442633Y371502D03*
X1438588Y380589D03*
X1440523Y382747D03*
X1435424Y430361D03*
X1434944Y605443D03*
X1438944Y605637D03*
X1448991Y694392D03*
X1451976Y693844D03*
X1438930Y716363D03*
X1446860Y730735D03*
X1446538Y719548D03*
X1446717Y735536D03*
X1435000Y818500D03*
X1435212Y854042D03*
X1448726Y864400D03*
X1439103Y898564D03*
X1441088Y976409D03*
X1439449Y979009D03*
X1440700Y981763D03*
X1440610Y1021567D03*
X1435266Y1031522D03*
X1437064Y1098767D03*
X1441220Y1131935D03*
Y1139435D03*
Y1134435D03*
Y1136935D03*
X1434520Y1125801D03*
X1437020D03*
X1434520Y1129301D03*
X1437020D03*
X1441220Y1141935D03*
Y1144435D03*
Y1146935D03*
X1442448Y1152684D03*
Y1160834D03*
X1434820Y1162384D03*
Y1164884D03*
Y1167384D03*
Y1169884D03*
Y1172384D03*
X1437320D03*
Y1169884D03*
Y1167384D03*
Y1164884D03*
Y1162384D03*
X1434925Y1179421D03*
Y1181921D03*
Y1184421D03*
Y1186921D03*
X1434820Y1174884D03*
X1437320D03*
X1437240Y1192621D03*
Y1190121D03*
X1436736Y1222194D03*
Y1226194D03*
X1437293Y1546125D03*
X1436801Y1568803D03*
X1464594Y3000D03*
X1462675Y14334D03*
X1457718Y84140D03*
Y76140D03*
Y80140D03*
X1452650Y94017D03*
X1460163Y117557D03*
X1455171D03*
X1463087Y103621D03*
X1451920Y103783D03*
X1455171Y122513D03*
X1460163Y131731D03*
Y122513D03*
X1455171Y131731D03*
X1458262Y146461D03*
X1460163Y136687D03*
X1455171D03*
X1457164Y152367D03*
X1463547Y180527D03*
X1458864Y180572D03*
Y185165D03*
X1463502Y185121D03*
X1452832Y184619D03*
X1454812Y206760D03*
X1456026Y256535D03*
X1457056Y279208D03*
X1461160Y281307D03*
X1465650Y293645D03*
X1455079Y290755D03*
X1451079D03*
X1465650Y288345D03*
Y290845D03*
X1463150Y288345D03*
Y290845D03*
Y293645D03*
X1455979Y391756D03*
X1459873Y391705D03*
X1463145Y391579D03*
X1458212Y403374D03*
X1464536Y433114D03*
X1455761Y683448D03*
X1460111Y683536D03*
X1460816Y727964D03*
X1455291Y759656D03*
X1455159Y763714D03*
X1454504Y777575D03*
X1462000Y957000D03*
X1458202Y960288D03*
X1459519Y989432D03*
X1462388Y1006560D03*
X1455939Y1018368D03*
X1465503Y1030233D03*
X1452000Y1644980D03*
X1476822Y40780D03*
X1480460Y60922D03*
X1475296Y55513D03*
X1472489Y91951D03*
X1471093Y117261D03*
X1478624Y113394D03*
X1481273Y110784D03*
X1481368Y130898D03*
X1478800Y180665D03*
Y172665D03*
X1467270Y192421D03*
X1478832Y200864D03*
Y212864D03*
Y216864D03*
Y221864D03*
X1480589Y252371D03*
X1480702Y368516D03*
X1468309Y408861D03*
X1473364Y410724D03*
X1472403Y417338D03*
X1475236Y412482D03*
X1466231Y423671D03*
X1469538Y416795D03*
X1469293Y428815D03*
X1466653Y428582D03*
X1471375Y433115D03*
X1474713Y685247D03*
X1476794Y691447D03*
X1469116Y719055D03*
X1471006Y744818D03*
X1470801Y739280D03*
X1476677Y827626D03*
X1480343Y914776D03*
X1480414Y952214D03*
X1479196Y970000D03*
X1479096Y997860D03*
X1471096D03*
X1475096D03*
X1467096D03*
X1471854Y1035088D03*
X1479624Y1035102D03*
X1468371Y1030701D03*
X1480193Y1102091D03*
X1474384D03*
X1480193Y1114691D03*
X1474384D03*
X1480193Y1127291D03*
X1474384D03*
X1472000Y1644980D03*
X1484594Y3000D03*
X1498621Y15043D03*
Y35043D03*
Y27043D03*
X1490842Y102249D03*
X1486842D03*
X1482842D03*
X1493859Y109172D03*
X1496859D03*
X1495866Y106495D03*
X1488867Y133298D03*
X1495600Y146012D03*
X1497506Y141228D03*
X1483014Y134579D03*
X1486642Y195176D03*
X1488761Y198883D03*
X1489142Y195176D03*
X1484142D03*
X1491942D03*
X1488761Y201683D03*
X1492690Y206838D03*
X1490190D03*
X1484002Y203393D03*
X1486502D03*
X1492186Y238589D03*
X1495152Y236121D03*
X1495071Y253198D03*
X1487318Y318200D03*
X1486360Y322700D03*
Y345200D03*
X1487152Y331272D03*
X1486360Y349700D03*
X1486890Y368576D03*
X1488000Y731500D03*
X1488731Y739500D03*
X1493301Y776911D03*
X1499633Y787794D03*
X1486957Y792457D03*
X1495170Y796670D03*
X1493092Y820444D03*
X1486957Y836457D03*
X1492625Y837324D03*
X1489805Y866386D03*
X1497488Y873839D03*
X1491414Y875383D03*
X1488138Y878339D03*
Y872839D03*
X1494000Y884000D03*
X1498084Y894825D03*
X1492101Y894860D03*
X1498446Y912370D03*
X1496383Y898023D03*
X1497208Y909740D03*
X1496500Y919000D03*
X1496000Y922000D03*
X1487075Y920925D03*
X1482535Y1008262D03*
Y1002453D03*
X1495339Y1009354D03*
X1491839D03*
X1486030D03*
X1491096Y997860D03*
X1483096D03*
X1495096D03*
X1487096D03*
X1482535Y1011762D03*
X1495339Y1021954D03*
X1491839D03*
X1486030D03*
X1483693Y1102091D03*
Y1114691D03*
Y1127291D03*
X1492000Y1644980D03*
X1500578Y4469D03*
X1501939Y24773D03*
Y44773D03*
X1509260Y53597D03*
X1511610Y116496D03*
Y109410D03*
Y102323D03*
X1499610Y116497D03*
X1506910D03*
X1504410D03*
X1506910Y109410D03*
X1511610Y123583D03*
X1499610Y130670D03*
Y123584D03*
X1506910Y130670D03*
X1504410D03*
Y123584D03*
X1506910Y123583D03*
X1511610Y130670D03*
Y137756D03*
X1499610Y137757D03*
X1504410D03*
X1500394Y150847D03*
X1508142Y213539D03*
X1509823Y238714D03*
X1502362Y247292D03*
X1501588Y238689D03*
X1500480Y295727D03*
X1501000Y317500D03*
X1509454Y402291D03*
X1514446D03*
X1509454Y397335D03*
X1514446D03*
X1512046Y411509D03*
X1507054Y416465D03*
Y411509D03*
X1512046Y425682D03*
X1507054D03*
X1512046Y416465D03*
Y439855D03*
X1507054D03*
X1512046Y430638D03*
X1507054D03*
X1512046Y444811D03*
X1507054D03*
Y468609D03*
X1512046D03*
X1507054Y473565D03*
X1512046D03*
X1507054Y487738D03*
X1512046D03*
X1507054Y482782D03*
X1512046D03*
X1507054Y517699D03*
X1512046D03*
X1507054Y512743D03*
X1512046D03*
X1507054Y526916D03*
X1512046Y531872D03*
X1507054D03*
X1512046Y526916D03*
X1507034Y888133D03*
X1507358Y909740D03*
X1507305Y912262D03*
X1510280Y899732D03*
X1516500Y947500D03*
X1507096Y997860D03*
X1503096D03*
X1511096D03*
X1499096D03*
X1505130Y1105091D03*
Y1117691D03*
X1512000Y1644980D03*
X1529260Y53597D03*
X1520072Y82984D03*
Y75184D03*
Y77784D03*
Y80384D03*
X1522626Y92849D03*
X1520072Y85584D03*
X1529586Y103037D03*
X1519610Y102323D03*
X1519862Y109410D03*
Y116496D03*
X1529720D03*
Y109410D03*
X1520034Y124576D03*
X1529720Y130670D03*
Y123583D03*
X1521087Y130670D03*
X1526311Y137756D03*
X1521082D03*
X1528355Y228726D03*
Y223726D03*
Y226226D03*
Y231226D03*
X1515779Y351594D03*
X1517456Y390223D03*
X1522448D03*
X1517456Y395179D03*
Y404396D03*
Y409352D03*
X1522448Y395179D03*
Y404396D03*
Y409352D03*
X1517456Y418569D03*
Y423525D03*
X1522448D03*
Y418569D03*
Y437699D03*
X1517456Y432743D03*
Y437699D03*
X1522448Y432743D03*
X1520200Y455921D03*
X1517456Y489895D03*
X1522448D03*
X1517456Y480677D03*
Y475721D03*
X1522448Y480677D03*
Y475721D03*
X1517456Y494851D03*
X1522448D03*
X1517456Y519855D03*
X1522448D03*
Y538984D03*
X1517456D03*
Y524811D03*
Y534028D03*
X1522448D03*
Y524811D03*
X1519185Y603600D03*
Y619600D03*
Y623600D03*
X1520729Y634190D03*
X1524200Y646098D03*
X1519063Y876339D03*
X1518517Y878898D03*
X1517344Y896999D03*
X1515743Y888133D03*
X1517344Y903179D03*
X1517153Y908367D03*
X1516283Y912240D03*
X1519116D03*
X1523053Y912262D03*
X1523000Y923740D03*
X1526611Y921442D03*
X1528087Y936394D03*
X1528500Y947612D03*
X1530594Y979952D03*
X1515096Y997860D03*
X1531096D03*
X1519096D03*
X1523096D03*
X1516776Y1024954D03*
Y1012354D03*
X1531993Y1056453D03*
X1531961Y1050849D03*
X1547367Y44773D03*
X1547003Y94017D03*
X1543003D03*
X1546732Y101701D03*
X1547131Y110445D03*
Y115401D03*
X1537720Y116496D03*
Y109410D03*
Y102323D03*
X1540478Y107649D03*
Y104249D03*
X1547131Y129574D03*
X1537720Y130670D03*
Y123583D03*
X1547131Y124618D03*
X1537720Y137756D03*
X1545044Y151540D03*
X1548561Y188727D03*
X1538811Y226461D03*
X1542518Y226141D03*
X1538811Y228961D03*
Y231461D03*
X1546780Y229286D03*
X1538811Y223661D03*
X1545318Y226141D03*
X1542761Y236611D03*
X1545261D03*
X1546780Y231786D03*
X1542463Y248891D03*
X1544963D03*
X1531901Y293796D03*
X1539915Y288190D03*
X1542415Y285690D03*
X1539915D03*
X1542415Y288190D03*
X1545215D03*
Y285690D03*
X1534401Y293796D03*
X1544736Y305156D03*
X1544375Y553407D03*
X1546875D03*
X1544375Y550907D03*
X1546875D03*
X1532000Y1644980D03*
X1560080Y84140D03*
Y76140D03*
Y80140D03*
X1555012Y94017D03*
X1551003D03*
X1562525Y117557D03*
X1557533D03*
X1552123Y115401D03*
Y110445D03*
X1554282Y103783D03*
X1562525Y122513D03*
X1552123Y129574D03*
Y124618D03*
X1557533Y131731D03*
Y122513D03*
X1562525Y131731D03*
X1560624Y146461D03*
X1557533Y136687D03*
X1562525D03*
X1559526Y152367D03*
X1561226Y180572D03*
X1548694Y191941D03*
X1555194Y184619D03*
X1561226Y185165D03*
X1557174Y206760D03*
X1550473Y222212D03*
Y224712D03*
X1547761Y236611D03*
X1550388Y256535D03*
X1558388D03*
X1547463Y248891D03*
X1559418Y279208D03*
X1563522Y281307D03*
X1549441Y290755D03*
X1553441D03*
X1557441D03*
X1550931Y305158D03*
X1553534Y327337D03*
X1553910Y331798D03*
X1556429Y389154D03*
X1563248D03*
X1548629D03*
Y403327D03*
Y410413D03*
X1556429Y396240D03*
X1557708Y404911D03*
X1561778Y396240D03*
X1548629D03*
X1556662Y412571D03*
X1557849Y426299D03*
X1548629Y417500D03*
Y424587D03*
Y438760D03*
Y431673D03*
X1558160Y445847D03*
X1548629D03*
X1556429Y467539D03*
X1548629D03*
X1556429Y474626D03*
X1548629D03*
Y488799D03*
X1556690Y480828D03*
X1548629Y481713D03*
Y495886D03*
X1562385Y610400D03*
X1561535Y653161D03*
X1564670Y650122D03*
X1565132Y677843D03*
X1547813Y906581D03*
X1552000Y1644980D03*
X1574851Y91951D03*
X1573455Y117261D03*
X1565449Y103621D03*
X1565909Y180527D03*
X1569632Y192421D03*
X1565864Y185121D03*
X1565512Y288345D03*
X1568012Y293645D03*
Y290845D03*
Y288345D03*
X1565512Y293645D03*
Y290845D03*
X1578587Y341787D03*
X1578420Y338309D03*
X1574540Y389154D03*
X1579340Y396240D03*
Y403327D03*
Y410413D03*
X1574540Y396240D03*
Y403327D03*
Y410413D03*
X1566555Y414823D03*
X1565863Y422864D03*
X1579340Y417500D03*
Y424586D03*
X1574540Y417500D03*
Y424586D03*
X1565933Y429832D03*
X1565538Y436447D03*
X1574540Y438760D03*
X1579340Y431673D03*
Y438760D03*
X1574540Y431673D03*
X1567573Y447953D03*
X1579340Y445847D03*
X1574540D03*
X1566740Y467539D03*
X1574540D03*
X1565482Y472772D03*
X1574540Y474626D03*
X1579340D03*
Y488799D03*
X1574540D03*
X1566216Y487711D03*
X1566329Y479104D03*
X1574540Y481713D03*
X1579340Y481712D03*
Y495886D03*
X1574540D03*
X1566740D03*
X1579340Y518760D03*
Y540020D03*
Y532933D03*
Y525846D03*
X1579753Y599100D03*
X1578679Y613047D03*
X1578114Y607563D03*
X1574222Y629872D03*
X1569926Y668885D03*
X1575950Y662981D03*
X1578000Y678776D03*
X1570331Y691851D03*
X1575942Y705043D03*
X1572000Y1644980D03*
X1592187Y-79306D03*
Y-82706D03*
X1582187Y-43786D03*
Y-40386D03*
X1582822Y60922D03*
X1580327Y57448D03*
X1593204Y102249D03*
X1585204D03*
X1589204D03*
X1580986Y113394D03*
X1583635Y110784D03*
X1591229Y133298D03*
X1583229D03*
X1585376Y134579D03*
X1581162Y180665D03*
Y172665D03*
X1586504Y195176D03*
X1594304D03*
X1589004D03*
X1591123Y198883D03*
X1591504Y195176D03*
X1581194Y212864D03*
Y200864D03*
X1586364Y203393D03*
X1588864D03*
X1591123Y201683D03*
X1595052Y206838D03*
X1592552D03*
X1581194Y221864D03*
Y216864D03*
X1594548Y238589D03*
X1582951Y252371D03*
X1586640Y389153D03*
X1581840D03*
Y403326D03*
Y410413D03*
X1586640D03*
X1581840Y396240D03*
X1586640D03*
Y403326D03*
Y417499D03*
X1581840D03*
Y424586D03*
X1586640D03*
X1581840Y438760D03*
X1586640D03*
Y431673D03*
X1581840D03*
X1586640Y467539D03*
X1581840D03*
Y474626D03*
X1586640D03*
X1581840Y488799D03*
X1586640D03*
X1581840Y481712D03*
X1586640D03*
X1581840Y518760D03*
Y511673D03*
X1586640D03*
Y518760D03*
Y525846D03*
Y532933D03*
X1581840D03*
Y525846D03*
X1595364Y562800D03*
X1595300Y558800D03*
X1592020Y1433061D03*
X1591610Y1469940D03*
X1591586Y1505130D03*
X1604301Y44773D03*
X1611622Y53597D03*
X1609272Y109410D03*
X1601972Y116497D03*
X1609272D03*
X1606772D03*
X1596221Y109172D03*
X1599221D03*
X1598228Y106495D03*
X1601972Y123584D03*
Y130670D03*
X1606772Y123584D03*
X1609272Y123583D03*
Y130670D03*
X1606772D03*
Y137757D03*
X1597962Y146012D03*
X1599868Y141228D03*
X1601972Y137757D03*
X1602756Y150847D03*
X1610504Y213539D03*
X1604724Y247292D03*
X1597514Y236121D03*
X1612185Y238714D03*
X1603950Y238689D03*
X1597433Y253198D03*
X1597006Y290417D03*
X1599127Y375587D03*
X1596253Y375633D03*
X1596714Y383003D03*
X1599527Y392718D03*
X1596534Y379760D03*
X1599527Y408718D03*
Y400718D03*
Y404718D03*
Y412718D03*
X1596760Y530000D03*
X1611327Y735973D03*
X1611627Y780327D03*
X1597225Y1437014D03*
X1603363Y1460570D03*
X1597457Y1452556D03*
X1598500Y1472500D03*
X1606745Y1474242D03*
X1602580Y1483108D03*
X1598000Y1486000D03*
X1604000Y1516000D03*
X1600700Y1534300D03*
X1622434Y82984D03*
Y80384D03*
Y75184D03*
Y77784D03*
X1624988Y92849D03*
X1622434Y85584D03*
X1621972Y102323D03*
X1622224Y109410D03*
Y116496D03*
X1613972D03*
Y102323D03*
Y109410D03*
X1622396Y124576D03*
X1623449Y130670D03*
X1613972D03*
Y123583D03*
X1623444Y137756D03*
X1613972D03*
X1625952Y431029D03*
X1626260Y427017D03*
X1625018Y435029D03*
X1625938Y449873D03*
X1625565Y472579D03*
Y479666D03*
Y486752D03*
Y493839D03*
Y523800D03*
Y516713D03*
Y537973D03*
Y530886D03*
Y566752D03*
Y588013D03*
Y573839D03*
Y580926D03*
Y602186D03*
Y595099D03*
Y609272D03*
Y616359D03*
X1627224Y643252D03*
X1613362Y656321D03*
X1616260Y678462D03*
X1619950Y678519D03*
X1615913Y692245D03*
X1624148Y708258D03*
X1612800Y705900D03*
X1627455Y759489D03*
X1612573Y761427D03*
X1619612Y783152D03*
X1620359Y774830D03*
X1619569Y796035D03*
X1620755Y787530D03*
X1613235Y808466D03*
X1620479Y815730D03*
X1620072Y801630D03*
X1616255Y824405D03*
X1619859Y839519D03*
X1618800Y1528558D03*
X1614200Y1519500D03*
X1614360Y1542860D03*
X1618600Y1532000D03*
X1631622Y53597D03*
X1631948Y103037D03*
X1632082Y116496D03*
Y109410D03*
X1640082Y116496D03*
Y109410D03*
Y102323D03*
X1642840Y104249D03*
Y107649D03*
X1632082Y130670D03*
Y123583D03*
X1640082Y130670D03*
Y123583D03*
X1628673Y137756D03*
X1640082D03*
X1641173Y231461D03*
X1630717Y223726D03*
Y226226D03*
Y231226D03*
Y228726D03*
X1641173Y223661D03*
Y226461D03*
X1644880Y226141D03*
X1641173Y228961D03*
X1644825Y248891D03*
X1644777Y288190D03*
X1642277Y285690D03*
X1644777D03*
X1642277Y288190D03*
X1636763Y293796D03*
X1634263D03*
X1629553Y329067D03*
X1632230Y330400D03*
X1635987Y335616D03*
X1629302Y334402D03*
X1629514Y331727D03*
X1630703Y350655D03*
X1636468Y345595D03*
X1640197Y374690D03*
X1638340Y379536D03*
X1641615Y379600D03*
X1636271Y410394D03*
Y403307D03*
X1637205Y440098D03*
Y437598D03*
Y435098D03*
Y432598D03*
Y430098D03*
X1637665Y458406D03*
Y451319D03*
X1637489Y462264D03*
X1632865Y465492D03*
X1637665D03*
Y472579D03*
X1632865D03*
X1630365D03*
Y479666D03*
X1632865D03*
X1637665Y479665D03*
Y486752D03*
X1630365D03*
X1632865D03*
X1630365Y493839D03*
X1637665D03*
X1632865Y509626D03*
Y516713D03*
X1630365D03*
Y523800D03*
X1632865D03*
X1637665Y523799D03*
Y516713D03*
Y509626D03*
X1630365Y530886D03*
X1637665D03*
X1632865D03*
X1637665Y537973D03*
X1630365D03*
X1637665Y559665D03*
Y566752D03*
X1630365D03*
X1632865D03*
Y559665D03*
Y573839D03*
X1630365Y580926D03*
X1632865D03*
X1637665D03*
Y588012D03*
X1630365Y588013D03*
X1632865Y588012D03*
X1637665Y573839D03*
X1630365D03*
X1632865Y602185D03*
X1630365Y602186D03*
X1637665Y602185D03*
Y595099D03*
X1632865D03*
X1630365D03*
Y616359D03*
X1632865Y609272D03*
X1630365D03*
X1637665Y616358D03*
Y609272D03*
X1637526Y699930D03*
X1637472Y717830D03*
X1631031Y732430D03*
X1631187Y750630D03*
X1629969Y740826D03*
X1644304Y891353D03*
X1650417Y5374D03*
X1649730Y24773D03*
Y44773D03*
X1649365Y94017D03*
X1657374D03*
X1653365D03*
X1645365D03*
X1649094Y101701D03*
X1659895Y117557D03*
X1654485Y110445D03*
Y115401D03*
X1649493Y110445D03*
Y115401D03*
X1656644Y103783D03*
X1659895Y122513D03*
Y131731D03*
X1654485Y124618D03*
Y129574D03*
X1649493Y124618D03*
Y129574D03*
X1659895Y136687D03*
X1647406Y151540D03*
X1651056Y191941D03*
X1657556Y184619D03*
X1650923Y188727D03*
X1659536Y206760D03*
X1647680Y226141D03*
X1649142Y229286D03*
X1652835Y222212D03*
Y224712D03*
X1645123Y236611D03*
X1650123D03*
X1647623D03*
X1649142Y231786D03*
X1647325Y248891D03*
X1649825D03*
X1660750Y256535D03*
X1652750D03*
X1647577Y285690D03*
Y288190D03*
X1655803Y290755D03*
X1651803D03*
X1659803D03*
X1645685Y390500D03*
X1655335Y381500D03*
X1645685D03*
X1648835Y390500D03*
X1655555Y430760D03*
X1655576Y433570D03*
X1655392Y437072D03*
X1655433Y439963D03*
X1655677Y443180D03*
X1655697Y454744D03*
X1655639Y452018D03*
X1653507Y470136D03*
X1645465Y466027D03*
X1655776Y465492D03*
X1655742Y460250D03*
X1655776Y472579D03*
X1645607Y475262D03*
X1647604Y467367D03*
X1645607Y489435D03*
X1655776Y486752D03*
Y479665D03*
X1645607Y482666D03*
X1645423Y495088D03*
X1655776Y493839D03*
X1646158Y514608D03*
X1646080Y522134D03*
X1645465Y509626D03*
X1655776D03*
Y516713D03*
X1646562Y535677D03*
X1646723Y529136D03*
X1652236Y537973D03*
X1654716Y525483D03*
X1654637Y532756D03*
X1645465Y559665D03*
X1645846Y565574D03*
X1655776Y559665D03*
Y566752D03*
X1645493Y574338D03*
X1655626Y579978D03*
X1655776Y573839D03*
X1645592Y616358D03*
X1655840Y608117D03*
X1654572Y771702D03*
X1656112Y768669D03*
X1657042Y773604D03*
X1647402Y881460D03*
X1648375Y886766D03*
X1645128Y929263D03*
X1650205Y925911D03*
X1648387Y945554D03*
X1647470Y952125D03*
X1649571Y983857D03*
X1653414Y990590D03*
X1657983Y1460782D03*
X1649322Y1456451D03*
Y1465913D03*
X1657983Y1465513D03*
X1649322Y1461182D03*
Y1476536D03*
X1657983Y1476136D03*
Y1470244D03*
X1649322Y1471805D03*
Y1481267D03*
X1657983Y1480867D03*
X1649322Y1487159D03*
Y1496621D03*
X1657983Y1496221D03*
X1649322Y1491890D03*
X1657983Y1491490D03*
Y1485598D03*
Y1500952D03*
X1649322Y1502514D03*
X1657983Y1511576D03*
X1649322Y1511976D03*
Y1507245D03*
X1657983Y1506845D03*
Y1516307D03*
X1649322Y1558813D03*
Y1563544D03*
X1657983Y1563144D03*
Y1572606D03*
X1649322Y1574167D03*
Y1568275D03*
X1657983Y1567875D03*
X1649322Y1578898D03*
X1657983Y1578498D03*
X1649322Y1583629D03*
X1657983Y1583229D03*
X1649322Y1594253D03*
X1657983Y1593853D03*
Y1587960D03*
X1649322Y1589522D03*
Y1609607D03*
X1657983Y1609207D03*
X1649322Y1598984D03*
X1657983Y1598584D03*
Y1603315D03*
X1649322Y1604876D03*
Y1614338D03*
X1657983Y1613938D03*
Y1618669D03*
X1652000Y1644980D03*
X1669319Y3001D03*
X1662442Y84140D03*
Y76140D03*
Y80140D03*
X1677213Y91951D03*
X1675817Y117261D03*
X1664887Y117557D03*
X1667811Y103621D03*
X1664887Y122513D03*
Y131731D03*
X1662986Y146461D03*
X1664887Y136687D03*
X1661888Y152367D03*
X1663588Y180572D03*
X1668271Y180527D03*
X1671994Y192421D03*
X1663588Y185165D03*
X1668226Y185121D03*
X1661780Y279208D03*
X1665884Y281307D03*
X1670374Y290845D03*
Y288345D03*
X1667874Y290845D03*
Y288345D03*
X1670374Y293645D03*
X1667874D03*
X1674226Y324139D03*
X1673203Y332017D03*
X1663760Y410394D03*
Y403307D03*
X1663576Y458406D03*
X1669767Y445908D03*
X1673717Y445787D03*
X1663576Y465492D03*
Y472579D03*
Y479665D03*
Y486752D03*
Y493839D03*
Y523799D03*
Y516713D03*
Y509626D03*
Y537973D03*
Y530886D03*
Y559665D03*
Y566752D03*
Y580925D03*
Y588012D03*
Y573839D03*
Y602185D03*
Y595099D03*
Y616358D03*
Y609272D03*
X1666645Y1465913D03*
Y1456451D03*
Y1461182D03*
X1675306Y1465513D03*
Y1460782D03*
X1666645Y1471805D03*
Y1476536D03*
Y1481267D03*
X1675306Y1476136D03*
Y1470244D03*
Y1480867D03*
X1666645Y1487159D03*
Y1491890D03*
Y1496621D03*
X1675306Y1491490D03*
Y1485598D03*
Y1496221D03*
Y1511576D03*
X1666645Y1511976D03*
Y1507245D03*
Y1502514D03*
X1675306Y1506845D03*
Y1500952D03*
Y1516307D03*
X1666645Y1558813D03*
Y1563544D03*
X1675306Y1563144D03*
Y1578498D03*
Y1572606D03*
X1666645Y1568275D03*
X1675306Y1567875D03*
X1666645Y1574167D03*
Y1578898D03*
Y1583629D03*
X1675306Y1583229D03*
X1666645Y1589522D03*
Y1594253D03*
X1675306Y1593853D03*
Y1587960D03*
X1666645Y1604876D03*
Y1598984D03*
X1675306Y1609207D03*
Y1598584D03*
Y1603315D03*
X1666645Y1609607D03*
Y1614338D03*
X1675306Y1613938D03*
Y1618669D03*
X1672000Y1644980D03*
X1689319Y3001D03*
X1685184Y60922D03*
X1680020Y55513D03*
X1695566Y102249D03*
X1683348Y113394D03*
X1685997Y110784D03*
X1687566Y102249D03*
X1691566D03*
X1686171Y130898D03*
X1693591Y133298D03*
X1687738Y134579D03*
X1683524Y172665D03*
Y180665D03*
X1691366Y195176D03*
X1688866D03*
X1693485Y198883D03*
X1683556Y200864D03*
Y212864D03*
X1691226Y203393D03*
X1693485Y201683D03*
X1688726Y203393D03*
X1683556Y221864D03*
Y216864D03*
X1685313Y252371D03*
X1681273Y316731D03*
X1691117Y321649D03*
X1687164Y336324D03*
X1678072Y342319D03*
X1691743Y353506D03*
X1680518Y385912D03*
Y393924D03*
Y389912D03*
Y409924D03*
Y405924D03*
Y401924D03*
X1677933Y418838D03*
X1689757Y466528D03*
Y471484D03*
Y480701D03*
Y485657D03*
Y515617D03*
Y510661D03*
Y524835D03*
Y529791D03*
Y565657D03*
Y560701D03*
Y589047D03*
Y574874D03*
Y579830D03*
Y603221D03*
Y594003D03*
Y608177D03*
X1683968Y1465913D03*
Y1456451D03*
Y1461182D03*
X1692629Y1465513D03*
Y1460782D03*
X1683968Y1471805D03*
Y1476536D03*
Y1481267D03*
X1692629Y1476136D03*
Y1470244D03*
Y1480867D03*
X1683968Y1487159D03*
Y1491890D03*
Y1496621D03*
X1692629Y1491490D03*
Y1485598D03*
Y1496221D03*
X1683968Y1502514D03*
Y1511976D03*
X1692629Y1506845D03*
Y1500952D03*
Y1511576D03*
X1683968Y1507245D03*
X1692629Y1516307D03*
X1683968Y1558813D03*
Y1563544D03*
X1692629Y1563144D03*
Y1572606D03*
X1683968Y1568275D03*
Y1574167D03*
Y1578898D03*
X1692629Y1567875D03*
Y1578498D03*
X1683968Y1583629D03*
Y1589522D03*
Y1594253D03*
X1692629Y1583229D03*
Y1593853D03*
Y1587960D03*
X1683968Y1598984D03*
X1692629Y1609207D03*
Y1598584D03*
Y1603315D03*
X1683968Y1609607D03*
Y1604876D03*
Y1614338D03*
X1692629Y1613938D03*
Y1618669D03*
X1692000Y1644980D03*
X1705303Y4470D03*
X1706664Y24774D03*
Y44774D03*
X1698583Y109172D03*
X1701583D03*
X1700590Y106495D03*
X1709134Y116497D03*
X1704334D03*
X1709134Y123584D03*
Y130670D03*
X1704334Y123584D03*
Y130670D03*
X1700324Y146012D03*
X1702230Y141228D03*
X1709134Y137757D03*
X1704334D03*
X1705118Y150847D03*
X1696666Y195176D03*
X1693866D03*
X1697414Y206838D03*
X1694914D03*
X1707086Y247292D03*
X1699876Y236121D03*
X1696910Y238589D03*
X1706312Y238689D03*
X1699795Y253198D03*
X1701495Y289735D03*
X1695142Y303839D03*
X1694749Y466528D03*
Y471484D03*
X1700159Y473640D03*
X1705151D03*
Y487813D03*
X1700159D03*
X1705151Y478596D03*
X1694749Y480701D03*
X1700159Y478596D03*
X1694749Y485657D03*
X1700159Y492769D03*
X1705151D03*
Y517774D03*
Y522730D03*
X1694749Y510661D03*
Y515617D03*
X1700159Y517774D03*
Y522730D03*
Y536903D03*
X1705151D03*
Y531947D03*
X1694749Y524835D03*
Y529791D03*
X1700159Y531947D03*
X1698716Y550065D03*
X1705151Y572769D03*
X1700159D03*
X1705151Y567813D03*
X1698839Y564843D03*
X1700159Y567813D03*
X1694749Y565657D03*
Y560701D03*
Y579830D03*
X1705151Y586943D03*
Y581987D03*
X1694749Y589047D03*
X1700159Y586943D03*
Y581987D03*
X1694749Y574874D03*
Y603221D03*
X1700159Y601116D03*
X1705151D03*
Y596160D03*
X1700159D03*
X1694749Y594003D03*
X1705151Y615289D03*
X1700159Y610333D03*
X1694749Y608177D03*
X1700159Y615289D03*
X1705151Y610333D03*
X1701290Y1465913D03*
Y1456451D03*
Y1461182D03*
Y1471805D03*
Y1476536D03*
Y1481267D03*
Y1487159D03*
Y1491890D03*
Y1496621D03*
Y1507245D03*
Y1502514D03*
Y1511976D03*
Y1558813D03*
Y1563544D03*
Y1568275D03*
Y1574167D03*
Y1578898D03*
Y1583629D03*
Y1589522D03*
Y1594253D03*
Y1609607D03*
Y1604876D03*
Y1598984D03*
Y1614338D03*
X1713985Y53598D03*
X1724796Y82984D03*
Y77784D03*
Y80384D03*
Y75184D03*
Y85584D03*
X1716334Y116496D03*
Y109410D03*
Y102323D03*
X1711634Y116497D03*
Y109410D03*
X1724334Y102323D03*
X1724586Y109410D03*
Y116496D03*
X1724758Y124576D03*
X1725811Y130670D03*
X1716334D03*
Y123583D03*
X1711634D03*
Y130670D03*
X1725806Y137756D03*
X1716334D03*
X1712866Y213539D03*
X1714547Y238714D03*
X1715705Y328692D03*
X1712734Y340534D03*
X1725746Y377173D03*
X1723964Y370935D03*
X1718710Y447486D03*
X1716310Y458334D03*
X1724930Y491118D03*
Y488618D03*
Y493618D03*
Y496118D03*
X1709952Y1465513D03*
Y1460782D03*
X1718613Y1465914D03*
Y1456452D03*
Y1461183D03*
Y1476537D03*
Y1471806D03*
Y1481268D03*
X1709952Y1476136D03*
Y1470244D03*
Y1480867D03*
Y1491490D03*
Y1485598D03*
Y1496221D03*
X1718613Y1491891D03*
Y1487160D03*
Y1496622D03*
Y1502515D03*
Y1511977D03*
X1709952Y1506845D03*
Y1500952D03*
Y1511576D03*
X1718613Y1507246D03*
X1709952Y1516307D03*
Y1563144D03*
X1718613Y1563544D03*
Y1558813D03*
X1709952Y1567875D03*
X1718613Y1568275D03*
X1709952Y1578498D03*
Y1572606D03*
X1718613Y1578898D03*
Y1574167D03*
Y1589522D03*
X1709952Y1583229D03*
X1718613Y1583629D03*
X1709952Y1593853D03*
Y1587960D03*
X1718613Y1594253D03*
Y1609607D03*
Y1598984D03*
Y1604876D03*
X1709952Y1609207D03*
Y1598584D03*
Y1603315D03*
Y1618669D03*
X1718613Y1614338D03*
X1709952Y1613938D03*
X1712000Y1644980D03*
X1736405Y-79278D03*
Y-82678D03*
X1733985Y53598D03*
X1727350Y92849D03*
X1734310Y103037D03*
X1734444Y116496D03*
Y109410D03*
Y130670D03*
Y123583D03*
X1730647Y137756D03*
X1733079Y223726D03*
Y226226D03*
Y231226D03*
Y228726D03*
X1743535Y223661D03*
X1739125Y293796D03*
X1736625D03*
X1734826Y376499D03*
X1733027Y392228D03*
X1728433Y392183D03*
X1739847Y409016D03*
X1735811Y409032D03*
X1732494Y402867D03*
X1728478Y396866D03*
X1733071D03*
X1729302Y439718D03*
Y442518D03*
X1739179Y449118D03*
Y446318D03*
X1738824Y452740D03*
X1736214Y450091D03*
X1737703Y472189D03*
X1740542Y468088D03*
Y465288D03*
X1736592Y487570D03*
Y490070D03*
X1728038Y491870D03*
X1730538D03*
X1733147Y493758D03*
Y496258D03*
X1730675Y1132361D03*
X1726963Y1132319D03*
X1732000Y1644980D03*
X1752778Y5374D03*
X1752091Y24773D03*
Y44773D03*
X1755727Y94017D03*
X1751456Y101701D03*
X1747727Y94017D03*
X1751727D03*
X1742444Y102323D03*
Y116496D03*
Y109410D03*
X1751855Y110445D03*
Y115401D03*
X1756847D03*
Y110445D03*
X1745202Y104249D03*
Y107649D03*
X1742444Y130670D03*
Y123583D03*
X1751855Y129574D03*
Y124618D03*
X1756847D03*
Y129574D03*
X1742444Y137756D03*
X1753418Y191941D03*
X1753285Y188727D03*
X1743535Y226461D03*
X1747242Y226141D03*
X1755197Y224712D03*
X1743535Y228961D03*
Y231461D03*
X1751504Y229286D03*
X1755197Y222212D03*
X1750042Y226141D03*
X1752485Y236611D03*
X1749985D03*
X1751504Y231786D03*
X1747485Y236611D03*
X1747187Y248891D03*
X1749687D03*
X1752187D03*
X1755112Y256535D03*
X1749939Y288190D03*
X1747139D03*
X1744639D03*
X1749939Y285690D03*
X1744639D03*
X1747139D03*
X1758165Y290755D03*
X1754165D03*
X1744524Y370010D03*
X1756497Y370976D03*
X1752497Y371076D03*
X1747561Y385161D03*
X1748252Y395248D03*
X1756844Y450041D03*
Y452841D03*
Y455641D03*
X1747179Y449118D03*
Y446318D03*
X1747359Y454309D03*
Y458309D03*
Y462309D03*
X1756089Y542952D03*
X1750879Y541940D03*
X1757402Y825111D03*
Y820155D03*
X1744937Y912517D03*
X1747937D03*
X1750751Y910785D03*
X1746600Y935100D03*
X1745824Y987058D03*
X1748677Y993986D03*
X1756192Y996132D03*
X1759569Y1021944D03*
X1743224Y1119055D03*
X1758583Y1581027D03*
X1750685Y1618504D03*
X1752000Y1644980D03*
X1765559Y3001D03*
X1764804Y84140D03*
Y76140D03*
Y80140D03*
X1759736Y94017D03*
X1767249Y117557D03*
X1770173Y103621D03*
X1759006Y103783D03*
X1762257Y117557D03*
Y122513D03*
Y131731D03*
X1767249Y122513D03*
Y131731D03*
X1762257Y136687D03*
X1767249D03*
X1765950Y180572D03*
X1770633Y180527D03*
X1774356Y192421D03*
X1759918Y184619D03*
X1770588Y185121D03*
X1765950Y185165D03*
X1761898Y206760D03*
X1763112Y256535D03*
X1764142Y279208D03*
X1768246Y281307D03*
X1772736Y293645D03*
X1770236D03*
Y290845D03*
Y288345D03*
X1772736Y290845D03*
Y288345D03*
X1762165Y290755D03*
X1760497Y371070D03*
X1765497Y370899D03*
X1766204Y398949D03*
X1770778Y402642D03*
X1773278D03*
X1767633Y409904D03*
Y407104D03*
X1763704Y401949D03*
X1767953Y413611D03*
X1770453D03*
X1772953D03*
X1772893Y423944D03*
X1770393D03*
X1767893D03*
X1765093D03*
X1765153Y413611D03*
X1766837Y450041D03*
Y452841D03*
Y455641D03*
X1765097Y466409D03*
X1765083Y487382D03*
X1764912Y482382D03*
X1768575Y479560D03*
X1765006Y478382D03*
X1770135Y490711D03*
X1758957Y543036D03*
X1761953Y706827D03*
X1772768Y818696D03*
X1761953Y865160D03*
X1773600Y888100D03*
X1773614Y895275D03*
X1773600Y902800D03*
X1770680Y926322D03*
X1763818Y926241D03*
X1774476Y995049D03*
X1773810Y990821D03*
X1762486Y990260D03*
X1760201Y992475D03*
X1769004Y1019395D03*
X1768844Y1023694D03*
Y1027248D03*
X1771773Y1028829D03*
X1774339Y1437975D03*
X1774216Y1470165D03*
X1765294Y1575434D03*
X1759092Y1588137D03*
X1767142Y1588219D03*
X1772000Y1644980D03*
X1788884Y59871D03*
X1782382Y55513D03*
X1790664Y71908D03*
X1779575Y91951D03*
X1778179Y117261D03*
X1785886Y172665D03*
Y180665D03*
X1785918Y200864D03*
Y212864D03*
Y216864D03*
Y221864D03*
X1790533Y303750D03*
X1790136Y399161D03*
Y401661D03*
Y396661D03*
X1778103Y399161D03*
Y401661D03*
Y396661D03*
X1783028Y408240D03*
X1785528D03*
X1780528D03*
X1783107Y424240D03*
X1780646Y420393D03*
X1785646D03*
X1783146D03*
X1783107Y426740D03*
X1786713Y455039D03*
X1790014Y468607D03*
X1783014Y474513D03*
X1784602Y564092D03*
X1778801Y836469D03*
X1782600Y874500D03*
X1788400Y888100D03*
X1781000Y888087D03*
X1788396Y895066D03*
X1788300Y902800D03*
X1780665Y902796D03*
X1786256Y927626D03*
X1784306Y924601D03*
X1786256Y930626D03*
X1789537Y930498D03*
X1779143Y995203D03*
X1779033Y1023432D03*
X1786740Y1019237D03*
X1780802Y1019474D03*
X1774863Y1019237D03*
X1774844Y1023694D03*
X1783844D03*
X1786844Y1027248D03*
X1780844D03*
X1774844D03*
X1789844Y1023694D03*
X1779581Y1222200D03*
Y1219400D03*
Y1216600D03*
Y1213800D03*
X1782581Y1222200D03*
Y1219400D03*
Y1216600D03*
Y1213800D03*
X1780397Y1237469D03*
Y1230569D03*
Y1228069D03*
X1779581Y1225000D03*
X1782581D03*
X1785961Y1224892D03*
X1780397Y1234969D03*
Y1241869D03*
Y1244369D03*
Y1248769D03*
Y1251269D03*
X1791099Y1260421D03*
X1779868Y1446668D03*
X1786564Y1478858D03*
X1777131Y1604357D03*
X1801761Y-43888D03*
Y-40488D03*
X1791570Y74535D03*
X1791088Y77296D03*
X1804993Y297591D03*
X1804984Y433975D03*
X1803570Y436164D03*
X1800933Y461607D03*
X1793149Y662810D03*
X1798705Y718793D03*
X1791302Y829031D03*
X1793474Y930374D03*
X1803351Y1027471D03*
X1805188Y1019078D03*
X1799646Y1018999D03*
X1793470Y1018762D03*
X1801844Y1023694D03*
X1795844D03*
X1798844Y1027248D03*
X1792844D03*
X1796607Y1200108D03*
X1801285Y1213373D03*
X1801147Y1208555D03*
X1802844Y1227695D03*
X1793976Y1440762D03*
X1807270Y1468535D03*
X1793879Y1472952D03*
X1792000Y1644980D03*
X1822983Y346053D03*
Y366053D03*
Y386053D03*
Y406053D03*
Y426053D03*
Y446053D03*
Y466053D03*
Y486053D03*
Y506053D03*
Y526053D03*
Y546053D03*
Y566053D03*
Y586053D03*
Y606053D03*
Y626053D03*
Y646053D03*
Y666053D03*
Y686053D03*
Y706053D03*
Y726053D03*
Y746053D03*
Y766053D03*
Y786053D03*
Y806053D03*
Y826053D03*
Y846053D03*
Y866053D03*
Y886053D03*
Y906053D03*
Y926053D03*
Y946053D03*
X1812538Y1026859D03*
X1811468Y1021084D03*
X1807844Y1023694D03*
Y1027248D03*
X1810349Y1031264D03*
X1809897Y1237285D03*
Y1230385D03*
Y1232885D03*
X1811482Y1226423D03*
X1809897Y1239785D03*
Y1244185D03*
Y1246685D03*
X1807393Y1436345D03*
X1812000Y1644980D03*
X1825559Y3001D03*
X1836543Y4470D03*
X1837904Y24774D03*
Y44774D03*
Y64774D03*
Y84774D03*
Y104774D03*
Y124774D03*
Y144774D03*
Y164774D03*
Y184774D03*
Y204774D03*
Y224774D03*
Y244774D03*
Y264774D03*
Y284774D03*
Y304774D03*
X1837728Y324733D03*
X1830094Y333210D03*
X1830472Y960970D03*
X1837937Y973244D03*
Y993244D03*
Y1013244D03*
Y1033244D03*
Y1053244D03*
Y1073244D03*
Y1093244D03*
X1824706Y1100185D03*
Y1106145D03*
Y1093150D03*
X1837937Y1113244D03*
Y1133244D03*
Y1153244D03*
Y1173244D03*
Y1193244D03*
Y1213244D03*
X1834665Y1213239D03*
X1837937Y1253244D03*
Y1273244D03*
Y1293244D03*
Y1313244D03*
Y1333244D03*
Y1353244D03*
Y1373244D03*
Y1393244D03*
Y1433244D03*
Y1453244D03*
Y1473244D03*
Y1493244D03*
Y1513244D03*
Y1533244D03*
Y1553244D03*
Y1573244D03*
X1837933Y1636171D03*
X1832000Y1644980D03*
G54D11*
X13780Y1226024D03*
X1450591Y1086654D03*
G54D20*
X190325Y368760D03*
X279360Y636752D03*
X1650620D03*
G54D30*
G01X-20602Y-468335D02*
Y-543335D01*
X479398D01*
Y-468335D01*
X-20602D01*
G01X-8602Y-533335D02*
Y-538335D01*
G01X-10059Y-533335D02*
X-7145D01*
G01X-2235Y-538335D02*
X-4769D01*
Y-533335D01*
X-2235D01*
G01X-3249Y-535752D02*
X-4769D01*
G01X331Y-533335D02*
Y-538335D01*
X2865D01*
G01X6698Y-538502D02*
X6571Y-538418D01*
Y-538252D01*
X6698Y-538168D01*
X6825Y-538252D01*
Y-538418D01*
X6698Y-538502D01*
G01Y-536252D02*
X6571Y-536168D01*
Y-536002D01*
X6698Y-535918D01*
X6825Y-536002D01*
Y-536168D01*
X6698Y-536252D01*
G01X11481Y-540002D02*
X10848Y-539168D01*
X10531Y-538335D01*
Y-535002D01*
X10848Y-534168D01*
X11481Y-533335D01*
G01X16898D02*
X16391Y-533502D01*
X16011Y-533918D01*
X15758Y-534418D01*
X15568Y-535085D01*
X15505Y-535835D01*
X15568Y-536585D01*
X15758Y-537252D01*
X16011Y-537752D01*
X16391Y-538168D01*
X16898Y-538335D01*
X17405Y-538168D01*
X17785Y-537752D01*
X18038Y-537252D01*
X18228Y-536585D01*
X18291Y-535835D01*
X18228Y-535085D01*
X18038Y-534418D01*
X17785Y-533918D01*
X17405Y-533502D01*
X16898Y-533335D01*
G01X20605Y-537335D02*
X20985Y-537918D01*
X21491Y-538252D01*
X22061Y-538335D01*
X22568Y-538252D01*
X23075Y-537835D01*
X23391Y-537335D01*
X23455Y-536835D01*
X23328Y-536252D01*
X22885Y-535835D01*
X22441Y-535668D01*
X21871D01*
G01X22441D02*
X22821Y-535418D01*
X23138Y-535002D01*
X23265Y-534502D01*
X23138Y-534002D01*
X22821Y-533585D01*
X22251Y-533335D01*
X21681Y-533418D01*
X21111Y-533752D01*
G01X27415Y-540002D02*
X28048Y-539168D01*
X28365Y-538335D01*
Y-535002D01*
X28048Y-534168D01*
X27415Y-533335D01*
G01X30805Y-537335D02*
X31185Y-537918D01*
X31691Y-538252D01*
X32261Y-538335D01*
X32768Y-538252D01*
X33275Y-537835D01*
X33591Y-537335D01*
X33655Y-536835D01*
X33528Y-536252D01*
X33085Y-535835D01*
X32641Y-535668D01*
X32071D01*
G01X32641D02*
X33021Y-535418D01*
X33338Y-535002D01*
X33465Y-534502D01*
X33338Y-534002D01*
X33021Y-533585D01*
X32451Y-533335D01*
X31881Y-533418D01*
X31311Y-533752D01*
G01X36095Y-534168D02*
X36475Y-533668D01*
X36918Y-533418D01*
X37425Y-533335D01*
X38058Y-533502D01*
X38501Y-533918D01*
X38628Y-534418D01*
X38565Y-534918D01*
X38311Y-535335D01*
X37045Y-536168D01*
X36475Y-536752D01*
X36095Y-537585D01*
X35968Y-538335D01*
X38628D01*
G01X42271D02*
X42398Y-537252D01*
X42588Y-536335D01*
X42841Y-535502D01*
X43158Y-534585D01*
X43665Y-533335D01*
X41131D01*
G01X46675Y-536668D02*
X48321D01*
G01X51395Y-534168D02*
X51775Y-533668D01*
X52218Y-533418D01*
X52725Y-533335D01*
X53358Y-533502D01*
X53801Y-533918D01*
X53928Y-534418D01*
X53865Y-534918D01*
X53611Y-535335D01*
X52345Y-536168D01*
X51775Y-536752D01*
X51395Y-537585D01*
X51268Y-538335D01*
X53928D01*
G01X56305Y-537335D02*
X56685Y-537918D01*
X57191Y-538252D01*
X57761Y-538335D01*
X58268Y-538252D01*
X58775Y-537835D01*
X59091Y-537335D01*
X59155Y-536835D01*
X59028Y-536252D01*
X58585Y-535835D01*
X58141Y-535668D01*
X57571D01*
G01X58141D02*
X58521Y-535418D01*
X58838Y-535002D01*
X58965Y-534502D01*
X58838Y-534002D01*
X58521Y-533585D01*
X57951Y-533335D01*
X57381Y-533418D01*
X56811Y-533752D01*
G01X63558Y-538335D02*
Y-533335D01*
X61215Y-536918D01*
X64381D01*
G01X66505Y-537585D02*
X66885Y-538002D01*
X67328Y-538252D01*
X67898Y-538335D01*
X68468Y-538168D01*
X68911Y-537835D01*
X69228Y-537252D01*
X69291Y-536585D01*
X69165Y-535918D01*
X68848Y-535502D01*
X68405Y-535168D01*
X67961Y-535085D01*
X67518Y-535168D01*
X66948Y-535502D01*
X67138Y-533335D01*
X68848D01*
G01X76895Y-538335D02*
Y-533335D01*
X79301D01*
G01X78415Y-535752D02*
X76895D01*
G01X81615Y-538335D02*
X83198Y-533335D01*
X84781Y-538335D01*
G01X84211Y-536585D02*
X82185D01*
G01X86968Y-538335D02*
X89628Y-533335D01*
G01X86968D02*
X89628Y-538335D01*
G01X93398Y-538502D02*
X93271Y-538418D01*
Y-538252D01*
X93398Y-538168D01*
X93525Y-538252D01*
Y-538418D01*
X93398Y-538502D01*
G01Y-536252D02*
X93271Y-536168D01*
Y-536002D01*
X93398Y-535918D01*
X93525Y-536002D01*
Y-536168D01*
X93398Y-536252D01*
G01X98181Y-540002D02*
X97548Y-539168D01*
X97231Y-538335D01*
Y-535002D01*
X97548Y-534168D01*
X98181Y-533335D01*
G01X103598D02*
X103091Y-533502D01*
X102711Y-533918D01*
X102458Y-534418D01*
X102268Y-535085D01*
X102205Y-535835D01*
X102268Y-536585D01*
X102458Y-537252D01*
X102711Y-537752D01*
X103091Y-538168D01*
X103598Y-538335D01*
X104105Y-538168D01*
X104485Y-537752D01*
X104738Y-537252D01*
X104928Y-536585D01*
X104991Y-535835D01*
X104928Y-535085D01*
X104738Y-534418D01*
X104485Y-533918D01*
X104105Y-533502D01*
X103598Y-533335D01*
G01X107305Y-537335D02*
X107685Y-537918D01*
X108191Y-538252D01*
X108761Y-538335D01*
X109268Y-538252D01*
X109775Y-537835D01*
X110091Y-537335D01*
X110155Y-536835D01*
X110028Y-536252D01*
X109585Y-535835D01*
X109141Y-535668D01*
X108571D01*
G01X109141D02*
X109521Y-535418D01*
X109838Y-535002D01*
X109965Y-534502D01*
X109838Y-534002D01*
X109521Y-533585D01*
X108951Y-533335D01*
X108381Y-533418D01*
X107811Y-533752D01*
G01X114115Y-540002D02*
X114748Y-539168D01*
X115065Y-538335D01*
Y-535002D01*
X114748Y-534168D01*
X114115Y-533335D01*
G01X117505Y-537335D02*
X117885Y-537918D01*
X118391Y-538252D01*
X118961Y-538335D01*
X119468Y-538252D01*
X119975Y-537835D01*
X120291Y-537335D01*
X120355Y-536835D01*
X120228Y-536252D01*
X119785Y-535835D01*
X119341Y-535668D01*
X118771D01*
G01X119341D02*
X119721Y-535418D01*
X120038Y-535002D01*
X120165Y-534502D01*
X120038Y-534002D01*
X119721Y-533585D01*
X119151Y-533335D01*
X118581Y-533418D01*
X118011Y-533752D01*
G01X122921Y-537752D02*
X123365Y-538168D01*
X123871Y-538335D01*
X124378Y-538168D01*
X124821Y-537668D01*
X125138Y-536918D01*
X125265Y-536168D01*
Y-535252D01*
X125138Y-534502D01*
X124821Y-533835D01*
X124441Y-533502D01*
X123998Y-533335D01*
X123491Y-533502D01*
X123111Y-533835D01*
X122858Y-534335D01*
X122731Y-535002D01*
X122858Y-535585D01*
X123175Y-536168D01*
X123555Y-536502D01*
X123998Y-536585D01*
X124505Y-536418D01*
X124885Y-536002D01*
X125265Y-535252D01*
G01X128971Y-538335D02*
X129098Y-537252D01*
X129288Y-536335D01*
X129541Y-535502D01*
X129858Y-534585D01*
X130365Y-533335D01*
X127831D01*
G01X133375Y-536668D02*
X135021D01*
G01X137905Y-537335D02*
X138285Y-537918D01*
X138791Y-538252D01*
X139361Y-538335D01*
X139868Y-538252D01*
X140375Y-537835D01*
X140691Y-537335D01*
X140755Y-536835D01*
X140628Y-536252D01*
X140185Y-535835D01*
X139741Y-535668D01*
X139171D01*
G01X139741D02*
X140121Y-535418D01*
X140438Y-535002D01*
X140565Y-534502D01*
X140438Y-534002D01*
X140121Y-533585D01*
X139551Y-533335D01*
X138981Y-533418D01*
X138411Y-533752D01*
G01X143195Y-536252D02*
X143638Y-535668D01*
X144018Y-535335D01*
X144525Y-535168D01*
X144968Y-535335D01*
X145285Y-535668D01*
X145538Y-536168D01*
X145601Y-536752D01*
X145538Y-537252D01*
X145285Y-537752D01*
X144905Y-538168D01*
X144461Y-538335D01*
X143955Y-538168D01*
X143511Y-537668D01*
X143258Y-536918D01*
X143195Y-536085D01*
X143321Y-535002D01*
X143511Y-534418D01*
X143828Y-533835D01*
X144271Y-533418D01*
X144715Y-533335D01*
X145158Y-533502D01*
X145475Y-533918D01*
G01X149498Y-538335D02*
Y-533335D01*
X148738Y-534335D01*
G01Y-538335D02*
X150258D01*
G01X155358D02*
Y-533335D01*
X153015Y-536918D01*
X156181D01*
G01X174398Y-468335D02*
Y-543335D01*
G01Y-518335D02*
X277398D01*
Y-493335D01*
G01X174398D02*
X277398D01*
G01Y-468335D02*
Y-543335D01*
G01X279398Y-468335D02*
Y-543335D01*
G01X284905Y-528335D02*
Y-523335D01*
X286171D01*
X286678Y-523585D01*
X287058Y-523918D01*
X287375Y-524418D01*
X287628Y-525002D01*
X287691Y-525835D01*
X287628Y-526668D01*
X287375Y-527252D01*
X287058Y-527752D01*
X286678Y-528085D01*
X286171Y-528335D01*
X284905D01*
G01X289815D02*
X291398Y-523335D01*
X292981Y-528335D01*
G01X292411Y-526585D02*
X290385D01*
G01X296498Y-523335D02*
Y-528335D01*
G01X295041Y-523335D02*
X297955D01*
G01X302865Y-528335D02*
X300331D01*
Y-523335D01*
X302865D01*
G01X301851Y-525752D02*
X300331D01*
G01X306698Y-528502D02*
X306571Y-528418D01*
Y-528252D01*
X306698Y-528168D01*
X306825Y-528252D01*
Y-528418D01*
X306698Y-528502D01*
G01Y-526252D02*
X306571Y-526168D01*
Y-526002D01*
X306698Y-525918D01*
X306825Y-526002D01*
Y-526168D01*
X306698Y-526252D01*
G01X279398Y-518335D02*
X479398D01*
G01X285031Y-503335D02*
Y-498335D01*
X286551D01*
X287058Y-498585D01*
X287438Y-499168D01*
X287565Y-499835D01*
X287438Y-500502D01*
X287121Y-501002D01*
X286551Y-501252D01*
X285031D01*
G01X290258Y-503502D02*
X292538Y-498335D01*
G01X295041Y-503335D02*
Y-498335D01*
X297955Y-503335D01*
Y-498335D01*
G01X301598Y-503502D02*
X301471Y-503418D01*
Y-503252D01*
X301598Y-503168D01*
X301725Y-503252D01*
Y-503418D01*
X301598Y-503502D01*
G01Y-501252D02*
X301471Y-501168D01*
Y-501002D01*
X301598Y-500918D01*
X301725Y-501002D01*
Y-501168D01*
X301598Y-501252D01*
G01X279398Y-493335D02*
X479398D01*
G01X285031Y-478335D02*
Y-473335D01*
X286551D01*
X287058Y-473585D01*
X287438Y-474168D01*
X287565Y-474835D01*
X287438Y-475502D01*
X287121Y-476002D01*
X286551Y-476252D01*
X285031D01*
G01X290131Y-478335D02*
Y-473335D01*
X291715D01*
X292221Y-473585D01*
X292538Y-473918D01*
X292665Y-474585D01*
X292538Y-475252D01*
X292158Y-475668D01*
X291715Y-475918D01*
X290131D01*
G01X291715D02*
X292665Y-478335D01*
G01X296498D02*
X295991Y-478252D01*
X295548Y-477918D01*
X295168Y-477418D01*
X294915Y-476835D01*
X294788Y-476168D01*
Y-475502D01*
X294915Y-474835D01*
X295168Y-474252D01*
X295548Y-473752D01*
X295991Y-473418D01*
X296498Y-473335D01*
X297005Y-473418D01*
X297448Y-473752D01*
X297828Y-474252D01*
X298081Y-474835D01*
X298208Y-475502D01*
Y-476168D01*
X298081Y-476835D01*
X297828Y-477418D01*
X297448Y-477918D01*
X297005Y-478252D01*
X296498Y-478335D01*
G01X300331Y-477335D02*
X300648Y-477835D01*
X301028Y-478168D01*
X301471Y-478335D01*
X301978Y-478168D01*
X302358Y-477835D01*
X302738Y-477335D01*
X302865Y-476668D01*
Y-473335D01*
G01X307965Y-478335D02*
X305431D01*
Y-473335D01*
X307965D01*
G01X306951Y-475752D02*
X305431D01*
G01X313191Y-473752D02*
X312811Y-473502D01*
X312368Y-473335D01*
X311861D01*
X311291Y-473585D01*
X310848Y-474002D01*
X310531Y-474502D01*
X310278Y-475335D01*
X310215Y-476085D01*
X310341Y-476835D01*
X310531Y-477335D01*
X310911Y-477835D01*
X311355Y-478168D01*
X311798Y-478335D01*
X312241D01*
X312685Y-478168D01*
X313065Y-477918D01*
X313381Y-477585D01*
G01X316898Y-473335D02*
Y-478335D01*
G01X315441Y-473335D02*
X318355D01*
G01X321998Y-478502D02*
X321871Y-478418D01*
Y-478252D01*
X321998Y-478168D01*
X322125Y-478252D01*
Y-478418D01*
X321998Y-478502D01*
G01Y-476252D02*
X321871Y-476168D01*
Y-476002D01*
X321998Y-475918D01*
X322125Y-476002D01*
Y-476168D01*
X321998Y-476252D01*
G01X394258Y-543563D02*
Y-518563D01*
G01X397031Y-520835D02*
Y-525835D01*
X399565D01*
G01X402638Y-520835D02*
X404158D01*
G01X403398D02*
Y-525835D01*
G01X402638D02*
X404158D01*
G01X409005Y-523168D02*
X409258Y-522918D01*
X409448Y-522502D01*
X409575Y-521918D01*
X409448Y-521418D01*
X409195Y-521085D01*
X408751Y-520835D01*
X407041D01*
Y-525835D01*
X409131D01*
X409575Y-525502D01*
X409828Y-525002D01*
X409955Y-524418D01*
X409828Y-523835D01*
X409448Y-523335D01*
X409005Y-523168D01*
X407041D01*
G01X413598Y-526002D02*
X413471Y-525918D01*
Y-525752D01*
X413598Y-525668D01*
X413725Y-525752D01*
Y-525918D01*
X413598Y-526002D01*
G01Y-523752D02*
X413471Y-523668D01*
Y-523502D01*
X413598Y-523418D01*
X413725Y-523502D01*
Y-523668D01*
X413598Y-523752D01*
G01X437258Y-518563D02*
Y-543563D01*
G01X437398Y-518335D02*
Y-543335D01*
G01X441298Y-520835D02*
Y-525835D01*
G01X439841Y-520835D02*
X442755D01*
G01X446398Y-525835D02*
X446018Y-525752D01*
X445638Y-525418D01*
X445385Y-524835D01*
X445258Y-524168D01*
X445385Y-523502D01*
X445638Y-522918D01*
X446018Y-522585D01*
X446398Y-522502D01*
X446778Y-522585D01*
X447158Y-522918D01*
X447411Y-523502D01*
X447475Y-524168D01*
X447411Y-524835D01*
X447158Y-525418D01*
X446778Y-525752D01*
X446398Y-525835D01*
G01X451498D02*
X451118Y-525752D01*
X450738Y-525418D01*
X450485Y-524835D01*
X450358Y-524168D01*
X450485Y-523502D01*
X450738Y-522918D01*
X451118Y-522585D01*
X451498Y-522502D01*
X451878Y-522585D01*
X452258Y-522918D01*
X452511Y-523502D01*
X452575Y-524168D01*
X452511Y-524835D01*
X452258Y-525418D01*
X451878Y-525752D01*
X451498Y-525835D01*
G01X456598D02*
Y-520835D01*
G01X461698Y-526002D02*
X461571Y-525918D01*
Y-525752D01*
X461698Y-525668D01*
X461825Y-525752D01*
Y-525918D01*
X461698Y-526002D01*
G01Y-523752D02*
X461571Y-523668D01*
Y-523502D01*
X461698Y-523418D01*
X461825Y-523502D01*
Y-523668D01*
X461698Y-523752D01*
G01X437398Y-493335D02*
Y-518335D01*
G01X440031Y-500835D02*
Y-495835D01*
X441615D01*
X442121Y-496085D01*
X442438Y-496418D01*
X442565Y-497085D01*
X442438Y-497752D01*
X442058Y-498168D01*
X441615Y-498418D01*
X440031D01*
G01X441615D02*
X442565Y-500835D01*
G01X447665D02*
X445131D01*
Y-495835D01*
X447665D01*
G01X446651Y-498252D02*
X445131D01*
G01X449915Y-495835D02*
X451498Y-500835D01*
X453081Y-495835D01*
G01X456598Y-501002D02*
X456471Y-500918D01*
Y-500752D01*
X456598Y-500668D01*
X456725Y-500752D01*
Y-500918D01*
X456598Y-501002D01*
G01Y-498752D02*
X456471Y-498668D01*
Y-498502D01*
X456598Y-498418D01*
X456725Y-498502D01*
Y-498668D01*
X456598Y-498752D01*
G01X445411Y-546502D02*
X445518Y-546377D01*
X445598Y-546168D01*
X445651Y-545877D01*
X445598Y-545627D01*
X445491Y-545460D01*
X445305Y-545335D01*
X444585D01*
Y-547835D01*
X445465D01*
X445651Y-547668D01*
X445758Y-547418D01*
X445811Y-547127D01*
X445758Y-546835D01*
X445598Y-546585D01*
X445411Y-546502D01*
X444585D01*
G01X447878Y-547835D02*
Y-546168D01*
G01Y-546460D02*
X447771Y-546293D01*
X447611Y-546210D01*
X447425Y-546168D01*
X447238Y-546252D01*
X447078Y-546418D01*
X446971Y-546668D01*
X446918Y-547002D01*
X446971Y-547335D01*
X447078Y-547585D01*
X447238Y-547752D01*
X447425Y-547835D01*
X447611Y-547793D01*
X447771Y-547668D01*
X447878Y-547502D01*
G01X449198Y-547543D02*
X449331Y-547710D01*
X449518Y-547835D01*
X449678D01*
X449838Y-547752D01*
X449945Y-547627D01*
X449998Y-547460D01*
X449971Y-547210D01*
X449865Y-547085D01*
X449385Y-546835D01*
X449278Y-546543D01*
X449331Y-546335D01*
X449438Y-546210D01*
X449598Y-546168D01*
X449758Y-546210D01*
X449918Y-546335D01*
G01X451398Y-546710D02*
X452251D01*
X452171Y-546418D01*
X452038Y-546252D01*
X451851Y-546168D01*
X451665Y-546210D01*
X451505Y-546335D01*
X451398Y-546627D01*
X451345Y-546877D01*
Y-547127D01*
X451398Y-547377D01*
X451531Y-547627D01*
X451691Y-547793D01*
X451878Y-547835D01*
X452065Y-547752D01*
X452251Y-547502D01*
G01X453518Y-547835D02*
Y-545335D01*
G01Y-546585D02*
X453651Y-546335D01*
X453811Y-546210D01*
X453971Y-546168D01*
X454211Y-546252D01*
X454371Y-546418D01*
X454478Y-546710D01*
Y-547043D01*
X454425Y-547377D01*
X454318Y-547627D01*
X454131Y-547793D01*
X453971Y-547835D01*
X453811Y-547793D01*
X453651Y-547668D01*
X453518Y-547460D01*
G01X456198Y-547835D02*
X456038Y-547793D01*
X455878Y-547627D01*
X455771Y-547335D01*
X455718Y-547002D01*
X455771Y-546668D01*
X455878Y-546377D01*
X456038Y-546210D01*
X456198Y-546168D01*
X456358Y-546210D01*
X456518Y-546377D01*
X456625Y-546668D01*
X456651Y-547002D01*
X456625Y-547335D01*
X456518Y-547627D01*
X456358Y-547793D01*
X456198Y-547835D01*
G01X458878D02*
Y-546168D01*
G01Y-546460D02*
X458771Y-546293D01*
X458611Y-546210D01*
X458425Y-546168D01*
X458238Y-546252D01*
X458078Y-546418D01*
X457971Y-546668D01*
X457918Y-547002D01*
X457971Y-547335D01*
X458078Y-547585D01*
X458238Y-547752D01*
X458425Y-547835D01*
X458611Y-547793D01*
X458771Y-547668D01*
X458878Y-547502D01*
G01X460225Y-547835D02*
Y-546168D01*
G01Y-546502D02*
X460358Y-546335D01*
X460491Y-546210D01*
X460678Y-546168D01*
X460811Y-546210D01*
X460971Y-546335D01*
G01X463278Y-545335D02*
Y-547835D01*
G01Y-547460D02*
X463171Y-547668D01*
X463011Y-547793D01*
X462825Y-547835D01*
X462611Y-547752D01*
X462451Y-547543D01*
X462345Y-547293D01*
X462318Y-547002D01*
X462345Y-546710D01*
X462451Y-546460D01*
X462611Y-546252D01*
X462825Y-546168D01*
X463011Y-546210D01*
X463145Y-546293D01*
X463278Y-546460D01*
G01X466665Y-547835D02*
Y-545335D01*
X467331D01*
X467545Y-545460D01*
X467678Y-545627D01*
X467731Y-545960D01*
X467678Y-546293D01*
X467518Y-546502D01*
X467331Y-546627D01*
X466665D01*
G01X467331D02*
X467731Y-547835D01*
G01X468998Y-546710D02*
X469851D01*
X469771Y-546418D01*
X469638Y-546252D01*
X469451Y-546168D01*
X469265Y-546210D01*
X469105Y-546335D01*
X468998Y-546627D01*
X468945Y-546877D01*
Y-547127D01*
X468998Y-547377D01*
X469131Y-547627D01*
X469291Y-547793D01*
X469478Y-547835D01*
X469665Y-547752D01*
X469851Y-547502D01*
G01X471118Y-546168D02*
X471598Y-547835D01*
X472078Y-546168D01*
G01X473798Y-547918D02*
X473745Y-547877D01*
Y-547793D01*
X473798Y-547752D01*
X473851Y-547793D01*
Y-547877D01*
X473798Y-547918D01*
G01X475545Y-547543D02*
X475731Y-547752D01*
X475945Y-547835D01*
X476158Y-547752D01*
X476345Y-547502D01*
X476478Y-547127D01*
X476531Y-546752D01*
Y-546293D01*
X476478Y-545918D01*
X476345Y-545585D01*
X476185Y-545418D01*
X475998Y-545335D01*
X475785Y-545418D01*
X475625Y-545585D01*
X475518Y-545835D01*
X475465Y-546168D01*
X475518Y-546460D01*
X475651Y-546752D01*
X475811Y-546918D01*
X475998Y-546960D01*
X476211Y-546877D01*
X476371Y-546668D01*
X476531Y-546293D01*
G01X478411Y-546502D02*
X478518Y-546377D01*
X478598Y-546168D01*
X478651Y-545877D01*
X478598Y-545627D01*
X478491Y-545460D01*
X478305Y-545335D01*
X477585D01*
Y-547835D01*
X478465D01*
X478651Y-547668D01*
X478758Y-547418D01*
X478811Y-547127D01*
X478758Y-546835D01*
X478598Y-546585D01*
X478411Y-546502D01*
X477585D01*
G01X-1490433Y-1677216D02*
Y3837819D01*
X4496476D01*
Y-1677216D01*
X-1490433D01*
G01X-7782Y-515685D02*
X-6215D01*
Y-517575D01*
X-6685Y-518205D01*
X-7234Y-518625D01*
X-8017Y-518835D01*
X-8800Y-518625D01*
X-9349Y-518205D01*
X-9819Y-517575D01*
X-10132Y-516840D01*
X-10289Y-516000D01*
Y-515265D01*
X-10132Y-514635D01*
X-9819Y-513900D01*
X-9349Y-513270D01*
X-8879Y-512850D01*
X-8252Y-512535D01*
X-7704D01*
X-7077Y-512745D01*
X-6607Y-513165D01*
G01X-3675Y-512535D02*
Y-517050D01*
X-3362Y-517995D01*
X-2735Y-518625D01*
X-1952Y-518835D01*
X-1169Y-518625D01*
X-542Y-517995D01*
X-229Y-517050D01*
Y-512535D01*
G01X3408D02*
X5288D01*
G01X4348D02*
Y-518835D01*
G01X3408D02*
X5288D01*
G01X9003Y-517995D02*
X9630Y-518520D01*
X10335Y-518835D01*
X10961D01*
X11588Y-518520D01*
X12058Y-517995D01*
X12293Y-517260D01*
X12136Y-516525D01*
X11745Y-515895D01*
X11040Y-515475D01*
X10100Y-515265D01*
X9551Y-514845D01*
X9316Y-514110D01*
X9473Y-513375D01*
X9865Y-512850D01*
X10413Y-512535D01*
X10961D01*
X11510Y-512745D01*
X11980Y-513270D01*
G01X15303Y-518835D02*
Y-512535D01*
G01X18593D02*
Y-518835D01*
G01Y-515685D02*
X15303D01*
G01X21290Y-518835D02*
X23248Y-512535D01*
X25206Y-518835D01*
G01X24501Y-516630D02*
X21995D01*
G01X27746Y-518835D02*
Y-512535D01*
X31350Y-518835D01*
Y-512535D01*
G01X40425Y-518835D02*
Y-512535D01*
X41991D01*
X42618Y-512850D01*
X43088Y-513270D01*
X43480Y-513900D01*
X43793Y-514635D01*
X43871Y-515685D01*
X43793Y-516735D01*
X43480Y-517470D01*
X43088Y-518100D01*
X42618Y-518520D01*
X41991Y-518835D01*
X40425D01*
G01X47508Y-512535D02*
X49388D01*
G01X48448D02*
Y-518835D01*
G01X47508D02*
X49388D01*
G01X53103Y-517995D02*
X53730Y-518520D01*
X54435Y-518835D01*
X55061D01*
X55688Y-518520D01*
X56158Y-517995D01*
X56393Y-517260D01*
X56236Y-516525D01*
X55845Y-515895D01*
X55140Y-515475D01*
X54200Y-515265D01*
X53651Y-514845D01*
X53416Y-514110D01*
X53573Y-513375D01*
X53965Y-512850D01*
X54513Y-512535D01*
X55061D01*
X55610Y-512745D01*
X56080Y-513270D01*
G01X61048Y-512535D02*
Y-518835D01*
G01X59246Y-512535D02*
X62850D01*
G01X67348Y-519045D02*
X67191Y-518940D01*
Y-518730D01*
X67348Y-518625D01*
X67505Y-518730D01*
Y-518940D01*
X67348Y-519045D01*
G01X73491Y-519990D02*
X73805Y-518625D01*
G01X79948Y-512535D02*
Y-518835D01*
G01X78146Y-512535D02*
X81750D01*
G01X84290Y-518835D02*
X86248Y-512535D01*
X88206Y-518835D01*
G01X87501Y-516630D02*
X84995D01*
G01X92548Y-518835D02*
X91921Y-518730D01*
X91373Y-518310D01*
X90903Y-517680D01*
X90590Y-516945D01*
X90433Y-516105D01*
Y-515265D01*
X90590Y-514425D01*
X90903Y-513690D01*
X91373Y-513060D01*
X91921Y-512640D01*
X92548Y-512535D01*
X93175Y-512640D01*
X93723Y-513060D01*
X94193Y-513690D01*
X94506Y-514425D01*
X94663Y-515265D01*
Y-516105D01*
X94506Y-516945D01*
X94193Y-517680D01*
X93723Y-518310D01*
X93175Y-518730D01*
X92548Y-518835D01*
G01X98848D02*
Y-516000D01*
X97281Y-512535D01*
G01X100415D02*
X98848Y-516000D01*
G01X103425Y-512535D02*
Y-517050D01*
X103738Y-517995D01*
X104365Y-518625D01*
X105148Y-518835D01*
X105931Y-518625D01*
X106558Y-517995D01*
X106871Y-517050D01*
Y-512535D01*
G01X109490Y-518835D02*
X111448Y-512535D01*
X113406Y-518835D01*
G01X112701Y-516630D02*
X110195D01*
G01X115946Y-518835D02*
Y-512535D01*
X119550Y-518835D01*
Y-512535D01*
G01X-6529Y-523060D02*
X-6999Y-522745D01*
X-7547Y-522535D01*
X-8174D01*
X-8879Y-522850D01*
X-9427Y-523375D01*
X-9819Y-524005D01*
X-10132Y-525055D01*
X-10210Y-526000D01*
X-10054Y-526945D01*
X-9819Y-527575D01*
X-9349Y-528205D01*
X-8800Y-528625D01*
X-8252Y-528835D01*
X-7704D01*
X-7155Y-528625D01*
X-6685Y-528310D01*
X-6294Y-527890D01*
G01X-2892Y-522535D02*
X-1012D01*
G01X-1952D02*
Y-528835D01*
G01X-2892D02*
X-1012D01*
G01X4348Y-522535D02*
Y-528835D01*
G01X2546Y-522535D02*
X6150D01*
G01X10648Y-528835D02*
Y-526000D01*
X9081Y-522535D01*
G01X12215D02*
X10648Y-526000D01*
G01X21525Y-527575D02*
X21995Y-528310D01*
X22621Y-528730D01*
X23326Y-528835D01*
X23953Y-528730D01*
X24580Y-528205D01*
X24971Y-527575D01*
X25050Y-526945D01*
X24893Y-526210D01*
X24345Y-525685D01*
X23796Y-525475D01*
X23091D01*
G01X23796D02*
X24266Y-525160D01*
X24658Y-524635D01*
X24815Y-524005D01*
X24658Y-523375D01*
X24266Y-522850D01*
X23561Y-522535D01*
X22856Y-522640D01*
X22151Y-523060D01*
G01X27825Y-527575D02*
X28295Y-528310D01*
X28921Y-528730D01*
X29626Y-528835D01*
X30253Y-528730D01*
X30880Y-528205D01*
X31271Y-527575D01*
X31350Y-526945D01*
X31193Y-526210D01*
X30645Y-525685D01*
X30096Y-525475D01*
X29391D01*
G01X30096D02*
X30566Y-525160D01*
X30958Y-524635D01*
X31115Y-524005D01*
X30958Y-523375D01*
X30566Y-522850D01*
X29861Y-522535D01*
X29156Y-522640D01*
X28451Y-523060D01*
G01X34125Y-527575D02*
X34595Y-528310D01*
X35221Y-528730D01*
X35926Y-528835D01*
X36553Y-528730D01*
X37180Y-528205D01*
X37571Y-527575D01*
X37650Y-526945D01*
X37493Y-526210D01*
X36945Y-525685D01*
X36396Y-525475D01*
X35691D01*
G01X36396D02*
X36866Y-525160D01*
X37258Y-524635D01*
X37415Y-524005D01*
X37258Y-523375D01*
X36866Y-522850D01*
X36161Y-522535D01*
X35456Y-522640D01*
X34751Y-523060D01*
G01X41991Y-528835D02*
X42148Y-527470D01*
X42383Y-526315D01*
X42696Y-525265D01*
X43088Y-524110D01*
X43715Y-522535D01*
X40581D01*
G01X48291Y-528835D02*
X48448Y-527470D01*
X48683Y-526315D01*
X48996Y-525265D01*
X49388Y-524110D01*
X50015Y-522535D01*
X46881D01*
G01X54591Y-529990D02*
X54905Y-528625D01*
G01X61048Y-522535D02*
Y-528835D01*
G01X59246Y-522535D02*
X62850D01*
G01X65390Y-528835D02*
X67348Y-522535D01*
X69306Y-528835D01*
G01X68601Y-526630D02*
X66095D01*
G01X72708Y-522535D02*
X74588D01*
G01X73648D02*
Y-528835D01*
G01X72708D02*
X74588D01*
G01X77598Y-522535D02*
X78695Y-528835D01*
X79948Y-522535D01*
X81201Y-528835D01*
X82298Y-522535D01*
G01X84290Y-528835D02*
X86248Y-522535D01*
X88206Y-528835D01*
G01X87501Y-526630D02*
X84995D01*
G01X90746Y-528835D02*
Y-522535D01*
X94350Y-528835D01*
Y-522535D01*
G01X104756Y-530935D02*
X103973Y-529885D01*
X103581Y-528835D01*
Y-524635D01*
X103973Y-523585D01*
X104756Y-522535D01*
G01X116181Y-528835D02*
Y-522535D01*
X118140D01*
X118766Y-522850D01*
X119158Y-523270D01*
X119315Y-524110D01*
X119158Y-524950D01*
X118688Y-525475D01*
X118140Y-525790D01*
X116181D01*
G01X118140D02*
X119315Y-528835D01*
G01X124048Y-529045D02*
X123891Y-528940D01*
Y-528730D01*
X124048Y-528625D01*
X124205Y-528730D01*
Y-528940D01*
X124048Y-529045D01*
G01X130348Y-528835D02*
X129721Y-528730D01*
X129173Y-528310D01*
X128703Y-527680D01*
X128390Y-526945D01*
X128233Y-526105D01*
Y-525265D01*
X128390Y-524425D01*
X128703Y-523690D01*
X129173Y-523060D01*
X129721Y-522640D01*
X130348Y-522535D01*
X130975Y-522640D01*
X131523Y-523060D01*
X131993Y-523690D01*
X132306Y-524425D01*
X132463Y-525265D01*
Y-526105D01*
X132306Y-526945D01*
X131993Y-527680D01*
X131523Y-528310D01*
X130975Y-528730D01*
X130348Y-528835D01*
G01X136648Y-529045D02*
X136491Y-528940D01*
Y-528730D01*
X136648Y-528625D01*
X136805Y-528730D01*
Y-528940D01*
X136648Y-529045D01*
G01X144671Y-523060D02*
X144201Y-522745D01*
X143653Y-522535D01*
X143026D01*
X142321Y-522850D01*
X141773Y-523375D01*
X141381Y-524005D01*
X141068Y-525055D01*
X140990Y-526000D01*
X141146Y-526945D01*
X141381Y-527575D01*
X141851Y-528205D01*
X142400Y-528625D01*
X142948Y-528835D01*
X143496D01*
X144045Y-528625D01*
X144515Y-528310D01*
X144906Y-527890D01*
G01X149248Y-529045D02*
X149091Y-528940D01*
Y-528730D01*
X149248Y-528625D01*
X149405Y-528730D01*
Y-528940D01*
X149248Y-529045D01*
G01X155940Y-530935D02*
X156723Y-529885D01*
X157115Y-528835D01*
Y-524635D01*
X156723Y-523585D01*
X155940Y-522535D01*
G01X-10054Y-508835D02*
Y-502535D01*
X-6450Y-508835D01*
Y-502535D01*
G01X-1952Y-508835D02*
X-2579Y-508730D01*
X-3127Y-508310D01*
X-3597Y-507680D01*
X-3910Y-506945D01*
X-4067Y-506105D01*
Y-505265D01*
X-3910Y-504425D01*
X-3597Y-503690D01*
X-3127Y-503060D01*
X-2579Y-502640D01*
X-1952Y-502535D01*
X-1325Y-502640D01*
X-777Y-503060D01*
X-307Y-503690D01*
X6Y-504425D01*
X163Y-505265D01*
Y-506105D01*
X6Y-506945D01*
X-307Y-507680D01*
X-777Y-508310D01*
X-1325Y-508730D01*
X-1952Y-508835D01*
G01X4348Y-509045D02*
X4191Y-508940D01*
Y-508730D01*
X4348Y-508625D01*
X4505Y-508730D01*
Y-508940D01*
X4348Y-509045D01*
G01X9160Y-503585D02*
X9630Y-502955D01*
X10178Y-502640D01*
X10805Y-502535D01*
X11588Y-502745D01*
X12136Y-503270D01*
X12293Y-503900D01*
X12215Y-504530D01*
X11901Y-505055D01*
X10335Y-506105D01*
X9630Y-506840D01*
X9160Y-507890D01*
X9003Y-508835D01*
X12293D01*
G01X16948D02*
Y-502535D01*
X16008Y-503795D01*
G01Y-508835D02*
X17888D01*
G01X23248D02*
Y-502535D01*
X22308Y-503795D01*
G01Y-508835D02*
X24188D01*
G01X29391Y-509990D02*
X29705Y-508625D01*
G01X33498Y-502535D02*
X34595Y-508835D01*
X35848Y-502535D01*
X37101Y-508835D01*
X38198Y-502535D01*
G01X43715Y-508835D02*
X40581D01*
Y-502535D01*
X43715D01*
G01X42461Y-505580D02*
X40581D01*
G01X46646Y-508835D02*
Y-502535D01*
X50250Y-508835D01*
Y-502535D01*
G01X53103Y-508835D02*
Y-502535D01*
G01X56393D02*
Y-508835D01*
G01Y-505685D02*
X53103D01*
G01X59325Y-502535D02*
Y-507050D01*
X59638Y-507995D01*
X60265Y-508625D01*
X61048Y-508835D01*
X61831Y-508625D01*
X62458Y-507995D01*
X62771Y-507050D01*
Y-502535D01*
G01X65390Y-508835D02*
X67348Y-502535D01*
X69306Y-508835D01*
G01X68601Y-506630D02*
X66095D01*
G01X78460Y-503585D02*
X78930Y-502955D01*
X79478Y-502640D01*
X80105Y-502535D01*
X80888Y-502745D01*
X81436Y-503270D01*
X81593Y-503900D01*
X81515Y-504530D01*
X81201Y-505055D01*
X79635Y-506105D01*
X78930Y-506840D01*
X78460Y-507890D01*
X78303Y-508835D01*
X81593D01*
G01X84446D02*
Y-502535D01*
X88050Y-508835D01*
Y-502535D01*
G01X90825Y-508835D02*
Y-502535D01*
X92391D01*
X93018Y-502850D01*
X93488Y-503270D01*
X93880Y-503900D01*
X94193Y-504635D01*
X94271Y-505685D01*
X94193Y-506735D01*
X93880Y-507470D01*
X93488Y-508100D01*
X93018Y-508520D01*
X92391Y-508835D01*
X90825D01*
G01X103581D02*
Y-502535D01*
X105540D01*
X106166Y-502850D01*
X106558Y-503270D01*
X106715Y-504110D01*
X106558Y-504950D01*
X106088Y-505475D01*
X105540Y-505790D01*
X103581D01*
G01X105540D02*
X106715Y-508835D01*
G01X109725D02*
Y-502535D01*
X111291D01*
X111918Y-502850D01*
X112388Y-503270D01*
X112780Y-503900D01*
X113093Y-504635D01*
X113171Y-505685D01*
X113093Y-506735D01*
X112780Y-507470D01*
X112388Y-508100D01*
X111918Y-508520D01*
X111291Y-508835D01*
X109725D01*
G01X117748Y-509045D02*
X117591Y-508940D01*
Y-508730D01*
X117748Y-508625D01*
X117905Y-508730D01*
Y-508940D01*
X117748Y-509045D01*
G01X14048Y-498135D02*
X11528Y-497718D01*
X9323Y-496052D01*
X7433Y-493552D01*
X6173Y-490635D01*
X5543Y-487302D01*
Y-483968D01*
X6173Y-480635D01*
X7433Y-477718D01*
X9323Y-475219D01*
X11528Y-473552D01*
X14048Y-473135D01*
X16568Y-473552D01*
X18773Y-475219D01*
X20663Y-477718D01*
X21923Y-480635D01*
X22553Y-483968D01*
Y-487302D01*
X21923Y-490635D01*
X20663Y-493552D01*
X18773Y-496052D01*
X16568Y-497718D01*
X14048Y-498135D01*
G01X16568Y-491468D02*
X20348Y-498135D01*
G01X33893Y-481469D02*
Y-493135D01*
X35153Y-496052D01*
X37043Y-497718D01*
X39248Y-498135D01*
X41453Y-497718D01*
X43343Y-496052D01*
X44603Y-493135D01*
G01Y-498135D02*
Y-481469D01*
G01X70118Y-498135D02*
Y-481469D01*
G01Y-484385D02*
X68858Y-482719D01*
X66968Y-481885D01*
X64763Y-481469D01*
X62558Y-482302D01*
X60668Y-483968D01*
X59408Y-486469D01*
X58778Y-489802D01*
X59408Y-493135D01*
X60668Y-495636D01*
X62558Y-497302D01*
X64763Y-498135D01*
X66968Y-497718D01*
X68858Y-496469D01*
X70118Y-494802D01*
G01X84293Y-498135D02*
Y-481469D01*
G01Y-485635D02*
X85553Y-483552D01*
X87443Y-481885D01*
X89963Y-481469D01*
X92168Y-481885D01*
X94058Y-483552D01*
X95003Y-486469D01*
Y-498135D01*
G01X114848Y-473135D02*
Y-498135D01*
G01X110438Y-481469D02*
X119258D01*
G01X145718Y-498135D02*
Y-481469D01*
G01Y-484385D02*
X144458Y-482719D01*
X142568Y-481885D01*
X140363Y-481469D01*
X138158Y-482302D01*
X136268Y-483968D01*
X135008Y-486469D01*
X134378Y-489802D01*
X135008Y-493135D01*
X136268Y-495636D01*
X138158Y-497302D01*
X140363Y-498135D01*
X142568Y-497718D01*
X144458Y-496469D01*
X145718Y-494802D01*
G01X185398Y-477835D02*
Y-485835D01*
X189398D01*
G01X197198D02*
Y-480502D01*
G01Y-481435D02*
X196798Y-480902D01*
X196198Y-480635D01*
X195498Y-480502D01*
X194798Y-480768D01*
X194198Y-481302D01*
X193798Y-482102D01*
X193598Y-483168D01*
X193798Y-484235D01*
X194198Y-485035D01*
X194798Y-485568D01*
X195498Y-485835D01*
X196198Y-485702D01*
X196798Y-485302D01*
X197198Y-484769D01*
G01X201298Y-488235D02*
X201898Y-488502D01*
X202698Y-488235D01*
X203198Y-487702D01*
X203598Y-487035D01*
X204198Y-484902D01*
X205498Y-480502D01*
G01X202298D02*
X204198Y-484902D01*
G01X209898Y-482235D02*
X213098D01*
X212798Y-481302D01*
X212298Y-480768D01*
X211598Y-480502D01*
X210898Y-480635D01*
X210298Y-481035D01*
X209898Y-481968D01*
X209698Y-482769D01*
Y-483568D01*
X209898Y-484368D01*
X210398Y-485168D01*
X210998Y-485702D01*
X211698Y-485835D01*
X212398Y-485568D01*
X213098Y-484769D01*
G01X217998Y-485835D02*
Y-480502D01*
G01Y-481568D02*
X218498Y-481035D01*
X218998Y-480635D01*
X219698Y-480502D01*
X220198Y-480635D01*
X220798Y-481035D01*
G01X211398Y-535835D02*
Y-532235D01*
X209398Y-527835D01*
G01X213398D02*
X211398Y-532235D01*
G01X217698Y-530502D02*
Y-534235D01*
X218098Y-535168D01*
X218698Y-535702D01*
X219398Y-535835D01*
X220098Y-535702D01*
X220698Y-535168D01*
X221098Y-534235D01*
G01Y-535835D02*
Y-530502D01*
G01X225698Y-535835D02*
Y-530502D01*
G01Y-531835D02*
X226098Y-531168D01*
X226698Y-530635D01*
X227498Y-530502D01*
X228198Y-530635D01*
X228798Y-531168D01*
X229098Y-532102D01*
Y-535835D01*
G01X237198D02*
Y-530502D01*
G01Y-531435D02*
X236798Y-530902D01*
X236198Y-530635D01*
X235498Y-530502D01*
X234798Y-530768D01*
X234198Y-531302D01*
X233798Y-532102D01*
X233598Y-533168D01*
X233798Y-534235D01*
X234198Y-535035D01*
X234798Y-535568D01*
X235498Y-535835D01*
X236198Y-535702D01*
X236798Y-535302D01*
X237198Y-534769D01*
G01X210198Y-500335D02*
X212598D01*
G01X211398D02*
Y-508335D01*
G01X210198D02*
X212598D01*
G01X217098D02*
Y-500335D01*
X221698Y-508335D01*
Y-500335D01*
G01X225198Y-507135D02*
X225798Y-507802D01*
X226498Y-508202D01*
X227398Y-508335D01*
X228298Y-508068D01*
X228998Y-507535D01*
X229498Y-506602D01*
X229598Y-505535D01*
X229398Y-504468D01*
X228898Y-503802D01*
X228198Y-503268D01*
X227498Y-503135D01*
X226798Y-503268D01*
X225898Y-503802D01*
X226198Y-500335D01*
X228898D01*
G01X236398Y-485835D02*
Y-477835D01*
X235198Y-479435D01*
G01Y-485835D02*
X237598D01*
G01X245598D02*
Y-477835D01*
X241898Y-483568D01*
X246898D01*
G01X311998Y-529168D02*
X312598Y-528368D01*
X313298Y-527968D01*
X314098Y-527835D01*
X315098Y-528102D01*
X315798Y-528768D01*
X315998Y-529568D01*
X315898Y-530369D01*
X315498Y-531035D01*
X313498Y-532368D01*
X312598Y-533302D01*
X311998Y-534635D01*
X311798Y-535835D01*
X315998D01*
G01X321898Y-527835D02*
X321098Y-528102D01*
X320498Y-528768D01*
X320098Y-529568D01*
X319798Y-530635D01*
X319698Y-531835D01*
X319798Y-533035D01*
X320098Y-534102D01*
X320498Y-534902D01*
X321098Y-535568D01*
X321898Y-535835D01*
X322698Y-535568D01*
X323298Y-534902D01*
X323698Y-534102D01*
X323998Y-533035D01*
X324098Y-531835D01*
X323998Y-530635D01*
X323698Y-529568D01*
X323298Y-528768D01*
X322698Y-528102D01*
X321898Y-527835D01*
G01X327998Y-529168D02*
X328598Y-528368D01*
X329298Y-527968D01*
X330098Y-527835D01*
X331098Y-528102D01*
X331798Y-528768D01*
X331998Y-529568D01*
X331898Y-530369D01*
X331498Y-531035D01*
X329498Y-532368D01*
X328598Y-533302D01*
X327998Y-534635D01*
X327798Y-535835D01*
X331998D01*
G01X335698Y-534235D02*
X336298Y-535168D01*
X337098Y-535702D01*
X337998Y-535835D01*
X338798Y-535702D01*
X339598Y-535035D01*
X340098Y-534235D01*
X340198Y-533435D01*
X339998Y-532502D01*
X339298Y-531835D01*
X338598Y-531568D01*
X337698D01*
G01X338598D02*
X339198Y-531168D01*
X339698Y-530502D01*
X339898Y-529702D01*
X339698Y-528902D01*
X339198Y-528235D01*
X338298Y-527835D01*
X337398Y-527968D01*
X336498Y-528502D01*
G01X344098Y-536102D02*
X347698Y-527835D01*
G01X353898D02*
X353098Y-528102D01*
X352498Y-528768D01*
X352098Y-529568D01*
X351798Y-530635D01*
X351698Y-531835D01*
X351798Y-533035D01*
X352098Y-534102D01*
X352498Y-534902D01*
X353098Y-535568D01*
X353898Y-535835D01*
X354698Y-535568D01*
X355298Y-534902D01*
X355698Y-534102D01*
X355998Y-533035D01*
X356098Y-531835D01*
X355998Y-530635D01*
X355698Y-529568D01*
X355298Y-528768D01*
X354698Y-528102D01*
X353898Y-527835D01*
G01X361898Y-535835D02*
Y-527835D01*
X360698Y-529435D01*
G01Y-535835D02*
X363098D01*
G01X368098Y-536102D02*
X371698Y-527835D01*
G01X377898D02*
X377098Y-528102D01*
X376498Y-528768D01*
X376098Y-529568D01*
X375798Y-530635D01*
X375698Y-531835D01*
X375798Y-533035D01*
X376098Y-534102D01*
X376498Y-534902D01*
X377098Y-535568D01*
X377898Y-535835D01*
X378698Y-535568D01*
X379298Y-534902D01*
X379698Y-534102D01*
X379998Y-533035D01*
X380098Y-531835D01*
X379998Y-530635D01*
X379698Y-529568D01*
X379298Y-528768D01*
X378698Y-528102D01*
X377898Y-527835D01*
G01X384198Y-534902D02*
X384898Y-535568D01*
X385698Y-535835D01*
X386498Y-535568D01*
X387198Y-534769D01*
X387698Y-533568D01*
X387898Y-532368D01*
Y-530902D01*
X387698Y-529702D01*
X387198Y-528635D01*
X386598Y-528102D01*
X385898Y-527835D01*
X385098Y-528102D01*
X384498Y-528635D01*
X384098Y-529435D01*
X383898Y-530502D01*
X384098Y-531435D01*
X384598Y-532368D01*
X385198Y-532902D01*
X385898Y-533035D01*
X386698Y-532769D01*
X387298Y-532102D01*
X387898Y-530902D01*
G01X311698Y-510835D02*
Y-502835D01*
X313698D01*
X314498Y-503235D01*
X315098Y-503768D01*
X315598Y-504568D01*
X315998Y-505502D01*
X316098Y-506835D01*
X315998Y-508168D01*
X315598Y-509102D01*
X315098Y-509902D01*
X314498Y-510435D01*
X313698Y-510835D01*
X311698D01*
G01X319398D02*
X321898Y-502835D01*
X324398Y-510835D01*
G01X323498Y-508035D02*
X320298D01*
G01X329898Y-502835D02*
X329098Y-503102D01*
X328498Y-503768D01*
X328098Y-504568D01*
X327798Y-505635D01*
X327698Y-506835D01*
X327798Y-508035D01*
X328098Y-509102D01*
X328498Y-509902D01*
X329098Y-510568D01*
X329898Y-510835D01*
X330698Y-510568D01*
X331298Y-509902D01*
X331698Y-509102D01*
X331998Y-508035D01*
X332098Y-506835D01*
X331998Y-505635D01*
X331698Y-504568D01*
X331298Y-503768D01*
X330698Y-503102D01*
X329898Y-502835D01*
G01X335998Y-510835D02*
Y-502835D01*
X339798D01*
G01X338398Y-506702D02*
X335998D01*
G01X345898Y-502835D02*
X345098Y-503102D01*
X344498Y-503768D01*
X344098Y-504568D01*
X343798Y-505635D01*
X343698Y-506835D01*
X343798Y-508035D01*
X344098Y-509102D01*
X344498Y-509902D01*
X345098Y-510568D01*
X345898Y-510835D01*
X346698Y-510568D01*
X347298Y-509902D01*
X347698Y-509102D01*
X347998Y-508035D01*
X348098Y-506835D01*
X347998Y-505635D01*
X347698Y-504568D01*
X347298Y-503768D01*
X346698Y-503102D01*
X345898Y-502835D01*
G01X353898D02*
Y-510835D01*
G01X351598Y-502835D02*
X356198D01*
G01X363898Y-510835D02*
X359898D01*
Y-502835D01*
X363898D01*
G01X362298Y-506702D02*
X359898D01*
G01X370698Y-506568D02*
X371098Y-506168D01*
X371398Y-505502D01*
X371598Y-504568D01*
X371398Y-503768D01*
X370998Y-503235D01*
X370298Y-502835D01*
X367598D01*
Y-510835D01*
X370898D01*
X371598Y-510302D01*
X371998Y-509502D01*
X372198Y-508568D01*
X371998Y-507635D01*
X371398Y-506835D01*
X370698Y-506568D01*
X367598D01*
G01X376698Y-502835D02*
X379098D01*
G01X377898D02*
Y-510835D01*
G01X376698D02*
X379098D01*
G01X383998D02*
Y-502835D01*
X387798D01*
G01X386398Y-506702D02*
X383998D01*
G01X393898Y-502835D02*
X393098Y-503102D01*
X392498Y-503768D01*
X392098Y-504568D01*
X391798Y-505635D01*
X391698Y-506835D01*
X391798Y-508035D01*
X392098Y-509102D01*
X392498Y-509902D01*
X393098Y-510568D01*
X393898Y-510835D01*
X394698Y-510568D01*
X395298Y-509902D01*
X395698Y-509102D01*
X395998Y-508035D01*
X396098Y-506835D01*
X395998Y-505635D01*
X395698Y-504568D01*
X395298Y-503768D01*
X394698Y-503102D01*
X393898Y-502835D01*
G01X329498Y-485835D02*
Y-477835D01*
X333298D01*
G01X331898Y-481702D02*
X329498D01*
G01X339398Y-477835D02*
X338598Y-478102D01*
X337998Y-478768D01*
X337598Y-479568D01*
X337298Y-480635D01*
X337198Y-481835D01*
X337298Y-483035D01*
X337598Y-484102D01*
X337998Y-484902D01*
X338598Y-485568D01*
X339398Y-485835D01*
X340198Y-485568D01*
X340798Y-484902D01*
X341198Y-484102D01*
X341498Y-483035D01*
X341598Y-481835D01*
X341498Y-480635D01*
X341198Y-479568D01*
X340798Y-478768D01*
X340198Y-478102D01*
X339398Y-477835D01*
G01X347398D02*
Y-485835D01*
G01X345098Y-477835D02*
X349698D01*
G01X352398Y-488502D02*
X358398D01*
G01X361898Y-482235D02*
X365098D01*
X364798Y-481302D01*
X364298Y-480768D01*
X363598Y-480502D01*
X362898Y-480635D01*
X362298Y-481035D01*
X361898Y-481968D01*
X361698Y-482769D01*
Y-483568D01*
X361898Y-484368D01*
X362398Y-485168D01*
X362998Y-485702D01*
X363698Y-485835D01*
X364398Y-485568D01*
X365098Y-484769D01*
G01X369898Y-480502D02*
X372898Y-485835D01*
G01Y-480502D02*
X369898Y-485835D01*
G01X377598Y-488502D02*
Y-480502D01*
G01Y-481702D02*
X378098Y-481035D01*
X378598Y-480635D01*
X379398Y-480502D01*
X380098Y-480635D01*
X380798Y-481302D01*
X381098Y-482235D01*
X381198Y-483168D01*
X381098Y-484102D01*
X380798Y-485035D01*
X380198Y-485568D01*
X379398Y-485835D01*
X378698Y-485702D01*
X377998Y-485302D01*
X377598Y-484769D01*
G01X389198Y-485835D02*
Y-480502D01*
G01Y-481435D02*
X388798Y-480902D01*
X388198Y-480635D01*
X387498Y-480502D01*
X386798Y-480768D01*
X386198Y-481302D01*
X385798Y-482102D01*
X385598Y-483168D01*
X385798Y-484235D01*
X386198Y-485035D01*
X386798Y-485568D01*
X387498Y-485835D01*
X388198Y-485702D01*
X388798Y-485302D01*
X389198Y-484769D01*
G01X393698Y-485835D02*
Y-480502D01*
G01Y-481835D02*
X394098Y-481168D01*
X394698Y-480635D01*
X395498Y-480502D01*
X396198Y-480635D01*
X396798Y-481168D01*
X397098Y-482102D01*
Y-485835D01*
G01X405198Y-477835D02*
Y-485835D01*
G01Y-484635D02*
X404798Y-485302D01*
X404198Y-485702D01*
X403498Y-485835D01*
X402698Y-485568D01*
X402098Y-484902D01*
X401698Y-484102D01*
X401598Y-483168D01*
X401698Y-482235D01*
X402098Y-481435D01*
X402698Y-480768D01*
X403498Y-480502D01*
X404198Y-480635D01*
X404698Y-480902D01*
X405198Y-481435D01*
G01X409898Y-482235D02*
X413098D01*
X412798Y-481302D01*
X412298Y-480768D01*
X411598Y-480502D01*
X410898Y-480635D01*
X410298Y-481035D01*
X409898Y-481968D01*
X409698Y-482769D01*
Y-483568D01*
X409898Y-484368D01*
X410398Y-485168D01*
X410998Y-485702D01*
X411698Y-485835D01*
X412398Y-485568D01*
X413098Y-484769D01*
G01X417998Y-485835D02*
Y-480502D01*
G01Y-481568D02*
X418498Y-481035D01*
X418998Y-480635D01*
X419698Y-480502D01*
X420198Y-480635D01*
X420798Y-481035D01*
G01X424398Y-488502D02*
X430398D01*
G01X433598Y-485835D02*
Y-477835D01*
G01Y-481835D02*
X434098Y-481035D01*
X434698Y-480635D01*
X435298Y-480502D01*
X436198Y-480768D01*
X436798Y-481302D01*
X437198Y-482235D01*
Y-483302D01*
X436998Y-484368D01*
X436598Y-485168D01*
X435898Y-485702D01*
X435298Y-485835D01*
X434698Y-485702D01*
X434098Y-485302D01*
X433598Y-484635D01*
G01X445198Y-477835D02*
Y-485835D01*
G01Y-484635D02*
X444798Y-485302D01*
X444198Y-485702D01*
X443498Y-485835D01*
X442698Y-485568D01*
X442098Y-484902D01*
X441698Y-484102D01*
X441598Y-483168D01*
X441698Y-482235D01*
X442098Y-481435D01*
X442698Y-480768D01*
X443498Y-480502D01*
X444198Y-480635D01*
X444698Y-480902D01*
X445198Y-481435D01*
G01X400398Y-538835D02*
Y-530835D01*
X399198Y-532435D01*
G01Y-538835D02*
X401598D01*
G01X406498Y-535502D02*
X407198Y-534568D01*
X407798Y-534035D01*
X408598Y-533768D01*
X409298Y-534035D01*
X409798Y-534568D01*
X410198Y-535368D01*
X410298Y-536302D01*
X410198Y-537102D01*
X409798Y-537902D01*
X409198Y-538568D01*
X408498Y-538835D01*
X407698Y-538568D01*
X406998Y-537769D01*
X406598Y-536568D01*
X406498Y-535235D01*
X406698Y-533502D01*
X406998Y-532568D01*
X407498Y-531635D01*
X408198Y-530968D01*
X408898Y-530835D01*
X409598Y-531102D01*
X410098Y-531768D01*
G01X416398Y-539102D02*
X416198Y-538968D01*
Y-538702D01*
X416398Y-538568D01*
X416598Y-538702D01*
Y-538968D01*
X416398Y-539102D01*
G01X422498Y-535502D02*
X423198Y-534568D01*
X423798Y-534035D01*
X424598Y-533768D01*
X425298Y-534035D01*
X425798Y-534568D01*
X426198Y-535368D01*
X426298Y-536302D01*
X426198Y-537102D01*
X425798Y-537902D01*
X425198Y-538568D01*
X424498Y-538835D01*
X423698Y-538568D01*
X422998Y-537769D01*
X422598Y-536568D01*
X422498Y-535235D01*
X422698Y-533502D01*
X422998Y-532568D01*
X423498Y-531635D01*
X424198Y-530968D01*
X424898Y-530835D01*
X425598Y-531102D01*
X426098Y-531768D01*
G01X445398Y-538835D02*
Y-530835D01*
X444198Y-532435D01*
G01Y-538835D02*
X446598D01*
G01X453198D02*
X453398Y-537102D01*
X453698Y-535635D01*
X454098Y-534302D01*
X454598Y-532835D01*
X455398Y-530835D01*
X451398D01*
G01X461398Y-539102D02*
X461198Y-538968D01*
Y-538702D01*
X461398Y-538568D01*
X461598Y-538702D01*
Y-538968D01*
X461398Y-539102D01*
G01X467498Y-532168D02*
X468098Y-531368D01*
X468798Y-530968D01*
X469598Y-530835D01*
X470598Y-531102D01*
X471298Y-531768D01*
X471498Y-532568D01*
X471398Y-533369D01*
X470998Y-534035D01*
X468998Y-535368D01*
X468098Y-536302D01*
X467498Y-537635D01*
X467298Y-538835D01*
X471498D01*
G01X465498Y-513835D02*
Y-505835D01*
X469298D01*
G01X467898Y-509702D02*
X465498D01*
G54D12*
X23622Y1604724D03*
X62205Y765197D03*
X74016Y333464D03*
X102224Y70866D03*
X409488Y1604724D03*
X433130Y70866D03*
X661674Y23622D03*
X785039Y1547638D03*
X890217Y23622D03*
X1055905Y1547637D03*
X1118760Y23622D03*
X1347303Y70866D03*
X1377559Y286220D03*
X1431457Y1604724D03*
X1575846Y23622D03*
X1766929Y333464D03*
X1778740Y765197D03*
X1795010Y23622D03*
X1817323Y1604724D03*
G54D21*
X420661Y1119422D03*
X423141Y1113822D03*
Y1119422D03*
X418181Y1113822D03*
Y1119422D03*
X420661Y1113822D03*
X455269Y1119422D03*
X450309Y1113822D03*
Y1119422D03*
X452789Y1113822D03*
Y1119422D03*
X455269Y1113822D03*
X488728Y1119422D03*
X483768Y1113822D03*
X486248D03*
Y1119422D03*
X483768D03*
X488728Y1113822D03*
X518376D03*
Y1119422D03*
X520856Y1113822D03*
Y1119422D03*
X515896Y1113822D03*
Y1119422D03*
X1332355Y1113822D03*
Y1119422D03*
X1334835Y1113822D03*
Y1119422D03*
X1337315Y1113822D03*
Y1119422D03*
X1366963D03*
Y1113822D03*
X1364483Y1119422D03*
Y1113822D03*
X1369443Y1119422D03*
Y1113822D03*
X1397942Y1119422D03*
X1400422D03*
Y1113822D03*
X1397942D03*
X1402902Y1119422D03*
Y1113822D03*
X1432550Y1119422D03*
Y1113822D03*
X1430070Y1119422D03*
Y1113822D03*
X1435030Y1119422D03*
Y1113822D03*
G54D31*
G01X48429Y916430D02*
X54001D01*
X55268Y917697D01*
X73405D01*
X95889Y895213D01*
Y893372D01*
X126022Y863239D01*
X132400D01*
X207154Y832275D01*
X246554D01*
X248967Y834688D01*
X279590D01*
X279978Y834300D01*
X384500D01*
X387500Y837300D01*
X445599D01*
X490231Y881932D01*
X509791D01*
G01X84367Y878286D02*
Y857001D01*
X84867Y856501D01*
X88515D01*
X89045Y857031D01*
Y864697D01*
X89575Y865227D01*
X91045D01*
X91575Y864697D01*
Y857031D01*
X92105Y856501D01*
X93575D01*
X94105Y857031D01*
Y864697D01*
X94635Y865227D01*
X96105D01*
X96635Y864697D01*
Y857031D01*
X97165Y856501D01*
X103961D01*
X236742Y801500D01*
X361520D01*
X381628Y793172D01*
X386770Y788030D01*
X402777Y781400D01*
X434790D01*
X455554Y790000D01*
X480270D01*
X506865Y778984D01*
X541879D01*
X543068Y777795D01*
X553175D01*
X572544Y769772D01*
X577638D01*
G01X571493Y763090D02*
X552644Y775685D01*
X540489D01*
X539300Y776874D01*
X504384D01*
X478729Y787500D01*
X455170D01*
X435373Y779300D01*
X435235D01*
X435210Y779290D01*
X403198D01*
X402777Y779116D01*
X402332Y779300D01*
X401818D01*
X386082Y785818D01*
X385719Y786181D01*
X385575Y786241D01*
X380555Y791261D01*
X361631Y799100D01*
X236468D01*
X158652Y831332D01*
X157753Y831935D01*
X105928Y853400D01*
X78041D01*
X76528Y854913D01*
Y857738D01*
X77058Y858268D01*
X81549D01*
X82079Y858798D01*
Y860268D01*
X81549Y860798D01*
X77058D01*
X76528Y861328D01*
Y862798D01*
X77058Y863328D01*
X81549D01*
X82079Y863858D01*
Y865328D01*
X81549Y865858D01*
X77058D01*
X76528Y866388D01*
Y878533D01*
G01X80339Y897943D02*
X91480Y886802D01*
X99047Y868534D01*
X106075Y859970D01*
X112054Y855975D01*
X236566Y804400D01*
X371240D01*
X382829Y799600D01*
X390936D01*
X392061Y800725D01*
X403125D01*
X407478Y798922D01*
X416600Y789800D01*
X446020D01*
X455178Y793593D01*
X489069D01*
X496194Y796544D01*
X510006D01*
X513704Y795012D01*
X516590Y792126D01*
X523978Y789066D01*
X561050D01*
X562387Y788512D01*
X570927Y779972D01*
X576729Y775137D01*
X578204D01*
G01X72035Y898346D02*
Y898834D01*
X72064Y899048D01*
X72090Y899302D01*
X72073Y899373D01*
Y899729D01*
X72078Y899777D01*
X72108Y899812D01*
X73760Y901464D01*
X73798Y901496D01*
X73826Y901511D01*
X73897Y901535D01*
X82066D01*
X97565Y886036D01*
X102674Y882622D01*
X107224Y878072D01*
X113907Y861937D01*
X120570Y855274D01*
X236940Y807071D01*
X366759D01*
X366797Y807033D01*
X396689D01*
X407918Y802382D01*
X417700Y792600D01*
X445465D01*
X455122Y796600D01*
X482677D01*
X487077Y801000D01*
X555337D01*
X567051Y796148D01*
X578999Y784200D01*
X586375D01*
X587183Y785008D01*
G01X424993Y728291D02*
X422977Y726275D01*
X128166D01*
X111993Y710102D01*
G01X1418023Y765343D02*
X1409843D01*
X1388258Y743758D01*
X1087286D01*
X1060460Y716932D01*
X1028666D01*
X1018340Y706606D01*
X1001939D01*
X995489Y700156D01*
X956761D01*
X952991Y696386D01*
X933198D01*
X933191Y696392D01*
X914647D01*
X912069Y698970D01*
X905511D01*
X904781Y699700D01*
X895200D01*
X886400Y708500D01*
X877555D01*
X867766Y718289D01*
X855244D01*
X848799Y711844D01*
Y705190D01*
X847089Y703480D01*
X831586D01*
X828976Y700870D01*
X795129D01*
X759739Y736260D01*
X710290D01*
X706727Y739823D01*
X579291D01*
X575092Y735624D01*
X549724D01*
X541500Y727400D01*
X431101D01*
X427401Y731100D01*
X417485D01*
X414070Y727685D01*
X146466D01*
X119099Y755052D01*
G01X1309753Y877589D02*
Y876203D01*
X1309472Y875922D01*
Y875821D01*
X1301926Y868275D01*
Y866086D01*
X1288400Y852560D01*
Y850693D01*
X1286869Y849162D01*
X1285053D01*
X1283815Y850400D01*
X1282046D01*
X1279058Y849162D01*
X1275396Y845500D01*
X1265123D01*
X1256158Y836535D01*
X1092387D01*
X1047973Y792121D01*
Y791952D01*
X1046858Y790837D01*
X1046689D01*
X1046476Y790624D01*
X1011686D01*
X1005273Y784211D01*
Y781274D01*
X1005108Y781109D01*
Y776278D01*
X997496Y768666D01*
Y743892D01*
X988388Y734784D01*
X968789D01*
X965805Y731800D01*
X953131D01*
X952426Y732505D01*
X874595D01*
X860600Y746500D01*
X857000D01*
X850500Y740000D01*
Y737000D01*
X848500Y735000D01*
X784403D01*
X770626Y748777D01*
X581625D01*
X575436Y742588D01*
X554006D01*
X540553Y729135D01*
X433739D01*
X429974Y732900D01*
X414000D01*
X410195Y729095D01*
X149996D01*
X120250Y758841D01*
G01X122437Y860775D02*
X134011D01*
X206993Y830545D01*
X247991D01*
X250446Y833000D01*
X279283D01*
X279393Y832890D01*
X394591D01*
X397401Y835700D01*
X417900D01*
X420800Y832800D01*
X426400D01*
X429300Y835700D01*
X446900D01*
X491267Y880067D01*
X508961D01*
X509001Y880027D01*
X510581D01*
X511696Y881142D01*
Y882722D01*
X511656Y882762D01*
Y884994D01*
X551281Y924619D01*
X678618D01*
X706599Y952600D01*
X809012D01*
X817912Y943700D01*
X844372D01*
X846327Y941745D01*
X871955D01*
X874710Y938990D01*
X945591D01*
X950698Y944097D01*
X1081601D01*
X1085904Y948400D01*
X1202806D01*
X1207676Y953270D01*
X1294825D01*
X1296795Y951300D01*
X1334300D01*
X1346400Y939200D01*
X1350701D01*
X1355401Y934500D01*
X1357900D01*
X1360550Y931850D01*
Y929150D01*
X1361581Y928119D01*
X1362981D01*
X1364500Y926600D01*
Y924000D01*
X1372012Y916488D01*
Y895100D01*
G01X125698Y857515D02*
X127678Y855535D01*
X237184Y810177D01*
X247676D01*
X247716Y810137D01*
X249296D01*
X249336Y810177D01*
X292845D01*
X302868Y820200D01*
X373844D01*
X374064Y820420D01*
X389801D01*
X391091Y819130D01*
X458324D01*
X458374Y819180D01*
X458870D01*
X486220Y846530D01*
X489852D01*
X496776Y853454D01*
X556926D01*
X557046Y853574D01*
X558626D01*
X558746Y853454D01*
X583123D01*
X593315Y843262D01*
X752780D01*
X752842Y843200D01*
X809400D01*
X816871Y850671D01*
X823929D01*
X824505Y850095D01*
X831410D01*
X834815Y853500D01*
X848342D01*
X849256Y854414D01*
Y855995D01*
X850371Y857110D01*
X851951D01*
X853361Y855700D01*
X863437D01*
X867610Y851527D01*
Y846091D01*
X876035Y837666D01*
X882534D01*
X883400Y836800D01*
Y833999D01*
X886699Y830700D01*
X904199D01*
X906299Y832800D01*
X909005D01*
X910930Y830875D01*
X921076D01*
X924900Y834699D01*
Y836900D01*
X931149Y843149D01*
Y844594D01*
X947455Y860900D01*
X949300D01*
X953316Y864916D01*
Y868801D01*
X972652Y888137D01*
X982120D01*
X985383Y891400D01*
X1015204D01*
X1016008Y892204D01*
X1020245D01*
X1020246Y892203D01*
X1022570D01*
X1022571Y892204D01*
X1024949D01*
X1031845Y899100D01*
X1071531D01*
X1094568Y922137D01*
X1181463D01*
X1184505Y919095D01*
X1187941D01*
X1191246Y922400D01*
X1271869D01*
X1273279Y923810D01*
X1281049D01*
X1283048Y921811D01*
X1310431D01*
X1320107Y912135D01*
X1336257D01*
X1336259Y912133D01*
X1336767D01*
X1343195Y905705D01*
Y897306D01*
X1347317Y893184D01*
Y885478D01*
X1345252Y883413D01*
G01X129666Y857514D02*
X131417Y855763D01*
X222859Y817886D01*
X242500D01*
X243986Y816400D01*
X251000D01*
X252486Y817886D01*
X263522D01*
X268468Y822832D01*
X297531D01*
X300299Y825600D01*
X391501D01*
X393691Y823410D01*
X452511D01*
X473127Y844026D01*
Y844042D01*
X474242Y845157D01*
X474258D01*
X481491Y852390D01*
X489589D01*
X495203Y858004D01*
X586500D01*
X595673Y848831D01*
X804080D01*
X816318Y861069D01*
X832963D01*
X837394Y865500D01*
X852081D01*
X857011Y870430D01*
X862187D01*
X869993Y862624D01*
X886600D01*
G01X160733Y1056594D02*
X164926D01*
X194920Y1026600D01*
X386700D01*
X444239Y969061D01*
X540506D01*
X545370Y973925D01*
X588634D01*
X589907Y975198D01*
X619303D01*
X626538Y982433D01*
Y1015644D01*
X618982Y1023200D01*
Y1031252D01*
X621592Y1033862D01*
G01X160627Y1053561D02*
X163842D01*
X193766Y1023637D01*
X387062D01*
X443048Y967651D01*
X541091D01*
X545955Y972515D01*
X589219D01*
X590492Y973788D01*
X619888D01*
X627948Y981848D01*
Y1016229D01*
X627868Y1016309D01*
Y1017621D01*
X621479Y1024010D01*
Y1030482D01*
G01X1345252Y880263D02*
X1348400Y883411D01*
Y894864D01*
X1345252Y898012D01*
Y906447D01*
X1337467Y914232D01*
X1320312D01*
X1311323Y923221D01*
X1283633D01*
X1281634Y925220D01*
X1272694D01*
X1271574Y924100D01*
X1093013D01*
X1073479Y904566D01*
X1021592D01*
X1010520Y893494D01*
X984388D01*
X982232Y891338D01*
X973335D01*
X954253Y872256D01*
X949545D01*
X948202Y870913D01*
Y863643D01*
X929309Y844750D01*
Y843809D01*
X923400Y837900D01*
Y835300D01*
X920700Y832600D01*
X911200D01*
X909500Y834300D01*
X905400D01*
X903300Y832200D01*
X889458D01*
X888958Y832700D01*
Y834606D01*
X887698Y835866D01*
Y835983D01*
X884605Y839076D01*
X877325D01*
X869346Y847055D01*
Y854284D01*
X866230Y857400D01*
X857000D01*
X854900Y859500D01*
X850300D01*
X848200Y857400D01*
X837840D01*
X837340Y857900D01*
X831199D01*
X827940Y854641D01*
X818640D01*
X810010Y846011D01*
X594503D01*
X594224Y846290D01*
X593714D01*
X593404Y846600D01*
X592424D01*
X584160Y854864D01*
X559331D01*
X559211Y854984D01*
X556461D01*
X556341Y854864D01*
X496191D01*
X489267Y847940D01*
X485635D01*
X458285Y820590D01*
X457789D01*
X457739Y820540D01*
X391759D01*
X389899Y822400D01*
X302621D01*
X295062Y814841D01*
X241204D01*
G01X254058Y819851D02*
X260268D01*
X265497Y825080D01*
X297385D01*
X299765Y827460D01*
X392440D01*
X394545Y825355D01*
X431555D01*
X436180Y829980D01*
X456945D01*
X480765Y853800D01*
X489004D01*
X494618Y859414D01*
X494714D01*
X494826Y859526D01*
X586973D01*
X596258Y850241D01*
X803495D01*
X816007Y862753D01*
Y866508D01*
X822920Y873421D01*
X825510D01*
X827860Y871071D01*
X833887D01*
X836267Y873451D01*
X862854D01*
X870532Y865773D01*
X880000D01*
G01X889178Y905619D02*
X887261Y907536D01*
X821831D01*
X818791Y910576D01*
X815824D01*
X812747Y913653D01*
X620818D01*
X572606Y865441D01*
X525064D01*
X522515Y867990D01*
X491691D01*
X455491Y831790D01*
X434690D01*
X430065Y827165D01*
X396835D01*
X394730Y829270D01*
X299015D01*
X296635Y826890D01*
X263203D01*
X258527Y822214D01*
X250345D01*
X248556Y824003D01*
G01X255289Y824340D02*
X259649Y828700D01*
X295885D01*
X298265Y831080D01*
X396569D01*
X399089Y833600D01*
X417100D01*
X419900Y830800D01*
X428869D01*
X431669Y833600D01*
X454601D01*
X490801Y869800D01*
X524199D01*
X526499Y867500D01*
X550724D01*
X555516Y872292D01*
X576281D01*
X623483Y919494D01*
X810249D01*
X816970Y912773D01*
X819714D01*
X822568Y909919D01*
X872151D01*
X874682Y912450D01*
Y916096D01*
X876628Y918042D01*
G01X1354185Y906498D02*
Y908015D01*
X1352681Y909519D01*
X1344381D01*
X1337421Y916479D01*
X1320115D01*
X1311243Y925351D01*
X1309753D01*
X1309033Y924631D01*
X1284218D01*
X1282219Y926630D01*
X1272109D01*
X1271222Y925743D01*
X1092209D01*
X1072762Y906296D01*
X1020250D01*
X1013124Y899170D01*
X993587D01*
X991582Y901175D01*
X988876D01*
X982223Y894522D01*
X973593D01*
X962923Y883852D01*
X952076D01*
X945475Y877251D01*
Y862911D01*
X927883Y845319D01*
Y844383D01*
X921700Y838200D01*
Y836110D01*
X919800Y834210D01*
X912191D01*
X910901Y835500D01*
X904001D01*
X902201Y833700D01*
X891700D01*
X884900Y840500D01*
X879701D01*
X871688Y848513D01*
Y857272D01*
X860696Y868264D01*
X857449D01*
X855215Y866030D01*
Y863618D01*
X853097Y861500D01*
X837545D01*
X835637Y859592D01*
X829491D01*
X825950Y856051D01*
X813295D01*
X804665Y847421D01*
X595088D01*
X594809Y847700D01*
X594299D01*
X585405Y856594D01*
X495894D01*
X488650Y849350D01*
X485050D01*
X457700Y822000D01*
X392700D01*
X390510Y824190D01*
X300991D01*
X297521Y820725D01*
X274096D01*
G01X333985Y1017945D02*
X336829Y1015101D01*
X389740D01*
X449041Y955800D01*
X531040D01*
X532863Y953977D01*
X552967D01*
X560790Y961800D01*
X571501D01*
X576532Y956769D01*
X586970D01*
X592001Y961800D01*
X681700D01*
X711100Y991200D01*
X742354D01*
X747244Y986310D01*
X898102D01*
X901992Y990200D01*
X916499D01*
X923789Y997490D01*
X993473D01*
X998828Y1002845D01*
X1064975D01*
X1066717Y1004587D01*
X1170746D01*
X1183562Y1017403D01*
X1204897D01*
X1213825Y1008475D01*
X1252524D01*
X1256920Y1004079D01*
X1334632D01*
X1346840Y991871D01*
Y990010D01*
X1366630Y970220D01*
X1380507D01*
X1419027Y931700D01*
X1447300D01*
X1451000Y928000D01*
X1458699D01*
X1488138Y898561D01*
Y878339D01*
G01X341077Y1018056D02*
X389844D01*
X446333Y961567D01*
X526393D01*
X528216Y959744D01*
X535744D01*
X546705Y970705D01*
X589969D01*
X591242Y971978D01*
X678163D01*
X707470Y1001285D01*
X825389D01*
X829974Y996700D01*
X866399D01*
X870389Y1000690D01*
X909050D01*
X912279Y1003919D01*
X965553D01*
X986335Y1024701D01*
Y1024758D01*
X987450Y1025873D01*
X987507D01*
X994534Y1032900D01*
X1009061D01*
X1014283Y1027678D01*
X1020700D01*
X1022178Y1026200D01*
X1042900D01*
X1046200Y1029500D01*
X1062418D01*
X1063369Y1028549D01*
X1063482D01*
X1071201Y1020830D01*
X1173969D01*
X1184099Y1030960D01*
X1219717D01*
X1231567Y1019110D01*
X1273555D01*
X1276106Y1016559D01*
X1291591D01*
X1291592Y1016560D01*
X1292440D01*
X1297000Y1012000D01*
X1336951D01*
X1354080Y994871D01*
Y993010D01*
X1369630Y977460D01*
X1389139D01*
X1398436Y968163D01*
X1407111D01*
X1419674Y955600D01*
X1457320D01*
X1458720Y957000D01*
X1462000D01*
G01X1378312Y895200D02*
Y896813D01*
X1378905Y897406D01*
Y920388D01*
X1376500Y922793D01*
Y932000D01*
X1372400Y936100D01*
X1366382D01*
X1358744Y943738D01*
X1356508D01*
X1342746Y957500D01*
X1088346D01*
X1081927Y951081D01*
X1033781D01*
X1033062Y951800D01*
X1032036D01*
X1032009Y951827D01*
X1030429D01*
X1030402Y951800D01*
X1030340D01*
X1028148Y949608D01*
X1013954D01*
X1012462Y951100D01*
X1004302D01*
X1002302Y949100D01*
X944837D01*
X942291Y946554D01*
X916327D01*
X913681Y949200D01*
X875802D01*
X873802Y947200D01*
X819420D01*
X810499Y956121D01*
X704822D01*
X677181Y928480D01*
X521780D01*
X469861Y876561D01*
Y870061D01*
X438791Y838991D01*
X386991D01*
X384462Y836462D01*
X358207D01*
G01X365691Y815127D02*
X368318Y812500D01*
X372900D01*
X377200Y816800D01*
X388301D01*
X389591Y815510D01*
X460070D01*
X460120Y815560D01*
X460370D01*
X484301Y839491D01*
X499390D01*
X503999Y844100D01*
X521300D01*
X524500Y840900D01*
X547091D01*
X547336Y840655D01*
Y840598D01*
X548451Y839483D01*
X550031D01*
X551146Y840598D01*
Y840655D01*
X553691Y843200D01*
X563306D01*
X566864Y839642D01*
X751280D01*
X762771Y828151D01*
X816652D01*
X821076Y832575D01*
X825176D01*
X828901Y836300D01*
X830900D01*
X833800Y839200D01*
X841699D01*
X847448Y833451D01*
X852226D01*
X856275Y837500D01*
X864800D01*
X869815Y832485D01*
Y826962D01*
X875713Y821064D01*
X877242Y820430D01*
X907551D01*
X915293Y823635D01*
X927836D01*
X931371Y827170D01*
X943001D01*
X950840Y835009D01*
Y842103D01*
X955937Y847200D01*
X957500D01*
X974266Y863966D01*
X1004266D01*
X1010484Y870184D01*
X1024384D01*
X1031500Y877300D01*
X1061500D01*
X1093548Y909348D01*
X1220965D01*
X1226894Y903419D01*
X1274720D01*
X1276572Y905271D01*
X1285094D01*
X1287363Y907540D01*
X1303361D01*
X1307800Y903101D01*
Y897600D01*
X1309100Y896300D01*
X1326066D01*
X1329504Y892862D01*
G01X1331073Y896282D02*
X1328197Y899158D01*
X1316563D01*
X1314396Y901325D01*
X1312136D01*
X1304111Y909350D01*
X1286613D01*
X1286363Y909100D01*
X1272899D01*
X1270841Y911158D01*
X1092557D01*
X1062999Y881600D01*
X1033199D01*
X1023761Y872162D01*
X1009562D01*
X1003176Y865776D01*
X971750D01*
X964828Y858854D01*
Y857427D01*
X956654Y849253D01*
X955289D01*
X948200Y842164D01*
Y838047D01*
X944453Y834300D01*
X932201D01*
X923346Y825445D01*
X914390D01*
X906651Y822240D01*
X877604D01*
X876738Y822599D01*
X872568Y826769D01*
Y832472D01*
X863716Y841324D01*
X852014D01*
X851974Y841364D01*
X850394D01*
X850354Y841324D01*
X849214D01*
X849174Y841364D01*
X847594D01*
X847554Y841324D01*
X833801D01*
X830460Y844665D01*
X826563D01*
X821174Y839276D01*
Y835874D01*
X817408Y832108D01*
X761842D01*
X752578Y841372D01*
X752110D01*
X752030Y841452D01*
X591389D01*
X584441Y848400D01*
X539046D01*
X538046Y847400D01*
X533700D01*
X529500Y851600D01*
X505801D01*
X495502Y841301D01*
X483551D01*
X459620Y817370D01*
X459370D01*
X459320Y817320D01*
X390341D01*
X389051Y818610D01*
X374814D01*
X371507Y815303D01*
G01X1285302Y881783D02*
X1284047D01*
X1283630Y882200D01*
X1279299D01*
X1275581Y878482D01*
X1270921D01*
X1268728Y876289D01*
X1088885D01*
X1071910Y859314D01*
Y840570D01*
X1058350Y827010D01*
X1037791D01*
X1033621Y831180D01*
X1026141D01*
X1020664Y825703D01*
X1016416D01*
X997813Y807100D01*
X967900D01*
X964300Y803500D01*
X952300D01*
X949886Y805914D01*
Y808543D01*
X947068Y811361D01*
X937596D01*
X933605Y809707D01*
X926998Y803100D01*
X905561D01*
X903914Y804747D01*
X867887D01*
X866855Y803715D01*
X866469D01*
X866284Y803900D01*
X858653D01*
X853987Y808566D01*
X830566D01*
X829000Y807000D01*
X810500D01*
X808573Y808927D01*
X645310D01*
X627169Y827068D01*
X627141D01*
X626490Y827719D01*
X578846D01*
X573883Y822756D01*
X565544D01*
X560600Y827700D01*
X546409D01*
X543609Y830500D01*
X538091D01*
X536501Y828910D01*
X503950D01*
X503940Y828900D01*
X503904D01*
X485204Y810200D01*
X470000D01*
X464700Y804900D01*
X413108D01*
X402864Y809143D01*
X367671D01*
X362042Y814772D01*
G01X387958Y813700D02*
X484149D01*
X502569Y832120D01*
X502605D01*
X502615Y832130D01*
X523231D01*
X526655Y835554D01*
X534086D01*
X534850Y834790D01*
X633397D01*
X649438Y818749D01*
X701573D01*
X704322Y816000D01*
X733000D01*
G01X383710Y1007283D02*
X391747D01*
X452930Y946100D01*
X594301D01*
X602201Y954000D01*
X686030D01*
X701375Y969345D01*
X825542D01*
X826270Y970073D01*
X839627D01*
X843110Y966590D01*
X910810D01*
X915088Y962312D01*
X919438D01*
X920553Y963427D01*
Y966778D01*
X928113Y974338D01*
X938882D01*
X942650Y970570D01*
X971596D01*
X975578Y974552D01*
X1074753D01*
X1082901Y982700D01*
X1177359D01*
X1189159Y994500D01*
X1204957D01*
X1207857Y991600D01*
X1211440D01*
X1212325Y990715D01*
X1299284D01*
X1305989Y984010D01*
X1309350D01*
X1311590Y981770D01*
X1337160D01*
X1361380Y957550D01*
X1374494D01*
X1418944Y913100D01*
X1443970D01*
X1457195Y899875D01*
Y894774D01*
X1463535Y888434D01*
Y884978D01*
X1466031Y882482D01*
Y857383D01*
X1486957Y836457D01*
G01X382465Y1012430D02*
X389571D01*
X453956Y948045D01*
X593045D01*
X601100Y956100D01*
X685299D01*
X701104Y971905D01*
X841611D01*
X845116Y968400D01*
X904300D01*
X913104Y977204D01*
X922824D01*
X926820Y981200D01*
X939700D01*
X944900Y976000D01*
X969346D01*
X974584Y981238D01*
X999157D01*
X1000519Y982600D01*
X1074099D01*
X1080159Y988660D01*
X1173700D01*
X1187230Y1002190D01*
X1203410D01*
X1213075Y992525D01*
X1308641D01*
X1310900Y990266D01*
Y986100D01*
X1313420Y983580D01*
X1337910D01*
X1362130Y959360D01*
X1375244D01*
X1419604Y915000D01*
X1446341D01*
X1465565Y895776D01*
Y887056D01*
X1468295Y884326D01*
Y859206D01*
X1487401Y840100D01*
X1489849D01*
X1492625Y837324D01*
G01X582100Y787600D02*
Y798700D01*
X571900Y808900D01*
X551100D01*
X548200Y811800D01*
X535000D01*
X531700Y808500D01*
X490300D01*
X488200Y806400D01*
X487038D01*
X487036Y806402D01*
X485456D01*
X485454Y806400D01*
X473000D01*
X467000Y800400D01*
X442000D01*
X436700Y795100D01*
X424100D01*
X423700Y795500D01*
G01X416029Y1371572D02*
Y1366471D01*
X423300Y1359200D01*
Y1319000D01*
X429185Y1313115D01*
X431885D01*
G01X430600Y797400D02*
Y800300D01*
X433200Y802900D01*
X466100D01*
X471400Y808200D01*
X472240D01*
X472250Y808210D01*
X484704D01*
X484706Y808212D01*
X485812D01*
X504700Y827100D01*
X517202D01*
X517702Y826600D01*
G01X451460Y974695D02*
X455081Y971074D01*
X539959D01*
X544620Y975735D01*
X587883D01*
X589156Y977008D01*
X618553D01*
X623900Y982355D01*
Y1013998D01*
X616869Y1021029D01*
Y1032833D01*
X620004Y1035968D01*
X644132D01*
X667600Y1012500D01*
X827499D01*
X833126Y1006873D01*
X845527D01*
X851744Y1013090D01*
X904269D01*
X908856Y1017677D01*
G01X459245Y807152D02*
X464392D01*
X469250Y812010D01*
X484454D01*
X503154Y830710D01*
X503190D01*
X503200Y830720D01*
X535121D01*
X536801Y832400D01*
X624369D01*
X627891Y828878D01*
X627919D01*
X646060Y810737D01*
X806467D01*
X807770Y812040D01*
X831100D01*
X833126Y814066D01*
X842290D01*
X843405Y812951D01*
Y811370D01*
X844399Y810376D01*
X854737D01*
X857613Y807500D01*
X859500D01*
X860500Y808500D01*
X865805D01*
X867748Y806557D01*
X927895D01*
X932734Y811396D01*
X937019Y813171D01*
X947818D01*
X950671Y810318D01*
X967282D01*
X968400Y809200D01*
X988200D01*
X992300Y813300D01*
X1000100D01*
X1004700Y817900D01*
Y820364D01*
X1014800Y830464D01*
X1017036D01*
X1018900Y828600D01*
X1021001D01*
X1025391Y832990D01*
X1034411D01*
X1038506Y828895D01*
X1057675D01*
X1070100Y841320D01*
Y860064D01*
X1088135Y878099D01*
X1090454D01*
X1090485Y878130D01*
X1268009D01*
X1270171Y880292D01*
X1271592D01*
X1278521Y887221D01*
X1281169D01*
X1284590Y883800D01*
X1293500D01*
G01X1375163Y895200D02*
Y899837D01*
X1374095Y900905D01*
Y917605D01*
X1368500Y923200D01*
Y931600D01*
X1367500Y932600D01*
X1363200D01*
X1359000Y936800D01*
X1355955D01*
X1340045Y952710D01*
X1297380D01*
X1295410Y954680D01*
X1207091D01*
X1205349Y952938D01*
X1088447D01*
X1081016Y945507D01*
X948407D01*
X943500Y940600D01*
X906000D01*
X903445Y943155D01*
X846912D01*
X844957Y945110D01*
X819515D01*
X809914Y954711D01*
X705511D01*
X676829Y926029D01*
X521530D01*
X476911Y881410D01*
Y873389D01*
X465492Y861970D01*
G01X458120Y974701D02*
X459621Y973200D01*
X537438D01*
X541783Y977545D01*
X587133D01*
X588406Y978818D01*
X617803D01*
X621278Y982293D01*
Y1006364D01*
X614497Y1013145D01*
Y1034121D01*
X618345Y1037969D01*
X646706D01*
X670175Y1014500D01*
X827901D01*
X828301Y1014900D01*
X900219D01*
X908422Y1023103D01*
G01X1169256Y694983D02*
X1153266D01*
X1149652Y698597D01*
X1071803D01*
X1038968Y665762D01*
X978706D01*
X974160Y670308D01*
X906792D01*
X903027Y674073D01*
X837961D01*
X823534Y688500D01*
X663100D01*
X659300Y684700D01*
X587600D01*
X574000Y671100D01*
X540043D01*
X522709Y688434D01*
X510993D01*
X498815Y676256D01*
X495345D01*
X488765Y669676D01*
Y667224D01*
G01X479448Y828594D02*
X488535Y837681D01*
X500140D01*
X504659Y842200D01*
X519751D01*
X523451Y838500D01*
X533700D01*
X535600Y836600D01*
X639547D01*
X655356Y820791D01*
X702600D01*
X704891Y818500D01*
X811548D01*
X812219Y817829D01*
X814485D01*
X816440Y819784D01*
X838038D01*
X839469Y821215D01*
X852400D01*
X857615Y816000D01*
X867100D01*
X870200Y812900D01*
X874846D01*
X875936Y813990D01*
X909384D01*
X913756Y815800D01*
X920300D01*
X923400Y812700D01*
X929482D01*
X931440Y814658D01*
X936427Y816721D01*
X965421D01*
X966200Y817500D01*
Y822998D01*
X965300Y823898D01*
Y830011D01*
X966454Y831165D01*
X996021D01*
X997194Y832338D01*
Y834978D01*
X1008652Y846436D01*
X1022836D01*
X1029863Y853463D01*
X1058944D01*
X1102132Y896651D01*
X1185411D01*
X1189593Y892469D01*
X1251854D01*
X1258485Y899100D01*
X1271000D01*
X1273800Y896300D01*
X1274800D01*
X1276700Y898200D01*
Y899600D01*
X1278000Y900900D01*
X1284962D01*
X1287227Y898635D01*
X1293224D01*
X1296866Y894993D01*
G01X506702Y978947D02*
X497694D01*
X487091Y989550D01*
G01X812440Y862306D02*
X811812D01*
X801157Y851651D01*
X597149D01*
X587416Y861384D01*
X524102D01*
X520556Y864930D01*
X501630D01*
X500187Y863487D01*
X494854D01*
X490706Y859339D01*
G01X503144Y957934D02*
X534235D01*
X536069Y956100D01*
X552299D01*
X559899Y963700D01*
X572300D01*
X577222Y958778D01*
X585978D01*
X590960Y963760D01*
X680699D01*
X710239Y993300D01*
X742800D01*
X743090Y993010D01*
X743104D01*
X747994Y988120D01*
X897352D01*
X901332Y992100D01*
X910440D01*
X912690Y994350D01*
G01X493091Y989550D02*
X501249Y981392D01*
X503933D01*
G01X920090Y666714D02*
X918216Y668588D01*
X905911D01*
X901845Y672654D01*
X837135D01*
X823289Y686500D01*
X663501D01*
X660001Y683000D01*
X588301D01*
X574601Y669300D01*
X538559D01*
X521540Y686319D01*
G01X1305740Y877534D02*
X1303828Y876742D01*
X1290669Y863583D01*
Y861069D01*
X1287144Y857544D01*
X1280898D01*
X1269032Y852622D01*
X1266051D01*
X1253584Y840155D01*
X1169509D01*
X1169505Y840164D01*
X1158283Y851386D01*
X1097913D01*
X1059527Y813000D01*
X1042606D01*
X1038283Y808677D01*
X1023630D01*
X1013053Y798100D01*
X1001384D01*
X996976Y793692D01*
X973756D01*
X964164Y784100D01*
X957400D01*
X955594Y782294D01*
X936208D01*
X929792Y788710D01*
X907591D01*
X900645Y795656D01*
X878878D01*
X877235Y794013D01*
X872265D01*
X868278Y798000D01*
X855700D01*
X850876Y802824D01*
X841324D01*
X833000Y794500D01*
X815500D01*
X805331Y804669D01*
X647121D01*
X644674Y807116D01*
X644561D01*
X626419Y825258D01*
X626391D01*
X625849Y825800D01*
X579487D01*
X573787Y820100D01*
X565300D01*
X559510Y825890D01*
X541690D01*
X540500Y824700D01*
X528003D01*
X525703Y827000D01*
X521674D01*
X518974Y824300D01*
X509877D01*
X509665Y824512D01*
G01X1383895Y878698D02*
X1396304Y891107D01*
Y912305D01*
X1397390Y913391D01*
Y917710D01*
X1392510Y922590D01*
Y930388D01*
X1371388Y951510D01*
X1358875D01*
X1334655Y975730D01*
X1319124D01*
X1318314Y974920D01*
X1305559D01*
X1298729Y981750D01*
X1185748D01*
X1179136Y975138D01*
X1084638D01*
X1078012Y968512D01*
X993011D01*
X987149Y962650D01*
X939010D01*
X936665Y964900D01*
X933700D01*
X924586Y955786D01*
X822126D01*
X815271Y962641D01*
X705642D01*
X674301Y931300D01*
X563250D01*
X555798Y938752D01*
X529355D01*
X526707Y941400D01*
X522305D01*
X520146Y939241D01*
G01X521353Y952266D02*
X523719Y949900D01*
X591999D01*
X600099Y958000D01*
X684100D01*
X699921Y973821D01*
X819443D01*
X825612Y979990D01*
X843694D01*
X849471Y974213D01*
X901354D01*
X909775Y982634D01*
X920034D01*
X924068Y986668D01*
X996907D01*
X1001539Y991300D01*
X1069999D01*
X1072789Y994090D01*
X1171450D01*
X1186360Y1009000D01*
X1201258D01*
X1203419Y1011161D01*
G01X722473Y693718D02*
X719732Y696459D01*
X713105D01*
X711182Y698382D01*
Y702907D01*
X713258Y704983D01*
Y708794D01*
X711894Y710158D01*
X702258D01*
X684500Y692400D01*
X662600D01*
X658636Y688436D01*
X586805D01*
X572695Y674326D01*
X557574D01*
X534457Y697443D01*
X529493D01*
G01X710196Y707562D02*
X701983D01*
X685121Y690700D01*
X663299D01*
X659499Y686900D01*
X587550D01*
X573250Y672600D01*
X556999D01*
X534656Y694943D01*
X529493D01*
G01X523289Y939195D02*
X525142Y937342D01*
X555213D01*
X562665Y929890D01*
X676190D01*
X707531Y961231D01*
X814234D01*
X821089Y954376D01*
X926177D01*
X931631Y959830D01*
X989731D01*
X995593Y965692D01*
X1079792D01*
X1085778Y971678D01*
X1180570D01*
X1186704Y977812D01*
X1195827D01*
X1201319Y972320D01*
X1285804D01*
X1285824Y972300D01*
X1294405D01*
X1295636Y973531D01*
X1301846D01*
X1303277Y972100D01*
X1319484D01*
X1320294Y972910D01*
X1333485D01*
X1357895Y948500D01*
X1370242D01*
X1386110Y932632D01*
Y917089D01*
X1392764Y910435D01*
Y893833D01*
X1392884Y893713D01*
Y891933D01*
X1385929Y884978D01*
G01X1200008Y1011161D02*
X1185961D01*
X1170700Y995900D01*
X1071600D01*
X1068860Y993160D01*
X1000839D01*
X996157Y988478D01*
X923078D01*
X919044Y984444D01*
X905839D01*
X897418Y976023D01*
X850221D01*
X844444Y981800D01*
X823094D01*
X817779Y976485D01*
X699586D01*
X683001Y959900D01*
X598601D01*
X593740Y955039D01*
X588438D01*
X586001Y952602D01*
X574730D01*
X573288Y954044D01*
Y957413D01*
X570801Y959900D01*
X561900D01*
X553900Y951900D01*
X528168D01*
X527879Y952189D01*
G01X551475Y661504D02*
X555113Y665142D01*
X655090D01*
X673472Y683524D01*
X708782D01*
X711328Y680978D01*
Y653821D01*
G01X543101Y698772D02*
Y690911D01*
X558220Y675792D01*
X572166D01*
X590474Y694100D01*
X656960D01*
X659209Y691851D01*
G01X928353Y686342D02*
X927097D01*
X922363Y681608D01*
X905272D01*
X903237Y683643D01*
X864782D01*
X858025Y690400D01*
X834801D01*
X828801Y696400D01*
X789499D01*
X756887Y729012D01*
X725467D01*
X724117Y730362D01*
X708300D01*
X705026Y733636D01*
X580936D01*
X577700Y730400D01*
X564435D01*
X562001Y732834D01*
G01X562374Y721593D02*
X565874Y725093D01*
X756307D01*
X786900Y694500D01*
X827599D01*
X833299Y688800D01*
X857296D01*
X864296Y681800D01*
X902366D01*
X909166Y675000D01*
X976699D01*
X981099Y670600D01*
X1019479D01*
X1022937Y674058D01*
Y691421D01*
G01X1381428Y812287D02*
Y810527D01*
X1378235Y807334D01*
X1321100D01*
Y807300D01*
X1319095Y805295D01*
Y796095D01*
X1314815Y791815D01*
X1285110D01*
X1270225Y806700D01*
X1177339D01*
X1177302Y806737D01*
X1105476D01*
X1039128Y740389D01*
X1020809D01*
X990309Y709889D01*
X988811D01*
X988810Y709890D01*
X987790D01*
X987652Y709752D01*
X912947D01*
X910146Y712553D01*
X902399D01*
X897008Y717944D01*
X880555D01*
X869978Y728521D01*
X834121D01*
X823600Y718000D01*
X798000D01*
X774438Y741562D01*
X737986D01*
X734457Y745091D01*
X580791D01*
X575300Y739600D01*
X563200D01*
G01X576556Y728219D02*
X723177D01*
G01X575979Y732517D02*
X581071Y737609D01*
X703603D01*
X707116Y734096D01*
X758358D01*
X793425Y699029D01*
X830826D01*
X832455Y697400D01*
X849215D01*
X854308Y702493D01*
Y708204D01*
X855882Y709778D01*
X864122D01*
X870400Y703500D01*
X873300D01*
X875200Y701600D01*
X885200D01*
X895200Y691600D01*
X905497D01*
X905925Y691172D01*
X931029D01*
X934601Y687600D01*
X993814D01*
X1005748Y699534D01*
X1018666D01*
X1027871Y708739D01*
X1063444D01*
X1080005Y725300D01*
X1168247D01*
X1175236Y732289D01*
X1315188D01*
X1317069Y730408D01*
X1349823D01*
X1365231Y715000D01*
X1412075D01*
X1417969Y720894D01*
G01X1367000Y900500D02*
X1369000Y902500D01*
Y911927D01*
X1356486Y924441D01*
Y926778D01*
X1355443Y927821D01*
X1349879D01*
X1348420Y929280D01*
Y931781D01*
X1344821Y935380D01*
X1340320D01*
X1328390Y947310D01*
X1206164D01*
X1204054Y945200D01*
X1087701D01*
X1082501Y940000D01*
X1052399D01*
X1042999Y930600D01*
X1029336D01*
X1024136Y935800D01*
X1014199D01*
X1010599Y939400D01*
X975450D01*
X972818Y936768D01*
X970656D01*
X969322Y935434D01*
X965505D01*
X963750Y933679D01*
X908712D01*
X906343Y931310D01*
X834420D01*
X829104Y936626D01*
X818274D01*
X808943Y945957D01*
X703357D01*
X678842Y921442D01*
X601110D01*
X592110Y912442D01*
Y895611D01*
G01X621592Y1033862D02*
X642237D01*
X665299Y1010800D01*
X666740D01*
X666850Y1010690D01*
X826711D01*
X834173Y1003228D01*
X865496D01*
X869693Y1007425D01*
X906284D01*
X907808Y1008949D01*
X962368D01*
X993375Y1039956D01*
X1049632D01*
X1056969Y1047293D01*
X1076868D01*
G01X1079910Y1045264D02*
X1066503D01*
X1058439Y1037200D01*
X1052398D01*
X1051052Y1038546D01*
X993960D01*
X962953Y1007539D01*
X910158D01*
X906929Y1004310D01*
X868573D01*
X866081Y1001818D01*
X833588D01*
X826206Y1009200D01*
X662135D01*
X640853Y1030482D01*
X621479D01*
G01X703600Y702212D02*
X701996D01*
X700954Y701170D01*
Y693641D01*
X704371Y690224D01*
X824175D01*
X838907Y675492D01*
X903608D01*
X907300Y671800D01*
X975300D01*
X979800Y667300D01*
X1037995D01*
X1070795Y700100D01*
X1150527D01*
X1163774Y713347D01*
G01X813548Y814000D02*
X690855D01*
X690449Y814406D01*
G01X711328Y653821D02*
X747452D01*
X770424Y676793D01*
X829496D01*
G01X703680Y697094D02*
X708974Y691800D01*
X825201D01*
X836998Y680003D01*
X901397D01*
X907900Y673500D01*
X975699D01*
X980199Y669000D01*
X1037437D01*
X1070337Y701900D01*
X1149546D01*
X1166115Y718469D01*
G01X712901Y821600D02*
X713396Y822095D01*
X816290D01*
X819395Y825200D01*
X831801D01*
X834505Y822496D01*
X837684D01*
X837724Y822536D01*
X837726D01*
X841270Y826080D01*
X853719D01*
X860399Y819400D01*
X866700D01*
X871390Y814710D01*
X874096D01*
X875186Y815800D01*
X908886D01*
X915550Y818560D01*
X920440D01*
X924200Y814800D01*
X928600D01*
X929900Y816100D01*
Y817694D01*
X931126Y818920D01*
X939221D01*
X942291Y821990D01*
X945838D01*
X947029Y820799D01*
X960300D01*
X963400Y823899D01*
Y830671D01*
X969309Y836580D01*
Y839334D01*
G01X724362Y504731D02*
X726777Y507146D01*
X741829D01*
X747031Y501944D01*
X823029D01*
X827768Y506683D01*
X833269D01*
G01X733000Y816000D02*
X733026Y815974D01*
X821974D01*
X823500Y817500D01*
X838811D01*
X840716Y819405D01*
X850290D01*
X857695Y812000D01*
X868509D01*
X869419Y811090D01*
X875596D01*
X876306Y811800D01*
X900045D01*
X903745Y808100D01*
X927442D01*
X932212Y812870D01*
X937143Y814911D01*
X969839D01*
X973252Y811498D01*
X982098D01*
X987150Y816550D01*
X991950D01*
X996793Y821393D01*
X1000993D01*
X1012831Y833231D01*
X1016768D01*
X1018799Y831200D01*
X1021399D01*
X1024599Y834400D01*
X1036200D01*
X1037895Y832705D01*
X1045923D01*
X1048085Y830543D01*
X1054844D01*
X1068600Y844299D01*
Y860559D01*
X1087901Y879860D01*
X1266960D01*
X1279260Y892160D01*
X1280139D01*
X1284399Y887900D01*
X1286579D01*
X1288774Y885705D01*
X1293872D01*
X1295167Y887000D01*
X1305967D01*
X1308220Y889253D01*
G01X732713Y853890D02*
X751979Y873156D01*
X820156D01*
X823100Y876100D01*
X827346D01*
X828646Y877400D01*
X861941D01*
X870418Y868923D01*
X879700D01*
G01X879300Y872063D02*
X871244D01*
X863256Y880051D01*
Y884243D01*
X861794Y885705D01*
X846874D01*
X846569Y885400D01*
X843900D01*
X840000Y881500D01*
X836205D01*
X834380Y879675D01*
X828219D01*
X826434Y877890D01*
X821891D01*
X818787Y874786D01*
X727786D01*
X722600Y869600D01*
G01X728503Y891692D02*
X741581Y878614D01*
X817428D01*
X823341Y884527D01*
X824447D01*
X829961Y890041D01*
Y893303D01*
X835711Y899053D01*
X846211D01*
X848792Y896472D01*
G01X728692Y886653D02*
X738702Y876643D01*
X818043D01*
X821100Y879700D01*
X825684D01*
X830232Y884248D01*
Y886941D01*
X832139Y888848D01*
Y892836D01*
X834258Y894955D01*
X836066D01*
G01X818031Y907747D02*
X809908Y899624D01*
X731188D01*
X724707Y893143D01*
G01X722400Y942500D02*
Y943555D01*
X723045Y944200D01*
X726700D01*
X730700Y940200D01*
X811299D01*
X816603Y934896D01*
X828387D01*
X833383Y929900D01*
X906928D01*
X909297Y932269D01*
X972043D01*
X973964Y933065D01*
X978699Y937800D01*
X1009303D01*
X1012803Y934300D01*
X1023499D01*
X1028855Y928944D01*
X1043388D01*
X1052115Y937671D01*
X1083171D01*
X1089100Y943600D01*
X1205139D01*
X1207439Y945900D01*
X1327301D01*
X1340101Y933100D01*
X1343001D01*
X1344442Y931659D01*
Y928858D01*
X1345058Y928242D01*
X1346958D01*
X1348445Y926755D01*
Y924464D01*
X1350050Y922859D01*
X1355407D01*
X1367000Y911266D01*
Y904500D01*
G01X1368882Y895100D02*
Y900069D01*
X1370500Y901687D01*
Y914237D01*
X1360405Y924332D01*
Y926669D01*
X1359038Y928036D01*
X1357804D01*
X1356438Y929402D01*
Y931962D01*
X1355576Y932824D01*
X1349976D01*
X1333600Y949200D01*
X1296900D01*
X1294240Y951860D01*
X1208261D01*
X1203101Y946700D01*
X1086199D01*
X1082186Y942687D01*
X951887D01*
X946500Y937300D01*
X873401D01*
X870366Y940335D01*
X845742D01*
X843977Y942100D01*
X817065D01*
X811465Y947700D01*
X729477D01*
X728846Y948331D01*
G01X869325Y761259D02*
X867000Y758934D01*
Y751000D01*
X865600Y749600D01*
X858807D01*
X851166Y752765D01*
X838322D01*
X828439Y762648D01*
X826934D01*
X823542Y764053D01*
X820163Y767432D01*
X814862D01*
X807715Y760285D01*
X798892D01*
X798362Y759755D01*
Y755803D01*
X797832Y755273D01*
X796362D01*
X795832Y755803D01*
Y759755D01*
X795302Y760285D01*
X793832D01*
X793302Y759755D01*
Y755803D01*
X792772Y755273D01*
X791302D01*
X790772Y755803D01*
Y759755D01*
X790242Y760285D01*
X745142D01*
X741992Y763435D01*
Y763480D01*
G01X883126Y766124D02*
X875195Y774055D01*
X868793Y776707D01*
X863201Y782299D01*
X858127Y784400D01*
X842480D01*
X841580Y783500D01*
X827480D01*
X825580Y785400D01*
X820527D01*
X755259Y772418D01*
X743428D01*
G01X742000Y768137D02*
X742769Y768906D01*
X748315D01*
X749084Y768137D01*
X788844D01*
X789374Y768667D01*
Y771470D01*
X789904Y772000D01*
X791374D01*
X791904Y771470D01*
Y768667D01*
X792434Y768137D01*
X793904D01*
X794434Y768667D01*
Y771470D01*
X794964Y772000D01*
X796434D01*
X796964Y771470D01*
Y768667D01*
X797494Y768137D01*
X798964D01*
X799494Y768667D01*
Y771470D01*
X800024Y772000D01*
X801494D01*
X802024Y771470D01*
Y768667D01*
X802554Y768137D01*
X804024D01*
X804554Y768667D01*
Y771470D01*
X805084Y772000D01*
X806554D01*
X807084Y771470D01*
Y768667D01*
X807614Y768137D01*
X809084D01*
X809614Y768667D01*
Y771470D01*
X810144Y772000D01*
X811614D01*
X812144Y771470D01*
Y770849D01*
X812674Y770319D01*
X821511D01*
X824824Y767006D01*
X828459Y765500D01*
X845380D01*
X847220Y767340D01*
X860410D01*
X862650Y765100D01*
X870748D01*
X883413Y759855D01*
G01X889763Y788159D02*
X869259D01*
X866795Y785695D01*
X860535D01*
X858399Y786580D01*
X851320D01*
X847800Y790100D01*
X829155D01*
X827066Y789235D01*
X793839D01*
X791634Y787030D01*
Y783030D01*
X791104Y782500D01*
X789634D01*
X789104Y783030D01*
Y787030D01*
X788574Y787560D01*
X787104D01*
X786574Y787030D01*
Y783030D01*
X786044Y782500D01*
X784574D01*
X784044Y783030D01*
Y787030D01*
X783514Y787560D01*
X782044D01*
X781514Y787030D01*
Y783030D01*
X780984Y782500D01*
X779514D01*
X778984Y783030D01*
Y787030D01*
X778454Y787560D01*
X776984D01*
X776454Y787030D01*
Y783030D01*
X775924Y782500D01*
X774454D01*
X773924Y783030D01*
Y787030D01*
X773394Y787560D01*
X771924D01*
X771394Y787030D01*
Y783030D01*
X770864Y782500D01*
X769394D01*
X768864Y783030D01*
Y787030D01*
X768334Y787560D01*
X766864D01*
X766334Y787030D01*
Y783130D01*
X765804Y782600D01*
X764334D01*
X763804Y783130D01*
Y787030D01*
X763274Y787560D01*
X761874D01*
X761374Y787060D01*
Y782630D01*
X760844Y782100D01*
X759374D01*
X758844Y782630D01*
Y786930D01*
X758214Y787560D01*
X753644D01*
X741993Y775909D01*
G01X817139Y890330D02*
X815769Y891700D01*
X812459D01*
X811307Y890548D01*
X736452D01*
G01X742407Y988452D02*
X746359Y984500D01*
X898852D01*
X902742Y988390D01*
X917249D01*
X921275Y992416D01*
X925746D01*
X929010Y995680D01*
X994223D01*
X999578Y1001035D01*
X1065725D01*
X1067090Y1002400D01*
X1171299D01*
X1184492Y1015593D01*
X1204007D01*
X1212935Y1006665D01*
X1251534D01*
X1255930Y1002269D01*
X1333882D01*
X1345030Y991121D01*
Y989260D01*
X1365880Y968410D01*
X1379757D01*
X1418603Y929564D01*
X1446436D01*
X1450300Y925700D01*
X1458400D01*
X1486000Y898100D01*
Y876901D01*
X1488138Y874763D01*
Y872839D01*
G01X743062Y1004460D02*
X826527D01*
X830899Y1000088D01*
X832758D01*
X832838Y1000008D01*
X866831D01*
X869323Y1002500D01*
X908300D01*
X911529Y1005729D01*
X963729D01*
X992719Y1034719D01*
X1011261D01*
X1013403Y1032577D01*
X1025933D01*
X1026910Y1031600D01*
X1062878D01*
X1064118Y1030360D01*
X1064231D01*
X1071035Y1023556D01*
X1079529D01*
X1080445Y1022640D01*
X1173219D01*
X1183349Y1032770D01*
X1220467D01*
X1232317Y1020920D01*
X1274305D01*
X1276515Y1018710D01*
X1297328D01*
X1302228Y1013810D01*
X1337701D01*
X1355890Y995621D01*
Y993760D01*
X1370380Y979270D01*
X1389889D01*
X1399069Y970090D01*
X1407631D01*
X1407748Y969973D01*
X1407861D01*
X1416692Y961142D01*
X1457348D01*
X1458202Y960288D01*
G01X839744Y1461959D02*
X838244Y1463459D01*
X830651D01*
X829037Y1461845D01*
Y1441237D01*
X835057Y1435217D01*
Y1426154D01*
X831705Y1422802D01*
X807472D01*
X798601Y1431673D01*
G01X1285302Y877283D02*
Y875233D01*
X1282395Y872326D01*
X1269885D01*
X1268371Y870812D01*
X1164840D01*
X1164268Y870240D01*
X1164241D01*
X1160355Y866354D01*
X1081654D01*
X1073720Y858420D01*
Y839820D01*
X1059099Y825199D01*
X1057601D01*
X1057600Y825200D01*
X1036300D01*
X1032500Y829000D01*
X1026521D01*
X1021414Y823893D01*
X1018669D01*
X1009590Y814814D01*
Y811810D01*
X996211Y798431D01*
X972331D01*
X964893Y790993D01*
X953492D01*
X952700Y790201D01*
Y787000D01*
X949900Y784200D01*
X936862D01*
X929919Y791143D01*
X908357D01*
X905600Y793900D01*
Y800501D01*
X903164Y802937D01*
X868637D01*
X867605Y801905D01*
X858088D01*
X854493Y805500D01*
X835095D01*
X832500Y802905D01*
X823095D01*
X821000Y805000D01*
X813000D01*
G01X814299Y840877D02*
X815322Y841900D01*
X818678D01*
X825063Y848285D01*
X832202D01*
X833817Y849900D01*
X835729D01*
X836129Y849500D01*
X855182D01*
X856992Y851310D01*
X860761D01*
X864160Y847911D01*
Y846040D01*
X876100Y834100D01*
X879100D01*
X887340Y825860D01*
X905543D01*
X913282Y829065D01*
X921826D01*
X926710Y833949D01*
Y836409D01*
X928610Y838309D01*
X933291D01*
X935275Y840293D01*
Y842283D01*
X939892Y846900D01*
X947300D01*
X955423Y855023D01*
Y856842D01*
X959670Y861089D01*
Y869989D01*
X975063Y885382D01*
X1016932D01*
X1019886Y888336D01*
X1029504D01*
X1037768Y896600D01*
X1071900D01*
X1095300Y920000D01*
X1180700D01*
X1183415Y917285D01*
X1188691D01*
X1191006Y919600D01*
X1198200D01*
X1201172Y916628D01*
X1266229D01*
X1266247Y916610D01*
X1268639D01*
X1274029Y922000D01*
X1280299D01*
X1282571Y919728D01*
X1309495D01*
X1318898Y910325D01*
X1335507D01*
X1338095Y907737D01*
Y895154D01*
X1335803Y892862D01*
G01X813887Y835146D02*
X817204D01*
X818899Y836841D01*
Y839561D01*
X825813Y846475D01*
X831211D01*
X832132Y845554D01*
X862046D01*
X875000Y832600D01*
X875040D01*
X875350Y832290D01*
X878350D01*
X886590Y824050D01*
X906291D01*
X914030Y827255D01*
X922577D01*
X931622Y836300D01*
X943831D01*
X946300Y838769D01*
Y843340D01*
X956460Y853500D01*
X958244D01*
X961777Y857033D01*
Y867544D01*
X977714Y883481D01*
X1018426D01*
X1020855Y885910D01*
X1030095D01*
X1038585Y894400D01*
X1072700D01*
X1095900Y917600D01*
X1179801D01*
X1182501Y914900D01*
X1189451D01*
X1191951Y917400D01*
X1196400D01*
X1199000Y914800D01*
X1270299D01*
X1271799Y916300D01*
X1274156D01*
X1276249Y918389D01*
X1277829D01*
X1281018Y915200D01*
X1288800D01*
X1290700Y913300D01*
X1309524D01*
X1314924Y907900D01*
X1330699D01*
X1334222Y904377D01*
Y897000D01*
G01X1004953Y923995D02*
X1004922Y924026D01*
X996710D01*
X992711Y928025D01*
X982786D01*
X977641Y922880D01*
X972084D01*
X964521Y919749D01*
X960982Y916210D01*
X953805D01*
X947507Y922508D01*
X911705D01*
X910416Y923797D01*
X895861D01*
X893776Y921712D01*
Y917657D01*
X895709Y915724D01*
Y905561D01*
X891695Y901547D01*
X885698D01*
X883386Y903859D01*
X825147D01*
X821963Y900675D01*
Y888463D01*
X817086Y883586D01*
X812219D01*
G01X812575Y880834D02*
X817088D01*
X828086Y891832D01*
Y899917D01*
X830208Y902039D01*
X882632D01*
X884944Y899727D01*
X892449D01*
X897529Y904807D01*
Y915042D01*
X898665Y916178D01*
Y919969D01*
X900295Y921599D01*
X909203D01*
X910606Y920196D01*
X946369D01*
X951765Y914800D01*
X961700D01*
X964901Y918001D01*
X972625Y921200D01*
X978400D01*
X983386Y926186D01*
X991497D01*
X996254Y921429D01*
X1006111D01*
X1008689Y924007D01*
X1008935D01*
G01X829496Y676793D02*
X830506D01*
X837150Y670149D01*
X849450D01*
X866951Y652648D01*
X998452D01*
X1005800Y645300D01*
Y637600D01*
G01X902841Y703665D02*
X892719Y713787D01*
X885620D01*
X883479Y715928D01*
X879713D01*
X868990Y726651D01*
X843544D01*
X833216Y716323D01*
Y711761D01*
X831997Y710542D01*
X823670D01*
G01X815500Y824000D02*
X818990Y827490D01*
X855510D01*
X862190Y820810D01*
X867807D01*
X876499Y817210D01*
X908582D01*
X915249Y819970D01*
X928969D01*
X929329Y820330D01*
X938636D01*
X941706Y823400D01*
X946423D01*
X947278Y822545D01*
X958875D01*
X961918Y825588D01*
Y831538D01*
X967035Y836655D01*
Y839898D01*
X970040Y842903D01*
G01X1305356Y902597D02*
X1304453Y903500D01*
X1287801D01*
X1287011Y902710D01*
X1277209D01*
X1275699Y901200D01*
X1207391D01*
X1203124Y896933D01*
X1187931D01*
X1186273Y898591D01*
X1101512D01*
X1061558Y858637D01*
X1027492D01*
X1017123Y848268D01*
X1002721D01*
X995180Y840727D01*
X976058D01*
X971849Y844936D01*
X970111D01*
X969983Y844808D01*
X969250D01*
X968135Y843693D01*
Y842993D01*
X965625Y840483D01*
Y840450D01*
X965359Y840184D01*
Y837680D01*
X965097Y837418D01*
Y836855D01*
X960536Y832294D01*
Y832151D01*
X960508Y832123D01*
Y826173D01*
X958290Y823955D01*
X951435D01*
X948542Y826848D01*
X948525Y826832D01*
X946945D01*
X945013Y824900D01*
X940700D01*
X937900Y822100D01*
X929225D01*
X928017Y821600D01*
X915466D01*
X908266Y818620D01*
X876882D01*
X874150Y819751D01*
X868005Y825896D01*
Y830967D01*
X863972Y835000D01*
X856722D01*
X851286Y829564D01*
X847459D01*
X846795Y828900D01*
X834160D01*
X830014Y833046D01*
G01X828964Y977780D02*
Y977457D01*
X831521Y974900D01*
X841455D01*
X846055Y970300D01*
X903000D01*
X911714Y979014D01*
X922074D01*
X926108Y983048D01*
X941552D01*
X944500Y980100D01*
X948300D01*
X949700Y981500D01*
X951386D01*
X953100Y979786D01*
X955085D01*
X957299Y982000D01*
X963167D01*
X964881Y980286D01*
X968933D01*
X971695Y983048D01*
X998407D01*
X999769Y984410D01*
X1073349D01*
X1079409Y990470D01*
X1172950D01*
X1186480Y1004000D01*
X1204301D01*
X1213272Y995029D01*
X1308783D01*
X1314000Y989812D01*
Y987100D01*
X1315710Y985390D01*
X1338660D01*
X1362880Y961170D01*
X1375994D01*
X1420064Y917100D01*
X1454663D01*
X1468297Y903466D01*
Y888017D01*
X1470866Y885448D01*
Y860346D01*
X1477812Y853400D01*
X1486600D01*
X1498750Y841250D01*
Y803050D01*
X1491169Y795469D01*
X1489969D01*
X1486957Y792457D01*
G01X838152Y700215D02*
X848206D01*
X851611Y703620D01*
Y710277D01*
X856720Y715386D01*
X865613D01*
X875199Y705800D01*
X884999D01*
X893699Y697100D01*
X894108D01*
X894118Y697090D01*
X903699D01*
X907007Y693782D01*
X932111D01*
X935691Y690210D01*
X991310D01*
X1003937Y702837D01*
X1018264D01*
X1029453Y714026D01*
X1061340D01*
X1087044Y739730D01*
X1334606D01*
X1336661Y737675D01*
G01X836078Y709619D02*
X851339Y724880D01*
X867592D01*
X878857Y713615D01*
X882522D01*
X884449Y711688D01*
X889712D01*
X900000Y701400D01*
X905076D01*
X906096Y700380D01*
X911484D01*
X914404Y703300D01*
X944481D01*
X945323Y702458D01*
X992667D01*
X992747Y702538D01*
X995529D01*
X1001205Y708214D01*
X1012595D01*
X1024150Y719769D01*
X1026916D01*
G01X1022346Y917669D02*
X1017815Y922200D01*
X1014399D01*
X1010599Y926000D01*
X1002101D01*
X998011Y930090D01*
X982291D01*
X976891Y924690D01*
X971448D01*
X964225Y921700D01*
X956522D01*
X952871Y925351D01*
X911422D01*
X911166Y925607D01*
X895111D01*
X894855Y925351D01*
X857424D01*
X853747Y921674D01*
X846696D01*
X846147Y921125D01*
Y916150D01*
X843977Y913980D01*
X841354D01*
X841274Y914060D01*
G01X843315Y916612D02*
Y922159D01*
X849056Y927900D01*
X908794D01*
X911325Y930431D01*
X955032D01*
X956548Y928915D01*
Y925959D01*
X958807Y923700D01*
X964323D01*
X971079Y926500D01*
X975560D01*
X981083Y932023D01*
X999381D01*
X1003504Y927900D01*
X1011400D01*
X1015000Y924300D01*
X1022988D01*
X1029570Y917718D01*
G01X835431Y977775D02*
X841174D01*
X846546Y972403D01*
X902104D01*
X910525Y980824D01*
X921324D01*
X925358Y984858D01*
X997657D01*
X999019Y986220D01*
X1070420D01*
X1072000Y987800D01*
Y990700D01*
X1073580Y992280D01*
X1172200D01*
X1186720Y1006800D01*
X1205900D01*
X1215861Y996839D01*
X1331630D01*
X1339600Y988869D01*
Y987010D01*
X1363630Y962980D01*
X1376744D01*
X1420324Y919400D01*
X1454923D01*
X1470107Y904216D01*
Y890140D01*
X1476400Y883847D01*
Y872100D01*
X1477700Y870800D01*
Y865004D01*
X1500560Y842144D01*
Y802060D01*
X1495170Y796670D01*
G01X881244Y1476859D02*
X873500Y1469115D01*
Y1447298D01*
X877699Y1443099D01*
Y1423174D01*
X876086Y1421561D01*
X855850D01*
X854113Y1423298D01*
Y1449802D01*
X841956Y1461959D01*
X839744D01*
G01X858169Y495032D02*
X887903D01*
X901446Y481489D01*
X921458D01*
X924999Y477948D01*
G01X1003900Y628700D02*
X1003700Y628900D01*
Y644001D01*
X998701Y649000D01*
X864010D01*
X861663Y646653D01*
G01X855300Y646819D02*
Y644901D01*
X855976Y644225D01*
X864125D01*
X866900Y647000D01*
X997500D01*
X1001605Y642895D01*
Y627605D01*
G01X1351550Y842470D02*
X1348346Y839266D01*
Y833901D01*
X1346857Y832412D01*
Y832356D01*
X1345917Y831416D01*
X1345861D01*
X1328145Y813700D01*
X1306898D01*
X1299343Y816827D01*
X1291167D01*
X1284697Y810357D01*
X1184400D01*
X1177752Y817005D01*
X1110249D01*
X1037253Y744009D01*
X1019309D01*
X988810Y713510D01*
X927041D01*
X921351Y719200D01*
X909386D01*
X908021Y717835D01*
X901632D01*
X899506Y719961D01*
X888055D01*
X885580Y722436D01*
X881280D01*
X859199Y744517D01*
G01X850686Y1006923D02*
X850739Y1006870D01*
Y1005421D01*
X851122Y1005038D01*
X864746D01*
X869178Y1009470D01*
X905769D01*
X907058Y1010759D01*
X961618D01*
X993685Y1042826D01*
X1045608D01*
X1063782Y1061000D01*
X1082530D01*
X1110084Y1033446D01*
X1169826D01*
X1178013Y1041633D01*
X1251102D01*
X1256660Y1036075D01*
X1300103D01*
X1305661Y1041633D01*
X1311132D01*
X1312324Y1042825D01*
X1315606D01*
G01X853449Y1007048D02*
X864048D01*
X868280Y1011280D01*
X905019D01*
X906473Y1012734D01*
X961033D01*
X992935Y1044636D01*
X1044858D01*
X1063205Y1062983D01*
X1083107D01*
X1110834Y1035256D01*
X1169076D01*
X1177263Y1043443D01*
X1251852D01*
X1257410Y1037885D01*
X1266815D01*
X1267345Y1038415D01*
Y1040734D01*
X1267875Y1041264D01*
X1269345D01*
X1269875Y1040734D01*
Y1038415D01*
X1270405Y1037885D01*
X1271875D01*
X1272405Y1038415D01*
Y1040734D01*
X1272935Y1041264D01*
X1274405D01*
X1274935Y1040734D01*
Y1038415D01*
X1275465Y1037885D01*
X1299353D01*
X1304911Y1043443D01*
X1310382D01*
X1312163Y1045224D01*
X1316650D01*
X1317618Y1044256D01*
Y1041602D01*
X1315756Y1039740D01*
Y1039344D01*
G01X1002883Y622521D02*
X999667Y625737D01*
Y641769D01*
X997138Y644298D01*
X885614D01*
X879135Y637819D01*
Y632552D01*
G01X876286Y698970D02*
X885530D01*
X898758Y685742D01*
X923167D01*
X925925Y688500D01*
X931400D01*
X943100Y676800D01*
X976901D01*
X981401Y672300D01*
X1019113D01*
X1020680Y673867D01*
Y697769D01*
X1021885Y698974D01*
G01X869325Y761259D02*
X871752Y760776D01*
X883060Y756091D01*
X898688Y745649D01*
X902062Y744251D01*
X902407Y744021D01*
X918402Y737398D01*
X918607D01*
X918844Y737300D01*
X960482D01*
X983555Y741890D01*
X987461Y745796D01*
G01X871600Y898584D02*
X871400Y898384D01*
Y882800D01*
X874263Y879937D01*
X884519D01*
G01X865973Y978187D02*
X869764Y981978D01*
X899381D01*
X903983Y986580D01*
X917999D01*
X922025Y990606D01*
X926496D01*
X929760Y993870D01*
X966229D01*
X969099Y991000D01*
X996119D01*
X1000409Y995290D01*
X1067290D01*
X1068104Y996104D01*
Y998905D01*
X1069789Y1000590D01*
X1172049D01*
X1185120Y1013661D01*
X1199700D01*
G01X1627224Y643252D02*
Y679302D01*
X1618126Y688400D01*
X1610239D01*
X1596811Y674972D01*
Y662089D01*
X1577974Y643252D01*
X1541378D01*
X1526592Y628466D01*
X1469002D01*
X1452684Y644784D01*
X1433086D01*
X1422178Y633876D01*
Y633798D01*
X1419496Y631116D01*
X1405868D01*
X1405073Y631911D01*
X1397869D01*
X1395505Y629547D01*
Y623934D01*
X1392610Y621039D01*
X1351874D01*
X1347210Y616375D01*
X1342099D01*
X1340074Y618400D01*
X1226224D01*
X1167364Y677260D01*
Y680326D01*
X1165481Y682209D01*
X1154631D01*
X1127007Y654585D01*
X1114942D01*
X1104220Y643863D01*
X1090252D01*
X1074498Y628109D01*
X1050426D01*
X1020833Y657702D01*
X904692D01*
X899156Y663238D01*
X886039D01*
X883309Y665968D01*
Y666608D01*
G01X1564670Y650122D02*
X1560623Y646075D01*
X1540085D01*
X1525276Y631266D01*
X1470318D01*
X1452092Y649492D01*
X1427140D01*
X1414015Y636367D01*
X1394868D01*
X1382340Y623839D01*
X1375137D01*
X1371466Y627510D01*
X1357331D01*
X1352005Y632836D01*
X1344914D01*
X1341781Y629703D01*
X1333206D01*
X1323083Y639826D01*
Y641090D01*
X1320551Y643622D01*
X1246066D01*
X1201655Y688033D01*
X1151466D01*
X1135818Y672385D01*
X1103090D01*
X1070699Y639994D01*
X1062602D01*
X1038899Y663697D01*
X907751D01*
X900682Y670766D01*
X890420D01*
X886304Y666650D01*
G01X889525Y722060D02*
X891165Y723700D01*
X920640D01*
X928040Y716300D01*
X953699D01*
X960714Y723315D01*
Y726039D01*
X961875Y727200D01*
X992702D01*
X1015600Y750098D01*
Y752100D01*
X1017400Y753900D01*
X1019200D01*
X1022900Y750200D01*
X1034899D01*
X1107744Y823045D01*
X1281322D01*
X1281777Y823500D01*
G01X883126Y766124D02*
X895516Y757845D01*
X904371Y748990D01*
X904881Y748649D01*
X919442Y742618D01*
X940536D01*
X948512Y750600D01*
X965435D01*
X973450Y747280D01*
G01X883413Y759855D02*
X903644Y746335D01*
X918922Y740008D01*
X945703D01*
X946233Y740538D01*
Y743682D01*
X946763Y744212D01*
X948233D01*
X948763Y743682D01*
Y740538D01*
X949293Y740008D01*
X950763D01*
X951293Y740538D01*
Y743682D01*
X951823Y744212D01*
X953293D01*
X953823Y743682D01*
Y740538D01*
X954353Y740008D01*
X959048D01*
X978948Y743966D01*
X981876Y745179D01*
G01X953837Y763025D02*
X952337D01*
X949520Y765842D01*
Y766592D01*
X953113Y770185D01*
Y770935D01*
X952153Y771895D01*
X951445D01*
X947231Y767681D01*
X946481D01*
X945442Y768720D01*
Y769470D01*
X949656Y773684D01*
Y774392D01*
X948496Y775552D01*
X947746D01*
X944153Y771959D01*
X943403D01*
X942364Y772998D01*
Y773748D01*
X945957Y777341D01*
Y778091D01*
X944918Y779130D01*
X944168D01*
X940575Y775537D01*
X939981D01*
X928918Y786600D01*
X894626D01*
X893410Y787816D01*
X890106D01*
X889763Y788159D01*
G01X889244Y1468859D02*
X889928D01*
X897624Y1461163D01*
Y1424292D01*
X899238Y1422678D01*
X917673D01*
X923600Y1428605D01*
Y1451543D01*
X921769Y1453374D01*
Y1476990D01*
X922893Y1478114D01*
X925435D01*
G01X1173034Y765060D02*
X1168931Y760957D01*
X1145732D01*
X1125466Y781223D01*
X1103133D01*
X1044980Y723070D01*
X1025456D01*
X1014623Y712237D01*
X1000451D01*
X992082Y703868D01*
X945908D01*
X944876Y704900D01*
X913186D01*
X908699Y709387D01*
G01X911289Y881400D02*
Y882890D01*
X911299Y882900D01*
Y902870D01*
X920115Y911686D01*
X962885D01*
X966106Y914907D01*
X972508Y917559D01*
X1013540D01*
X1016909Y914190D01*
X1070510D01*
X1089301Y932981D01*
X1205018D01*
X1215117Y943080D01*
X1302873D01*
X1306863Y939090D01*
X1331209D01*
X1336122Y934177D01*
Y929378D01*
X1338003Y927497D01*
X1343503D01*
X1344515Y926485D01*
Y924333D01*
X1347608Y921240D01*
X1354760D01*
X1365000Y911000D01*
Y898300D01*
X1366000Y897300D01*
Y894687D01*
X1365713Y894400D01*
G01X1362564Y894336D02*
X1361000Y895900D01*
Y912700D01*
X1354257Y919443D01*
X1344957D01*
X1342200Y922200D01*
X1330600D01*
X1328500Y924300D01*
Y931501D01*
X1323701Y936300D01*
X1321136D01*
X1319036Y934200D01*
X1301131D01*
X1297431Y937900D01*
X1251715D01*
X1245386Y931571D01*
X1089886D01*
X1071095Y912780D01*
X1015820D01*
X1012451Y916149D01*
X972822D01*
X967232Y913832D01*
X963610Y910210D01*
X922010D01*
X912864Y901064D01*
Y879937D01*
G01X908920Y905630D02*
X916390Y913100D01*
X962200D01*
X965801Y916701D01*
X972565Y919500D01*
X979599D01*
X983899Y923800D01*
X991400D01*
X995838Y919362D01*
X1013936D01*
X1017698Y915600D01*
X1069925D01*
X1088716Y934391D01*
X1204433D01*
X1214532Y944490D01*
X1306730D01*
X1310118Y941102D01*
X1320039D01*
X1321256Y942319D01*
Y943815D01*
G01X1383895Y875549D02*
X1397714Y889368D01*
Y911113D01*
X1398800Y912199D01*
Y918999D01*
X1393920Y923879D01*
Y930973D01*
X1371973Y952920D01*
X1359460D01*
X1335240Y977140D01*
X1318539D01*
X1317729Y976330D01*
X1306144D01*
X1299090Y983384D01*
X1197354D01*
X1196938Y983800D01*
X1185465D01*
X1178453Y976788D01*
X1084189D01*
X1077323Y969922D01*
X991622D01*
X986100Y964400D01*
X941105D01*
X938525Y966980D01*
X933181D01*
X925701Y959500D01*
X912711D01*
X909811Y962400D01*
G01X912690Y994350D02*
X917640Y999300D01*
X991099D01*
X996454Y1004655D01*
X1064225D01*
X1065967Y1006397D01*
X1169996D01*
X1183030Y1019431D01*
X1201800D01*
G01X915800Y629700D02*
Y636236D01*
X918364Y638800D01*
X975488D01*
X988488Y625800D01*
X996188D01*
X1001388Y620600D01*
X1020588D01*
X1053500Y587688D01*
Y554188D01*
X1060588Y547100D01*
X1078488D01*
X1087888Y537700D01*
X1107612D01*
X1114912Y545000D01*
X1129188D01*
X1136588Y537600D01*
X1141600D01*
X1142800Y538800D01*
X1159000D01*
X1165400Y545200D01*
Y553300D01*
G01X918300Y629700D02*
Y635200D01*
X920000Y636900D01*
X974800D01*
X987800Y623900D01*
X995400D01*
X1000600Y618700D01*
X1019800D01*
X1051600Y586900D01*
Y553400D01*
X1059800Y545200D01*
X1077700D01*
X1087100Y535800D01*
X1108400D01*
X1115700Y543100D01*
X1128400D01*
X1133000Y538500D01*
Y534000D01*
X1134600Y532400D01*
X1140300D01*
X1144800Y536900D01*
X1159700D01*
X1167988Y545188D01*
Y553212D01*
X1167900Y553300D01*
G01X913247Y714204D02*
X915751Y711700D01*
X989560D01*
X1020059Y742199D01*
X1038378D01*
X1104726Y808547D01*
X1178052D01*
X1178089Y808510D01*
X1270975D01*
X1285860Y793625D01*
X1307725D01*
X1314905Y800805D01*
Y805205D01*
X1319100Y809400D01*
X1336484D01*
X1341584Y814500D01*
X1368120D01*
X1371000Y811620D01*
G01X917588Y884288D02*
Y896089D01*
X930199Y908700D01*
X964200D01*
X967634Y912134D01*
X973924Y914739D01*
X1011862D01*
X1015231Y911370D01*
X1071680D01*
X1090471Y930161D01*
X1245971D01*
X1252300Y936490D01*
X1296244D01*
X1300434Y932300D01*
X1318600D01*
X1324572Y926328D01*
Y924328D01*
X1328400Y920500D01*
X1339699D01*
X1344499Y915700D01*
X1352701D01*
X1357849Y910552D01*
Y892862D01*
G01X922313Y886236D02*
Y896574D01*
X928440Y902701D01*
X931904D01*
X935514Y906311D01*
X964112D01*
X968815Y911014D01*
X974400Y913329D01*
X1006966D01*
X1011971Y908324D01*
X1016852D01*
X1018488Y909960D01*
X1072265D01*
X1091056Y928751D01*
X1246556D01*
X1251305Y933500D01*
X1296126D01*
X1298796Y930830D01*
X1317670D01*
X1321600Y926900D01*
Y924815D01*
X1328015Y918400D01*
X1339000D01*
X1343900Y913500D01*
X1351901D01*
X1356264Y909137D01*
Y894300D01*
G01X925462Y886236D02*
Y896573D01*
X929348Y900459D01*
X933093D01*
X937534Y904900D01*
X956494D01*
X959733Y901661D01*
X970341D01*
X980580Y911900D01*
X1006400D01*
X1011386Y906914D01*
X1011389D01*
X1011551Y906752D01*
X1017276D01*
X1019074Y908550D01*
X1072850D01*
X1091641Y927341D01*
X1247141D01*
X1251800Y932000D01*
X1295038D01*
X1300738Y926300D01*
X1308707D01*
X1311325Y928918D01*
G01X1376708Y901000D02*
Y919633D01*
X1372407Y923934D01*
Y931493D01*
X1369400Y934500D01*
X1365400D01*
X1358273Y941627D01*
X1353123D01*
X1350142Y944608D01*
Y946758D01*
X1340810Y956090D01*
X1089604D01*
X1080431Y946917D01*
X946362D01*
X943953Y944508D01*
X915003D01*
X914193Y945318D01*
G01X928227Y951125D02*
X935522Y958420D01*
X990317D01*
X996179Y964282D01*
X1080727D01*
X1086393Y969948D01*
X1181287D01*
X1186492Y975153D01*
X1196147D01*
X1200390Y970910D01*
X1285219D01*
X1286629Y969500D01*
X1293600D01*
X1296221Y972121D01*
X1301261D01*
X1305982Y967400D01*
X1316779D01*
X1320879Y971500D01*
X1332900D01*
X1357482Y946918D01*
X1363479D01*
X1369197Y941200D01*
X1371299D01*
X1372599Y942500D01*
X1374247D01*
X1384700Y932047D01*
Y897002D01*
X1381481Y893783D01*
G01X1379896Y892862D02*
Y895041D01*
X1380500Y895645D01*
Y932000D01*
X1374700Y937800D01*
X1370601D01*
X1362893Y945508D01*
X1356733D01*
X1337741Y964500D01*
X1323800D01*
X1321997Y966303D01*
X1320314D01*
X1319731Y965720D01*
X1300640D01*
X1299050Y967310D01*
X1286824D01*
X1284634Y969500D01*
X1197801D01*
X1195401Y971900D01*
X1187100D01*
X1180898Y965698D01*
X1084138D01*
X1081312Y962872D01*
X1003452D01*
X997400Y956820D01*
X938441D01*
X929585Y947964D01*
X924651D01*
X921364Y951251D01*
G01X1196300Y998600D02*
X1195914Y998986D01*
X1188486D01*
X1175900Y986400D01*
X1080749D01*
X1072521Y978172D01*
X974078D01*
X970096Y974190D01*
X944150D01*
X938950Y979390D01*
X927910D01*
X918265Y969745D01*
G01X913005Y969605D02*
Y969385D01*
X914550Y967840D01*
X919055D01*
X927715Y976500D01*
X939280D01*
X943400Y972380D01*
X970846D01*
X974828Y976362D01*
X1073271D01*
X1081499Y984590D01*
X1176650D01*
X1176860Y984800D01*
X1176899D01*
X1188633Y996534D01*
X1200213D01*
X1202028Y998349D01*
G01X1367298Y867665D02*
X1369263Y865700D01*
X1384006D01*
X1389716Y871410D01*
X1401614D01*
X1407289Y877085D01*
Y877097D01*
X1406291Y878095D01*
X1404710D01*
X1403595Y879210D01*
Y880790D01*
X1404710Y881905D01*
X1406290D01*
Y884515D01*
X1403595Y887210D01*
Y888790D01*
X1404710Y889905D01*
X1406291D01*
X1407289Y890903D01*
Y892365D01*
X1407365Y892441D01*
Y895170D01*
X1407405Y895210D01*
Y896790D01*
X1407365Y896830D01*
Y903170D01*
X1407405Y903210D01*
Y904790D01*
X1407365Y904830D01*
Y922119D01*
X1373744Y955740D01*
X1360630D01*
X1336410Y979960D01*
X1310840D01*
X1308600Y982200D01*
X1304899D01*
X1298194Y988905D01*
X1211575D01*
X1210690Y989790D01*
X1207107D01*
X1206268Y990629D01*
X1188304D01*
X1178275Y980600D01*
X1083401D01*
X1075543Y972742D01*
X976328D01*
X972346Y968760D01*
X941900D01*
X940132Y970528D01*
X933020D01*
X931748Y971800D01*
X928135D01*
X923289Y966954D01*
Y965780D01*
G01X1195757Y988131D02*
X1194669Y989219D01*
X1188889D01*
X1177868Y978198D01*
X1083604D01*
X1076738Y971332D01*
X990733D01*
X985401Y966000D01*
X941500D01*
X939110Y968390D01*
X932400D01*
X931090Y969700D01*
X929201D01*
X926796Y967295D01*
Y966297D01*
G01X1307000Y960500D02*
X1305400Y962100D01*
X1298900D01*
X1297400Y963600D01*
X1283734D01*
X1281888Y965446D01*
X1185846D01*
X1182478Y962078D01*
X1087388D01*
X1084562Y959252D01*
X1032552D01*
X1030199Y956899D01*
X1026319D01*
X1024198Y959020D01*
X1004720D01*
X998900Y953200D01*
X945301D01*
X941101Y949000D01*
X938855D01*
X936371Y951484D01*
G01X1332500Y961500D02*
X1331500Y962500D01*
X1324830D01*
X1322090Y959760D01*
X1319040D01*
X1314890Y963910D01*
X1299890D01*
X1298300Y965500D01*
X1284394D01*
X1282204Y967690D01*
X1197051D01*
X1197041Y967700D01*
X1196499D01*
X1194109Y970090D01*
X1187850D01*
X1181648Y963888D01*
X1084888D01*
X1082062Y961062D01*
X1004202D01*
X998150Y955010D01*
X943993D01*
X940716Y951733D01*
G01X935255Y962725D02*
X936744Y961240D01*
X988240D01*
X994102Y967102D01*
X1078903D01*
X1085209Y973408D01*
X1179853D01*
X1186045Y979600D01*
X1196483D01*
X1198583Y977500D01*
X1300532D01*
X1304522Y973510D01*
X1318899D01*
X1319709Y974320D01*
X1334070D01*
X1358290Y950100D01*
X1370803D01*
X1391100Y929803D01*
Y914800D01*
X1394174Y911726D01*
Y894418D01*
X1394294Y894298D01*
Y891348D01*
X1384774Y881828D01*
G01X949823Y491982D02*
X952159Y489646D01*
Y477076D01*
X955816Y473419D01*
G01X958736Y482165D02*
X961800Y479101D01*
Y470513D01*
X962564Y469749D01*
X973101D01*
X976397Y473045D01*
G01X1332654Y861367D02*
X1330851Y863170D01*
X1312832D01*
X1311193Y861531D01*
Y859093D01*
X1299200Y847100D01*
X1292410D01*
X1290185Y844875D01*
Y843085D01*
X1286200Y839100D01*
X1267311D01*
X1259716Y831505D01*
X1097706D01*
X1051375Y785174D01*
X1039494D01*
X1032822Y778502D01*
X1024701D01*
X1011185Y764986D01*
Y761694D01*
X1003404Y753913D01*
Y747101D01*
X988998Y732695D01*
X970879D01*
X968295Y730111D01*
X951151D01*
G01X955225Y788984D02*
X965785D01*
X972303Y795502D01*
X996226D01*
X1011400Y810676D01*
Y814064D01*
X1019336Y822000D01*
X1024893D01*
X1026226Y820667D01*
X1057473D01*
X1076100Y839294D01*
Y858100D01*
X1081821Y863821D01*
X1160382D01*
X1164991Y868430D01*
X1180239D01*
G01X1197173Y940645D02*
X1195326Y938798D01*
X1093641D01*
X1093559Y938880D01*
X1091979D01*
X1091897Y938798D01*
X1090198D01*
X1076300Y924900D01*
X1025399D01*
X1023502Y926797D01*
X1015412D01*
X1012409Y929800D01*
X1004181D01*
X999981Y934000D01*
X980499D01*
X975148Y928649D01*
X971533D01*
X964169Y925600D01*
X960621D01*
X958567Y927654D01*
G01X1300500Y960000D02*
X1299958Y959458D01*
X1087776D01*
X1087614Y959296D01*
X1087582D01*
X1085496Y957210D01*
X1033511D01*
X1031375Y955074D01*
X1025527D01*
X1023391Y957210D01*
X1011019D01*
X1007019Y953210D01*
X1003852D01*
X1001821Y951179D01*
X946363D01*
G01X976397Y473045D02*
X980347Y469095D01*
X988660D01*
X1000039Y457716D01*
X1056114D01*
X1057909Y455921D01*
X1063113D01*
G01X968589Y722434D02*
X971323Y719700D01*
X992296D01*
X1018415Y745819D01*
X1036503D01*
X1109499Y818815D01*
X1184456D01*
X1187771Y815500D01*
X1287280D01*
X1290417Y818637D01*
X1299703D01*
X1301484Y817900D01*
X1301485D01*
X1307259Y815510D01*
X1324813D01*
X1335803Y826500D01*
G01X1315600Y844046D02*
X1314886Y844760D01*
X1309521D01*
X1303900Y839139D01*
Y831895D01*
X1297225Y825220D01*
X1292085D01*
X1287900Y829405D01*
X1270015D01*
X1266475Y825865D01*
X1105364D01*
X1048474Y768975D01*
X1028916D01*
X1026741Y766800D01*
X1021473D01*
X1020504Y765831D01*
Y761271D01*
X1009182Y749949D01*
Y747306D01*
X990576Y728700D01*
X972062D01*
X970839Y729923D01*
G01X965042Y722234D02*
X968351Y725543D01*
X993743D01*
X1016900Y748700D01*
X1035394D01*
X1108329Y821635D01*
X1185626D01*
X1185666Y821595D01*
X1282567D01*
X1282972Y822000D01*
X1303800D01*
X1307200Y825400D01*
Y832300D01*
X1308937Y834037D01*
X1310275Y834591D01*
G01X971081Y722637D02*
X972500Y724056D01*
X994657D01*
X1017891Y747290D01*
X1035979D01*
X1108914Y820225D01*
X1185041D01*
X1188066Y817200D01*
X1286100D01*
X1289400Y820500D01*
X1304600D01*
X1309756Y825656D01*
X1328438D01*
X1335803Y833021D01*
G01X967337Y828901D02*
X971947D01*
X974463Y826385D01*
X998734D01*
X1012549Y840200D01*
X1030072D01*
X1034772Y844900D01*
X1045101D01*
X1050121Y839880D01*
X1051119D01*
X1053281Y837718D01*
X1053913D01*
G01X964280Y927777D02*
X970754Y930459D01*
X972406D01*
X975297Y931657D01*
X979540Y935900D01*
X1001303D01*
X1005403Y931800D01*
X1013800D01*
X1016600Y929000D01*
X1024400D01*
X1026358Y927042D01*
X1075342D01*
X1089800Y941500D01*
X1188422D01*
X1189219Y940703D01*
G01X978352Y730766D02*
X989829D01*
X1006562Y747499D01*
Y754275D01*
X1013332Y761045D01*
Y762739D01*
X1019393Y768800D01*
X1026746D01*
X1028542Y770596D01*
X1048100D01*
X1104779Y827275D01*
X1265890D01*
X1269815Y831200D01*
X1293024D01*
X1308304Y846480D01*
X1316594D01*
X1317298Y847184D01*
G01X1315388Y881834D02*
X1313153Y879599D01*
X1308593D01*
X1307661Y878667D01*
Y876570D01*
X1299340Y868249D01*
Y866060D01*
X1286694Y853414D01*
X1282679D01*
X1276595Y850892D01*
X1269862D01*
X1269782Y850812D01*
X1267875D01*
X1255408Y838345D01*
X1087432D01*
X1047776Y798689D01*
X1039913D01*
X1039056Y799546D01*
X1026553D01*
X1022572Y795565D01*
X1002265D01*
X995070Y788370D01*
X988274D01*
X987394Y787490D01*
G01X978214Y821224D02*
X980474Y823484D01*
X1000524D01*
X1012794Y835754D01*
X1021654D01*
X1024290Y838390D01*
X1030822D01*
X1030823Y838391D01*
X1038317D01*
X1042050Y834658D01*
X1047175D01*
X1047988Y835471D01*
X1054361D01*
X1055900Y837010D01*
Y840700D01*
X1055700Y840900D01*
G01X988240Y1020015D02*
X997462Y1029237D01*
X1006784D01*
X1012100Y1023921D01*
X1013969D01*
X1018290Y1019600D01*
X1050460D01*
X1052850Y1017210D01*
X1175469D01*
X1185599Y1027340D01*
X1218217D01*
X1233462Y1012095D01*
X1291785D01*
X1295500Y1008380D01*
X1335451D01*
X1350460Y993371D01*
Y991510D01*
X1368130Y973840D01*
X1387229D01*
X1409369Y951700D01*
X1460069D01*
X1464732Y953632D01*
X1470300Y959200D01*
X1486900D01*
X1489800Y956300D01*
X1503955D01*
X1505976Y954279D01*
X1514756D01*
X1519082Y949953D01*
Y945233D01*
X1521115Y943200D01*
X1530499D01*
X1531872Y941827D01*
X1637474D01*
X1640896Y938405D01*
X1662706D01*
X1669001Y944700D01*
X1795800D01*
X1820041Y968941D01*
Y996270D01*
X1818898Y997413D01*
X1813423D01*
X1812279Y998557D01*
Y1000848D01*
X1813778Y1002347D01*
Y1003097D01*
X1811793Y1005082D01*
Y1005832D01*
X1813547Y1007586D01*
X1814297D01*
X1816282Y1005601D01*
X1817032D01*
X1818786Y1007355D01*
Y1008105D01*
X1816801Y1010090D01*
Y1010840D01*
X1818555Y1012594D01*
X1819305D01*
X1821290Y1010609D01*
X1822040D01*
X1823794Y1012363D01*
Y1013113D01*
X1821809Y1015098D01*
Y1015848D01*
X1823563Y1017602D01*
X1824313D01*
X1826053Y1015862D01*
X1826761D01*
X1830000Y1019101D01*
Y1090699D01*
X1823708Y1096991D01*
Y1099187D01*
X1824706Y1100185D01*
G01X988240Y1016923D02*
X992445Y1021128D01*
X1013113D01*
X1019841Y1014400D01*
X1048948D01*
X1049948Y1015400D01*
X1176219D01*
X1186349Y1025530D01*
X1216771D01*
X1232016Y1010285D01*
X1291035D01*
X1294750Y1006570D01*
X1334701D01*
X1348650Y992621D01*
Y990760D01*
X1367380Y972030D01*
X1386241D01*
X1410881Y947390D01*
X1463127D01*
X1472737Y957000D01*
X1485634D01*
X1498482Y944152D01*
Y937418D01*
X1501900Y934000D01*
X1515320D01*
X1518591Y930729D01*
X1530991D01*
X1538020Y923700D01*
X1651600D01*
X1670700Y942800D01*
X1796800D01*
X1825925Y971925D01*
Y1012041D01*
X1832400Y1018516D01*
Y1098451D01*
X1824706Y1106145D01*
G01X988240Y1023968D02*
X995362Y1031090D01*
X1007989D01*
X1013348Y1025731D01*
X1014719D01*
X1018550Y1021900D01*
X1025500D01*
X1027800Y1024200D01*
X1046635D01*
X1050125Y1027690D01*
X1061668D01*
X1070338Y1019020D01*
X1174719D01*
X1184849Y1029150D01*
X1218967D01*
X1230817Y1017300D01*
X1272805D01*
X1275356Y1014749D01*
X1275581D01*
X1275582Y1014748D01*
X1276855D01*
X1276856Y1014749D01*
X1291691D01*
X1296250Y1010190D01*
X1336201D01*
X1352270Y994121D01*
Y992260D01*
X1368880Y975650D01*
X1387979D01*
X1410029Y953600D01*
X1459427D01*
X1462623Y954924D01*
X1471699Y964000D01*
X1488691D01*
X1494091Y958600D01*
X1501426D01*
X1503594Y960768D01*
X1512331D01*
X1516378Y956721D01*
Y955434D01*
X1519912Y951900D01*
X1524900D01*
X1526430Y950370D01*
Y946000D01*
X1526930Y945500D01*
X1531300D01*
X1533100Y943700D01*
X1638199D01*
X1641684Y940215D01*
X1659916D01*
X1668701Y949000D01*
X1739100D01*
X1788820Y998720D01*
X1801421D01*
X1827697Y1024996D01*
Y1090159D01*
X1824706Y1093150D01*
G01X1007990Y765899D02*
Y776713D01*
X1007083Y777620D01*
Y783461D01*
X1012436Y788814D01*
X1048154D01*
X1094065Y834725D01*
X1256908D01*
X1265283Y843100D01*
X1278121D01*
X1280644Y845623D01*
X1285890D01*
X1291045Y850778D01*
Y852645D01*
X1305786Y867386D01*
Y867704D01*
G01X1314490Y840889D02*
X1313291Y839690D01*
X1308127D01*
X1305566Y837129D01*
Y831566D01*
X1297810Y823810D01*
X1284162D01*
X1282567Y825405D01*
X1280987D01*
X1280037Y824455D01*
X1106276D01*
X1041282Y759461D01*
X1020845D01*
X1013486Y752102D01*
Y750773D01*
G01X1013319Y785929D02*
X1022687D01*
X1027984Y780632D01*
X1032287D01*
X1038632Y786977D01*
X1050077D01*
X1096015Y832915D01*
X1257658D01*
X1265843Y841100D01*
X1285901D01*
X1287800Y842999D01*
Y844973D01*
X1292422Y849595D01*
X1294290D01*
X1295405Y850710D01*
Y850767D01*
X1295924Y851286D01*
Y854623D01*
X1298449Y857148D01*
X1303348D01*
X1308325Y862125D01*
Y867479D01*
X1309685Y868839D01*
X1313056D01*
X1316606Y872389D01*
X1318900D01*
G01X1013821Y813520D02*
X1015401Y815100D01*
X1023106D01*
X1026863Y818857D01*
X1058935D01*
X1099800Y859722D01*
X1162875D01*
X1166960Y863807D01*
X1269477D01*
X1271438Y861846D01*
G01X1315602Y884988D02*
X1312544Y881930D01*
X1306455D01*
X1287405Y862880D01*
Y862096D01*
X1286904Y861595D01*
X1278292D01*
X1276346Y859649D01*
X1166236D01*
X1164462Y857875D01*
X1100776D01*
X1058854Y815953D01*
X1039246D01*
X1033780Y810487D01*
X1022766D01*
X1021807Y809528D01*
X1015572D01*
X1014781Y810319D01*
G01X1326970Y736464D02*
X1088559D01*
X1062832Y710737D01*
X1030910D01*
X1029885Y711762D01*
G01X1026916Y719769D02*
X1057274D01*
X1084758Y747253D01*
X1148962D01*
G01X1316906Y855068D02*
X1314835Y852997D01*
X1312197D01*
X1300644Y841444D01*
X1294924D01*
X1286835Y833355D01*
X1269513D01*
X1264843Y828685D01*
X1104194D01*
X1052259Y776750D01*
X1038678D01*
G01X1311970Y856671D02*
X1300743Y845444D01*
X1292806D01*
X1292767Y845405D01*
X1292710D01*
X1291595Y844290D01*
Y841494D01*
X1287791Y837690D01*
X1269545D01*
X1263603Y831748D01*
X1261954D01*
X1260301Y830095D01*
X1101095D01*
X1053161Y782161D01*
X1043016D01*
G01X1066931Y645389D02*
Y646189D01*
X1104310Y683568D01*
X1131723D01*
X1140882Y692727D01*
X1285579D01*
X1315606Y662700D01*
X1379900D01*
X1392900Y649700D01*
X1397529D01*
X1401312Y653483D01*
Y655402D01*
X1403855Y657945D01*
X1413928D01*
X1436963Y680980D01*
X1453293D01*
X1455761Y683448D01*
G01X1091031Y374810D02*
X1092421Y376200D01*
X1094799D01*
X1096117Y374882D01*
Y367464D01*
X1100288Y363293D01*
X1217111D01*
X1228698Y365597D01*
X1247892Y384791D01*
X1268552Y388900D01*
X1289100D01*
X1291600Y391400D01*
X1307800D01*
X1318200Y401800D01*
Y406899D01*
X1321501Y410200D01*
X1334900D01*
X1343100Y402000D01*
X1428075D01*
X1453088Y376987D01*
X1484784Y370682D01*
X1486890Y368576D01*
G01X1078920Y856700D02*
X1083839Y861619D01*
X1160877D01*
X1165513Y866255D01*
X1190066D01*
X1192431Y868620D01*
G01X1774476Y995049D02*
X1776100Y993425D01*
Y988948D01*
X1752663Y965511D01*
X1559711D01*
X1556523Y962323D01*
X1537082D01*
X1534059Y959300D01*
X1520601D01*
X1515396Y964505D01*
X1511267D01*
X1506595Y969177D01*
Y977681D01*
X1505776Y978500D01*
X1478922D01*
X1476579Y976157D01*
X1468145D01*
X1464069Y974469D01*
X1458900Y969300D01*
X1446001D01*
X1440020Y963319D01*
X1417838D01*
X1409140Y972017D01*
X1399702D01*
X1390639Y981080D01*
X1371130D01*
X1357700Y994510D01*
Y996371D01*
X1338451Y1015620D01*
X1302978D01*
X1298005Y1020593D01*
X1277192D01*
X1275055Y1022730D01*
X1233067D01*
X1221217Y1034580D01*
X1182599D01*
X1172469Y1024450D01*
X1081195D01*
X1076110Y1029535D01*
G01X1078755Y1031518D02*
X1084013Y1026260D01*
X1171719D01*
X1181849Y1036390D01*
X1227735D01*
X1234176Y1029949D01*
X1256525D01*
X1260171Y1026303D01*
X1294855D01*
X1303728Y1017430D01*
X1339269D01*
X1359800Y996899D01*
Y994970D01*
X1371880Y982890D01*
X1391389D01*
X1400115Y974164D01*
X1411903D01*
X1417718Y968349D01*
X1442295D01*
X1445346Y971400D01*
X1458101D01*
X1463012Y976311D01*
X1467271Y978075D01*
X1475719D01*
X1478044Y980400D01*
X1506728D01*
X1508463Y978665D01*
Y969913D01*
X1512003Y966373D01*
X1516134D01*
X1521342Y961165D01*
X1533065D01*
X1536033Y964133D01*
X1555534D01*
X1558732Y967331D01*
X1751552D01*
X1772635Y988414D01*
Y989646D01*
X1773810Y990821D01*
G01X1531993Y1056453D02*
X1525054D01*
X1507264Y1038663D01*
X1459124D01*
X1451433Y1030972D01*
Y1006675D01*
X1427558Y982800D01*
X1400369D01*
X1393745Y989200D01*
X1382100D01*
X1376936Y994364D01*
Y1004365D01*
X1374201Y1007100D01*
X1358500D01*
X1342990Y1022610D01*
X1318178D01*
X1311203Y1029585D01*
X1261721D01*
X1258217Y1033089D01*
X1257940D01*
X1257860Y1033169D01*
X1235511D01*
X1228980Y1039700D01*
X1180000D01*
X1170296Y1029996D01*
X1101504D01*
X1084207Y1047293D01*
X1076868D01*
G01X1079910Y1045264D02*
X1083097D01*
X1100291Y1028070D01*
X1170969D01*
X1181099Y1038200D01*
X1228485D01*
X1234926Y1031759D01*
X1257275D01*
X1257355Y1031679D01*
X1257632D01*
X1261136Y1028175D01*
X1310618D01*
X1317593Y1021200D01*
X1340799D01*
X1363499Y998500D01*
X1367101D01*
X1378201Y987400D01*
X1392899D01*
X1399099Y981200D01*
X1427953D01*
X1452843Y1006090D01*
Y1030387D01*
X1459709Y1037253D01*
X1511927D01*
X1522374Y1047700D01*
X1526400D01*
X1529549Y1050849D01*
X1531961D01*
G01X1487318Y318200D02*
X1482618D01*
X1480378Y320440D01*
X1463701D01*
X1460727Y323414D01*
X1456287D01*
X1454603Y325098D01*
X1450293D01*
X1449738Y324543D01*
X1448158D01*
X1435401Y337300D01*
X1432444D01*
X1388904Y380840D01*
X1335317D01*
X1331300Y376823D01*
Y368199D01*
X1314401Y351300D01*
X1307101D01*
X1303701Y347900D01*
X1299800D01*
X1295300Y352400D01*
X1291900D01*
X1286865Y347365D01*
X1242771D01*
X1238006Y342600D01*
X1225000D01*
X1222600Y340200D01*
X1218500D01*
X1215965Y342735D01*
X1105623D01*
X1103432Y340544D01*
G01X1097976Y340477D02*
Y342177D01*
X1100519Y344720D01*
X1236852D01*
X1241512Y349380D01*
X1285681D01*
X1290601Y354300D01*
X1314500D01*
X1327007Y366807D01*
Y375091D01*
X1334616Y382700D01*
X1389899D01*
X1430046Y342553D01*
X1436587D01*
X1444283Y334857D01*
X1450468D01*
X1450847Y334478D01*
X1450850Y334477D01*
X1451830D01*
X1454505Y331802D01*
X1469445D01*
X1471530Y329717D01*
Y329001D01*
X1466575Y324049D01*
Y323333D01*
X1467083Y322825D01*
X1467799D01*
X1472754Y327777D01*
X1473470D01*
X1476457Y324790D01*
X1480966D01*
X1483056Y322700D01*
X1486360D01*
G01X1105012Y353504D02*
X1108154Y356646D01*
X1240138D01*
X1243413Y353371D01*
X1281676D01*
X1289305Y361000D01*
X1314300D01*
X1318793Y365493D01*
Y372193D01*
X1326800Y380200D01*
Y387459D01*
X1327813Y388472D01*
X1390712D01*
X1428118Y351066D01*
X1433492D01*
X1441682Y342876D01*
X1452062D01*
X1453177Y341761D01*
Y341704D01*
X1453781Y341100D01*
X1460723D01*
X1463328Y338495D01*
X1478825D01*
X1481111Y336209D01*
X1487985D01*
X1490271Y338495D01*
X1533877D01*
X1545375Y349993D01*
X1556306D01*
X1558089Y348210D01*
X1609319D01*
X1625802Y331727D01*
X1629514D01*
G01X1098845Y353404D02*
X1100854Y351395D01*
X1283595D01*
X1291200Y359000D01*
X1315797D01*
X1323000Y366203D01*
Y373645D01*
X1333955Y384600D01*
X1391642D01*
X1431742Y344500D01*
X1437200D01*
X1443200Y338500D01*
X1450529D01*
X1450554Y338525D01*
X1452134D01*
X1453703Y336956D01*
X1462244D01*
X1465588Y333612D01*
X1470195D01*
X1470207Y333600D01*
X1476754D01*
X1476759Y333605D01*
X1478339D01*
X1478344Y333600D01*
X1494060D01*
X1494899Y334439D01*
X1538567D01*
X1540551Y336423D01*
X1543783D01*
X1550223Y342863D01*
X1556762D01*
X1560299Y346400D01*
X1608569D01*
X1625052Y329917D01*
X1625165D01*
X1626015Y329067D01*
X1629553D01*
G01X1480702Y368516D02*
X1458365D01*
X1426883Y399998D01*
X1342403D01*
X1335501Y406900D01*
X1330401D01*
X1323800Y400299D01*
Y396622D01*
X1321501Y394323D01*
X1316523D01*
X1309700Y387500D01*
Y384600D01*
X1306800Y381700D01*
X1298024D01*
X1294824Y384900D01*
X1284876D01*
X1283000Y383024D01*
X1249692D01*
X1227460Y360792D01*
X1099908D01*
X1093841Y366859D01*
Y371335D01*
G01X1108779Y327705D02*
X1115084Y321400D01*
X1152875D01*
X1158402Y326927D01*
X1190315D01*
X1201037Y337649D01*
X1226757D01*
X1229799Y340691D01*
X1248309D01*
X1250618Y343000D01*
X1257682D01*
X1259991Y340691D01*
G01X1126622Y506256D02*
X1127768Y507402D01*
X1242986D01*
X1265020Y529436D01*
X1371062D01*
X1383907Y516591D01*
G01X1139673Y530000D02*
X1156301D01*
X1168887Y542586D01*
X1250860D01*
X1253490Y539956D01*
X1373458D01*
X1399757Y513657D01*
X1492816D01*
X1498078Y508395D01*
X1515477D01*
X1523367Y516285D01*
X1557514D01*
X1560048Y518819D01*
X1563681D01*
X1576735Y505765D01*
X1588711D01*
X1593162Y510216D01*
Y526402D01*
X1596760Y530000D01*
G01X1155146Y699491D02*
Y698563D01*
X1157260Y696449D01*
X1166825D01*
X1172723Y702347D01*
X1248961D01*
X1271243Y724629D01*
X1290373D01*
X1312526Y702476D01*
X1323601D01*
X1325040Y703915D01*
X1345322D01*
X1346041Y704634D01*
X1358053D01*
X1372078Y690609D01*
X1407932D01*
X1408723Y691400D01*
X1413146D01*
X1413546Y691000D01*
X1420301D01*
X1424333Y695032D01*
X1434076D01*
X1435119Y693989D01*
X1444720D01*
X1449107Y698376D01*
X1475745D01*
X1481287Y700672D01*
X1500079Y719464D01*
X1609296D01*
X1612800Y715960D01*
Y705900D01*
G01X1147468Y766093D02*
X1155741Y774366D01*
X1241964D01*
X1257603Y790005D01*
X1319704D01*
X1323024Y793325D01*
X1388931D01*
X1392586Y796980D01*
Y804989D01*
X1393474Y805877D01*
X1451394D01*
X1460736Y815219D01*
Y856632D01*
X1446189Y871179D01*
Y881888D01*
X1438018Y890059D01*
Y897479D01*
X1439103Y898564D01*
G01X1157646Y699491D02*
Y703453D01*
X1161841Y707648D01*
X1246765D01*
X1269047Y729930D01*
X1292569D01*
X1312421Y710078D01*
X1324562D01*
X1325137Y709503D01*
X1329731D01*
X1332423Y712195D01*
X1344269D01*
X1346713Y709751D01*
X1360173D01*
X1370757Y699167D01*
X1384892D01*
X1388333Y695726D01*
X1405460D01*
X1408686Y698952D01*
X1419618D01*
X1420553Y699887D01*
X1434399D01*
X1436413Y701901D01*
X1445799D01*
X1447381Y703483D01*
X1458143D01*
X1458673Y704013D01*
Y704418D01*
X1473849Y719594D01*
X1476798D01*
X1478380Y718012D01*
X1487155D01*
X1494635Y725492D01*
X1583750D01*
X1609711Y751453D01*
Y762892D01*
X1611627Y764808D01*
Y780327D01*
G01X1162646Y699491D02*
X1165784D01*
X1170407Y704114D01*
X1248229D01*
X1270511Y726396D01*
X1291105D01*
X1310957Y706544D01*
X1323098D01*
X1323673Y705969D01*
X1331195D01*
X1333887Y708661D01*
X1342805D01*
X1345249Y706217D01*
X1358709D01*
X1372734Y692192D01*
X1407276D01*
X1408067Y692983D01*
X1413802D01*
X1414335Y692450D01*
X1419450D01*
X1423615Y696615D01*
X1434732D01*
X1435775Y695572D01*
X1444064D01*
X1448451Y699959D01*
X1475443D01*
X1480380Y702004D01*
X1500069Y721693D01*
X1605772D01*
X1614187Y730108D01*
Y738019D01*
X1612573Y739633D01*
Y761427D01*
G01X1160146Y699491D02*
Y703149D01*
X1162878Y705881D01*
X1247497D01*
X1269779Y728163D01*
X1291837D01*
X1311689Y708311D01*
X1323830D01*
X1324405Y707736D01*
X1330463D01*
X1333155Y710428D01*
X1343537D01*
X1345981Y707984D01*
X1359441D01*
X1373466Y693959D01*
X1406544D01*
X1407335Y694750D01*
X1414534D01*
X1415205Y694079D01*
X1418890D01*
X1423193Y698382D01*
X1435464D01*
X1436507Y697339D01*
X1443332D01*
X1447719Y701726D01*
X1475392D01*
X1479167Y703290D01*
X1499571Y723694D01*
X1604532D01*
X1611327Y730489D01*
Y735973D01*
G01X1293500Y879800D02*
X1285033D01*
X1281905Y876672D01*
X1271671D01*
X1267621Y872622D01*
X1163403D01*
X1159887Y869106D01*
G01X1188598Y381500D02*
X1190676Y379422D01*
X1202679D01*
X1208401Y373700D01*
X1226900D01*
X1247800Y394600D01*
X1285499D01*
X1286799Y393300D01*
X1307001D01*
X1311600Y397899D01*
Y403287D01*
X1320413Y412100D01*
X1335799D01*
X1344080Y403819D01*
X1429335D01*
X1443754Y389400D01*
X1460966D01*
X1463145Y391579D01*
G01X1181654Y894671D02*
X1184616D01*
X1189263Y890024D01*
X1271910D01*
X1277586Y895700D01*
X1277680D01*
X1277760Y895780D01*
X1292807D01*
X1296987Y891600D01*
X1302139D01*
X1303646Y893107D01*
X1310384D01*
X1312177Y894900D01*
X1318017D01*
X1320055Y892862D01*
G01X1315600Y891287D02*
X1304386D01*
X1302809Y889710D01*
X1285149D01*
X1280889Y893970D01*
X1278510D01*
X1271817Y887277D01*
X1188860D01*
X1185058Y883475D01*
G01X1319500Y901500D02*
X1318300Y902700D01*
X1314105D01*
X1305605Y911200D01*
X1287800D01*
X1285800Y913200D01*
X1279891D01*
X1278061Y911370D01*
X1273832D01*
X1272234Y912968D01*
X1176008D01*
X1174461Y914515D01*
G01X1191748Y392676D02*
Y391252D01*
X1200400Y382600D01*
X1203100D01*
X1209900Y375800D01*
X1225701D01*
X1246501Y396600D01*
X1264699D01*
X1267206Y399107D01*
X1288106D01*
X1294009Y405010D01*
X1311210D01*
X1320300Y414100D01*
X1348300D01*
X1357171Y405229D01*
X1446349D01*
X1459873Y391705D01*
G01X1383899Y872399D02*
X1385000Y873500D01*
Y874200D01*
X1387100Y876300D01*
X1387800D01*
X1399416Y887916D01*
Y910116D01*
X1400700Y911400D01*
Y919600D01*
X1396342Y923958D01*
Y930546D01*
X1372558Y954330D01*
X1360045D01*
X1335825Y978550D01*
X1316900D01*
X1316090Y977740D01*
X1306997D01*
X1298300Y986437D01*
X1206463D01*
X1205706Y987194D01*
X1196694D01*
X1195757Y988131D01*
G01X1234904Y316942D02*
X1243962Y326000D01*
X1263072D01*
X1266616Y322456D01*
G01X1241629Y550065D02*
X1327570D01*
X1329553Y552048D01*
X1381216D01*
X1383556Y554388D01*
G01X1378957Y722457D02*
X1382014Y719400D01*
X1393090D01*
X1400686Y726996D01*
X1421257D01*
X1425147Y723106D01*
X1485607D01*
X1506800Y744299D01*
Y843777D01*
X1484400Y866177D01*
Y874900D01*
X1480200Y879100D01*
Y901199D01*
X1457599Y923800D01*
X1421807D01*
X1379007Y966600D01*
X1365130D01*
X1343220Y988510D01*
Y990371D01*
X1333132Y1000459D01*
X1250640D01*
X1248106Y1002993D01*
Y1004700D01*
G01X1385290Y722400D02*
Y724790D01*
X1391500Y731000D01*
X1422181D01*
X1427781Y725400D01*
X1485200D01*
X1502370Y742570D01*
Y844179D01*
X1479748Y866801D01*
Y874152D01*
X1478300Y875600D01*
Y898583D01*
X1455283Y921600D01*
X1420684D01*
X1377494Y964790D01*
X1364380D01*
X1341410Y987760D01*
Y989621D01*
X1332382Y998649D01*
X1246603D01*
X1244696Y1000556D01*
Y1002996D01*
X1245400Y1003700D01*
G01X1250048Y1768377D02*
X1543481D01*
X1547451Y1772347D01*
Y1774407D01*
X1543481Y1778377D01*
X1250048D01*
G01X1259991Y340691D02*
X1274626D01*
X1279348Y345413D01*
X1288313D01*
X1292720Y349820D01*
X1294080D01*
G01X1284659Y377173D02*
Y368315D01*
X1289836Y363138D01*
X1312613D01*
X1316365Y366890D01*
Y372464D01*
X1324906Y381005D01*
Y388136D01*
X1327052Y390282D01*
X1391517D01*
X1427308Y354491D01*
X1438441D01*
X1445532Y347400D01*
X1450299D01*
X1451441Y348542D01*
X1456042D01*
X1457700Y350200D01*
X1463898D01*
X1471109Y342989D01*
X1481193D01*
X1483404Y345200D01*
X1486360D01*
G01Y349700D02*
X1483797Y347137D01*
X1477333D01*
X1470147Y354323D01*
X1445030D01*
X1439966Y359387D01*
X1425379D01*
X1392674Y392092D01*
X1326243D01*
X1322644Y388493D01*
Y381444D01*
X1314343Y373143D01*
Y368114D01*
X1311485Y365256D01*
X1293227D01*
X1289400Y369083D01*
Y380700D01*
X1288200Y381900D01*
X1285426D01*
X1280699Y377173D01*
G01X1283400Y715500D02*
X1290240D01*
X1316698Y689042D01*
X1402248D01*
X1404310Y686980D01*
X1415980D01*
X1418000Y689000D01*
G01X1313999Y888127D02*
X1310449Y884577D01*
X1305316D01*
X1294439Y873700D01*
X1294295D01*
X1294290Y873705D01*
X1292710D01*
X1292705Y873700D01*
X1292463D01*
X1289156Y870393D01*
X1283192D01*
X1279695Y866896D01*
X1274396D01*
G01X1390741Y569000D02*
X1389607Y567866D01*
X1343969D01*
X1341232Y570603D01*
X1302785D01*
X1300817Y568635D01*
G01X1390741Y565000D02*
X1387289Y561548D01*
X1375350D01*
X1368289Y554487D01*
X1312225D01*
X1301194Y565518D01*
G01X1299717Y1024136D02*
X1304613Y1019240D01*
X1340059D01*
X1362699Y996600D01*
X1364700D01*
X1376500Y984800D01*
X1392200D01*
X1397800Y979200D01*
X1429052D01*
X1433707Y983855D01*
X1456856D01*
X1464498Y991497D01*
X1519697D01*
X1521025Y990169D01*
Y987295D01*
X1524173Y984147D01*
X1525279D01*
X1526200Y983226D01*
Y977300D01*
X1528000Y975500D01*
X1744488D01*
X1751500Y982512D01*
Y988593D01*
X1748677Y991416D01*
Y993986D01*
G01X1544736Y305156D02*
X1444325D01*
X1396360Y353121D01*
X1391418D01*
X1389839Y354700D01*
X1380900D01*
X1378550Y357050D01*
Y360650D01*
X1375373Y363827D01*
X1361497D01*
X1356500Y358830D01*
Y335160D01*
X1351023Y329683D01*
X1309683D01*
X1306692Y326692D01*
X1303000D01*
G01Y331000D02*
X1306415D01*
X1307000Y331585D01*
X1350186D01*
X1354600Y335999D01*
Y359801D01*
X1360699Y365900D01*
X1377651D01*
X1382851Y360700D01*
X1388106D01*
X1390788Y358018D01*
X1396052D01*
X1446636Y307434D01*
X1548655D01*
X1550931Y305158D01*
G01X1307819Y474382D02*
X1308701Y473500D01*
X1312549D01*
X1316749Y477700D01*
X1336200D01*
X1347788Y466112D01*
X1402093D01*
X1411846Y456359D01*
Y451538D01*
X1424879Y438505D01*
X1459145D01*
X1464536Y433114D01*
G01X1448726Y864400D02*
X1445445Y861119D01*
Y832738D01*
X1435603Y822896D01*
X1429505D01*
X1428001Y824400D01*
X1422058D01*
X1416444Y830014D01*
X1401804D01*
X1390921Y840897D01*
G01X1429059Y908579D02*
Y888371D01*
X1427634Y886946D01*
Y870058D01*
X1415518Y857942D01*
X1394074D01*
X1392215Y859801D01*
G01X1305786Y867704D02*
Y869421D01*
X1315055Y878690D01*
G01X1331096Y549931D02*
X1336415Y544612D01*
X1379486D01*
X1390741Y555867D01*
Y561000D01*
G01X1319323Y598454D02*
X1381695D01*
X1390741Y607500D01*
G01X1344129Y606914D02*
X1329086D01*
X1327000Y609000D01*
G01X1390741Y615500D02*
X1381298D01*
X1379219Y613421D01*
X1344076D01*
X1343636Y612981D01*
X1335727D01*
X1333224Y615484D01*
G01X1346378Y623734D02*
X1339906D01*
X1337340Y626300D01*
X1332060D01*
X1329700Y623940D01*
X1327003D01*
G01X1327000Y621000D02*
X1330814D01*
X1334128Y624314D01*
X1336493D01*
X1339807Y621000D01*
X1342765D01*
X1344680Y619085D01*
G01X1327011Y646064D02*
X1329352Y648405D01*
X1367974D01*
X1372188Y652619D01*
X1382611D01*
X1387830Y647400D01*
X1397676D01*
X1404209Y653933D01*
X1413150D01*
X1435442Y676225D01*
X1464549D01*
X1473571Y685247D01*
X1474713D01*
G01X1426085Y910281D02*
Y898970D01*
X1415797Y888682D01*
Y882794D01*
X1410343Y877340D01*
Y868544D01*
X1401972Y860173D01*
X1394197D01*
X1391393Y862977D01*
X1369701D01*
X1368865Y862141D01*
G01X1417284Y911009D02*
X1419515Y908778D01*
Y902596D01*
X1408699Y891780D01*
Y876472D01*
X1397729Y865502D01*
X1386512D01*
X1385025Y864015D01*
X1367361D01*
X1365719Y862373D01*
G01X1403085Y460565D02*
X1401418Y458898D01*
X1346555D01*
X1343846Y461607D01*
G01X1344433Y601201D02*
X1367152D01*
X1374251Y608300D01*
X1387541D01*
X1390741Y611500D01*
G01X1340299Y686243D02*
X1346985D01*
X1349545Y683683D01*
X1377751D01*
X1383797Y677637D01*
X1414637D01*
X1418000Y681000D01*
G01Y685000D02*
X1416000Y683000D01*
X1402256D01*
X1398213Y687043D01*
X1350929D01*
G01X1336450Y765675D02*
Y777198D01*
X1344575Y785323D01*
X1355770D01*
X1357515Y787068D01*
X1406955D01*
X1414339Y779684D01*
Y772261D01*
X1422914Y763686D01*
Y752043D01*
X1435600Y739357D01*
X1439340D01*
X1442472Y736225D01*
Y731629D01*
X1446137Y727964D01*
X1460816D01*
G01X1471006Y744818D02*
X1460928D01*
X1442886Y762860D01*
Y772714D01*
X1428758Y786842D01*
X1414157D01*
X1409914Y791085D01*
X1352002D01*
X1348917Y788000D01*
G01X1470801Y739280D02*
X1463872D01*
X1441052Y762100D01*
Y771954D01*
X1427998Y785008D01*
X1413397D01*
X1409154Y789251D01*
X1354068D01*
X1352817Y788000D01*
G01X1365000Y804000D02*
X1367300Y801700D01*
X1381428D01*
X1387128Y807400D01*
X1436098D01*
X1437000Y808302D01*
Y816500D01*
X1435000Y818500D01*
G01Y814500D02*
X1427900Y821600D01*
X1421001D01*
X1416601Y826000D01*
X1411701D01*
X1411001Y825300D01*
X1365570D01*
X1357849Y833021D01*
G01Y836170D02*
X1355900Y834221D01*
Y829700D01*
X1362500Y823100D01*
X1407529D01*
X1408600Y822029D01*
X1414602D01*
X1424131Y812500D01*
X1432000D01*
X1435000Y809500D01*
G01Y825500D02*
X1427948Y832552D01*
X1422726D01*
X1417217Y838061D01*
X1396982D01*
X1387845Y847198D01*
G01X1388766Y850334D02*
X1397015Y842085D01*
X1418827D01*
X1424336Y836576D01*
X1428899D01*
X1434975Y830500D01*
G01X1471375Y433115D02*
X1469260Y431000D01*
X1461099D01*
X1459699Y432400D01*
X1425699D01*
X1420499Y437600D01*
X1377808D01*
X1375400Y435192D01*
G01X1375360Y432234D02*
X1384052D01*
X1387418Y435600D01*
X1420100D01*
X1425339Y430361D01*
X1435424D01*
G01X1383343Y508228D02*
X1386165Y505406D01*
X1406992D01*
X1409392Y507806D01*
X1445588D01*
X1457686Y495708D01*
X1512279D01*
X1514878Y498307D01*
X1550241D01*
X1552983Y495565D01*
X1559796D01*
X1562538Y498307D01*
X1639492D01*
X1647604Y490195D01*
Y467367D01*
G01X1378957Y630957D02*
X1381091D01*
X1391378Y641244D01*
X1400706D01*
X1407162Y647700D01*
X1411176D01*
X1433576Y670100D01*
X1558203D01*
X1562203Y674100D01*
X1570399D01*
X1573500Y677201D01*
Y681999D01*
X1574701Y683200D01*
X1595101D01*
X1609901Y698000D01*
X1620337D01*
X1630852Y708515D01*
Y717848D01*
X1624900Y723800D01*
Y744701D01*
X1619632Y749969D01*
Y765909D01*
X1622392Y768669D01*
X1656112D01*
G01X1435212Y854042D02*
X1386357D01*
X1383766Y856633D01*
G01X1387125Y417312D02*
X1390982Y413455D01*
X1474263D01*
X1475236Y412482D01*
G01X1393177Y424804D02*
X1399273Y430900D01*
X1418101D01*
X1425330Y423671D01*
X1466231D01*
G01X1641615Y379600D02*
X1638971Y382244D01*
X1635862D01*
X1632418Y378800D01*
X1599248D01*
X1596618Y377711D01*
X1573642D01*
X1566955Y384398D01*
X1550998D01*
X1536100Y369500D01*
X1517925D01*
X1492589Y394836D01*
Y415311D01*
X1486300Y421600D01*
X1424800D01*
X1417600Y428800D01*
X1406500D01*
X1400000Y422300D01*
X1392155D01*
X1389777Y424678D01*
X1389557D01*
G01X1389431Y421593D02*
X1390824Y420200D01*
X1403927D01*
X1410594Y426867D01*
X1416632D01*
X1423953Y419546D01*
X1485131D01*
X1489694Y414983D01*
Y394583D01*
X1516777Y367500D01*
X1536900D01*
X1551988Y382588D01*
X1566205D01*
X1573160Y375633D01*
X1596253D01*
G01X1391623Y409900D02*
X1403221D01*
X1404354Y408767D01*
X1413430D01*
X1414498Y409835D01*
X1467335D01*
X1468309Y408861D01*
G01X1469538Y416795D02*
X1423901D01*
X1416196Y424500D01*
X1412700D01*
X1405778Y417578D01*
X1390271D01*
G01X1393208Y428109D02*
X1397499Y432400D01*
X1418800D01*
X1425279Y425921D01*
X1485986D01*
X1495863Y416044D01*
Y403536D01*
X1512398Y387001D01*
X1589293D01*
X1596534Y379760D01*
G01X1466653Y428582D02*
X1465971Y427900D01*
X1425799D01*
X1419799Y433900D01*
X1396136D01*
X1393336Y431100D01*
G01X1803181Y463855D02*
Y472111D01*
X1785226Y490066D01*
X1776020D01*
X1774301Y488347D01*
X1769496D01*
X1756896Y500947D01*
X1663042D01*
X1658049Y505940D01*
X1643840D01*
X1638998Y501098D01*
X1575785D01*
X1568777Y508106D01*
X1521762D01*
X1511866Y498210D01*
X1458283D01*
X1447088Y509405D01*
X1406092D01*
X1404543Y507856D01*
X1393944D01*
G01X1770135Y490711D02*
X1756378Y504468D01*
X1661968D01*
X1658772Y507664D01*
X1643151D01*
X1638395Y502908D01*
X1576702D01*
X1565370Y514240D01*
X1525449D01*
X1514117Y502908D01*
X1512073D01*
X1510655Y504326D01*
X1454937D01*
X1448273Y510990D01*
X1394044D01*
G01X1698716Y550065D02*
X1689900Y541249D01*
X1624179D01*
X1615230Y532300D01*
X1590471D01*
X1580271Y542500D01*
X1567820D01*
X1553620Y528300D01*
X1537905D01*
X1524593Y541612D01*
X1494074D01*
X1484396Y551290D01*
X1428036D01*
X1421860Y557466D01*
X1396854D01*
X1395605Y556217D01*
G01X1384657Y631620D02*
X1392454Y639417D01*
X1401690D01*
X1407573Y645300D01*
X1412099D01*
X1434399Y667600D01*
X1558500D01*
X1562895Y671995D01*
X1571395D01*
X1575600Y676200D01*
Y680348D01*
X1576309Y681057D01*
X1595773D01*
X1610431Y695715D01*
X1620615D01*
X1632800Y707900D01*
Y718657D01*
X1626800Y724657D01*
Y746100D01*
X1621500Y751400D01*
Y764400D01*
X1623600Y766500D01*
X1657201D01*
X1658807Y768106D01*
Y771839D01*
X1657042Y773604D01*
G01X1397000Y652000D02*
X1399129Y654129D01*
Y657228D01*
X1404101Y662200D01*
X1409838D01*
X1436845Y689207D01*
X1454440D01*
X1460111Y683536D01*
G01X1425909Y691120D02*
Y681408D01*
X1408601Y664100D01*
X1403824D01*
X1397000Y657276D01*
Y656000D01*
G01X1448991Y694392D02*
X1446323Y691724D01*
X1435729D01*
X1434326Y690321D01*
X1431558D01*
X1428673Y693206D01*
X1425256D01*
X1422357Y690307D01*
Y681057D01*
X1413295Y671995D01*
X1408995D01*
X1397000Y660000D01*
G01Y699000D02*
X1399000Y701000D01*
X1406154D01*
X1408071Y702917D01*
X1420174D01*
X1421704Y704447D01*
X1434678D01*
X1436839Y706608D01*
X1445139D01*
X1457586Y719055D01*
X1469116D01*
G01X1446538Y719548D02*
X1438850D01*
X1435165Y715863D01*
X1431743D01*
X1426815Y710935D01*
X1400935D01*
X1397000Y707000D01*
G01X1438930Y716363D02*
Y711290D01*
X1434248Y706608D01*
X1420674D01*
X1420226Y707056D01*
X1408494D01*
X1406369Y704931D01*
X1398931D01*
X1397000Y703000D01*
G01X1476677Y827626D02*
X1476475Y827828D01*
Y844359D01*
X1449500Y871334D01*
Y889299D01*
X1454700Y894499D01*
Y899810D01*
X1447302Y907208D01*
X1435037D01*
X1432128Y904299D01*
Y888900D01*
X1429712Y886484D01*
Y865749D01*
X1438929Y856532D01*
Y852549D01*
X1437418Y851038D01*
X1422495D01*
X1417436Y845979D01*
X1400742D01*
X1399872Y845109D01*
G01X1834665Y1213239D02*
Y1016453D01*
X1828211Y1009999D01*
Y971312D01*
X1797599Y940700D01*
X1671400D01*
X1652500Y921800D01*
X1530401D01*
X1526191Y926010D01*
X1501333D01*
X1491439Y935904D01*
Y948514D01*
X1489878Y950075D01*
X1485699D01*
X1480874Y954900D01*
X1473316D01*
X1463918Y945502D01*
X1410074D01*
X1396869Y958707D01*
G01X1638340Y379536D02*
X1632204Y373400D01*
X1573398D01*
X1565620Y381178D01*
X1553409D01*
X1538131Y365900D01*
X1513425D01*
X1482952Y396373D01*
Y408540D01*
X1476627Y414865D01*
X1421676D01*
X1418897Y417644D01*
X1415610D01*
G01X1407844Y411033D02*
X1408456Y411645D01*
X1468313D01*
X1479926Y400032D01*
Y395411D01*
X1511337Y364000D01*
X1538791D01*
X1554159Y379368D01*
X1564870D01*
X1572648Y371590D01*
X1637097D01*
X1640197Y374690D01*
G01X1404249Y735858D02*
X1415142D01*
X1418000Y733000D01*
G01X1431484Y470045D02*
X1436161Y465368D01*
X1449474D01*
X1457126Y457716D01*
X1513201D01*
X1514996Y455921D01*
X1520200D01*
G01X1431000Y591000D02*
Y597500D01*
X1432900Y599400D01*
X1466700D01*
X1509976Y556124D01*
Y550164D01*
X1512113Y548027D01*
X1518561D01*
X1522988Y543600D01*
X1528357D01*
X1541581Y530376D01*
X1552755D01*
X1566979Y544600D01*
X1580920D01*
X1590946Y534574D01*
X1614885D01*
X1623482Y543171D01*
X1676082D01*
X1685211Y552300D01*
X1700301D01*
X1705301Y547300D01*
X1745519D01*
X1750879Y541940D01*
G01X1520729Y634190D02*
X1492045D01*
X1468082Y658153D01*
X1430481D01*
G01X1779143Y995203D02*
X1778320D01*
X1776441Y997082D01*
X1771551D01*
X1766957Y992488D01*
Y985443D01*
X1750666Y969152D01*
X1557662D01*
X1554464Y965954D01*
X1535170D01*
X1532191Y962975D01*
X1522359D01*
X1519304Y966030D01*
Y968597D01*
X1513921Y973980D01*
Y978469D01*
X1509590Y982800D01*
X1463973D01*
X1461594Y980421D01*
Y977593D01*
X1457301Y973300D01*
X1423338D01*
X1419446Y977192D01*
G01X1645685Y381500D02*
Y373912D01*
X1639535Y367762D01*
X1583744D01*
X1575530Y359548D01*
X1509835D01*
X1504920Y364463D01*
X1456737D01*
X1449698Y371502D01*
X1442633D01*
G01X1648835Y390500D02*
X1643692Y385357D01*
Y374754D01*
X1638463Y369525D01*
X1582356D01*
X1574607Y361776D01*
X1510054D01*
X1505550Y366280D01*
X1456990D01*
X1440523Y382747D01*
G01X1434944Y605443D02*
X1438787Y601600D01*
X1467800D01*
X1523800Y545600D01*
X1533602D01*
X1543313Y535889D01*
X1555153D01*
X1568353Y549089D01*
X1579179D01*
X1591873Y536395D01*
X1603076D01*
X1621118Y554437D01*
X1622801D01*
X1623331Y553907D01*
Y545500D01*
X1623831Y545000D01*
X1625361D01*
X1625861Y545500D01*
Y553907D01*
X1626391Y554437D01*
X1627861D01*
X1628391Y553907D01*
Y545600D01*
X1628891Y545100D01*
X1630421D01*
X1630921Y545600D01*
Y553907D01*
X1632314Y555300D01*
X1743741D01*
X1756089Y542952D01*
G01X1438944Y605637D02*
X1441082Y603499D01*
X1468701D01*
X1524278Y547922D01*
X1534974D01*
X1545035Y537861D01*
X1553282D01*
X1566381Y550960D01*
X1580999D01*
X1593744Y538215D01*
X1602014D01*
X1620999Y557200D01*
X1744793D01*
X1758957Y543036D01*
G01X1524200Y646098D02*
X1486516D01*
X1472050Y660564D01*
X1433529D01*
G01X1488000Y731500D02*
X1486019Y733481D01*
X1449606D01*
X1446860Y730735D01*
G01X1488731Y739500D02*
X1486731Y737500D01*
X1474897D01*
X1472933Y735536D01*
X1446717D01*
G01X1762486Y990260D02*
Y984987D01*
X1748521Y971022D01*
X1556726D01*
X1553627Y967923D01*
X1533223D01*
X1530085Y964785D01*
X1523326D01*
X1521122Y966989D01*
Y969978D01*
X1515985Y975115D01*
Y979206D01*
X1510491Y984700D01*
X1463300D01*
X1457800Y979200D01*
X1443879D01*
X1441088Y976409D01*
G01X1760201Y992475D02*
Y986902D01*
X1746263Y972964D01*
X1535065D01*
X1528696Y966595D01*
X1524186D01*
X1522986Y967795D01*
Y970951D01*
X1517829Y976108D01*
Y981270D01*
X1512499Y986600D01*
X1462300D01*
X1457463Y981763D01*
X1440700D01*
G01X1451976Y693844D02*
X1456589D01*
X1458986Y691447D01*
X1476794D01*
G01X1493301Y776911D02*
Y773978D01*
X1482952Y763629D01*
X1462549D01*
X1459805Y760885D01*
X1456520D01*
X1455291Y759656D01*
G01X1499633Y787794D02*
X1496393D01*
X1488894Y780295D01*
Y775228D01*
X1480838Y767172D01*
X1460435D01*
X1456976Y763713D01*
X1455160D01*
X1455159Y763714D01*
G01X1493092Y820444D02*
Y812493D01*
X1458174Y777575D01*
X1454504D01*
G01X1459519Y989432D02*
X1463551Y993464D01*
X1521441D01*
X1526115Y988790D01*
Y986898D01*
X1528149Y984864D01*
Y978142D01*
X1528691Y977600D01*
X1736350D01*
X1745808Y987058D01*
X1745824D01*
G01X1648375Y886766D02*
X1642830Y881221D01*
X1500203D01*
X1490124Y891300D01*
Y899576D01*
X1478128Y911572D01*
Y916717D01*
X1480341Y918930D01*
Y939727D01*
X1482454Y941840D01*
Y950174D01*
X1480414Y952214D01*
G01X1480343Y914776D02*
X1509338D01*
X1512162Y917600D01*
X1633000D01*
X1635100Y915500D01*
X1648799D01*
X1668399Y935100D01*
X1746600D01*
G01X1479196Y970000D02*
X1501173D01*
X1503571Y967602D01*
Y964972D01*
X1505930Y962613D01*
X1513488D01*
X1518222Y957879D01*
Y956475D01*
X1519697Y955000D01*
X1644595D01*
X1647470Y952125D01*
G01X1791088Y77296D02*
X1793000Y79208D01*
Y95562D01*
X1784930Y103632D01*
Y117161D01*
X1807034Y139265D01*
Y139378D01*
X1807077Y139421D01*
Y273404D01*
X1807033Y273448D01*
Y273561D01*
X1782548Y298046D01*
X1691306D01*
X1668543Y320809D01*
X1668430D01*
X1666839Y322400D01*
X1544863D01*
X1542320Y324943D01*
X1539423D01*
X1537963Y323483D01*
X1512577D01*
X1508104Y327956D01*
X1490468D01*
X1487152Y331272D01*
G01X1501000Y317500D02*
X1504000D01*
X1505458Y318958D01*
X1550759D01*
X1552302Y320501D01*
X1561601D01*
X1563104Y318998D01*
X1667794D01*
X1690556Y296236D01*
X1781798D01*
X1805223Y272811D01*
Y140014D01*
X1783120Y117911D01*
Y101879D01*
X1788375Y96624D01*
Y74197D01*
X1790664Y71908D01*
G01X1518517Y878898D02*
X1644840D01*
X1647402Y881460D01*
G01X1650205Y925911D02*
Y932195D01*
X1646800Y935600D01*
X1641100D01*
X1636800Y939900D01*
X1531239D01*
X1529749Y941390D01*
X1519610D01*
X1516500Y944500D01*
Y947500D01*
G01X1648387Y945554D02*
X1533995D01*
X1531937Y947612D01*
X1528500D01*
G01X1530594Y979952D02*
X1638752D01*
X1649390Y990590D01*
X1653414D01*
G01X1578587Y341787D02*
X1580369Y340005D01*
Y335918D01*
X1575590Y331139D01*
X1568852D01*
X1567799Y332192D01*
X1560306D01*
X1557992Y329878D01*
X1554612D01*
X1553534Y328800D01*
Y327337D01*
G01X1578420Y338309D02*
X1576641Y336530D01*
X1559667D01*
X1557485Y334348D01*
X1555357D01*
X1553910Y332901D01*
Y331798D01*
G01X1615913Y692245D02*
X1609717D01*
X1596248Y678776D01*
X1578000D01*
G01X1647402Y881460D02*
X1695817Y929875D01*
X1747275D01*
X1752170Y934770D01*
X1775930D01*
X1779900Y930800D01*
Y923000D01*
X1782700Y920200D01*
X1786530D01*
X1795388Y929058D01*
Y931343D01*
X1794404Y932327D01*
X1791366D01*
X1789537Y930498D01*
G01X1648375Y886766D02*
X1693809Y932200D01*
X1746700D01*
X1751100Y936600D01*
X1776800D01*
X1781900Y931500D01*
Y924101D01*
X1783601Y922400D01*
X1785500D01*
X1793474Y930374D01*
G01X1803181Y463855D02*
X1807290D01*
X1812158Y458987D01*
Y404583D01*
X1780813Y373238D01*
X1754659D01*
X1752497Y371076D01*
G01X1811482Y1226423D02*
X1811666D01*
X1813750Y1224339D01*
Y1224090D01*
X1819001Y1218839D01*
X1826602D01*
X1832300Y1213141D01*
Y1117855D01*
X1821797Y1107352D01*
Y1076903D01*
X1823900Y1074800D01*
Y1024500D01*
X1800325Y1000925D01*
X1784865D01*
X1779143Y995203D01*
G01X1803181Y463855D02*
X1800933Y461607D01*
G54D13*
X51043Y60709D03*
Y150197D03*
X153405Y60709D03*
Y150197D03*
X190325Y455492D03*
Y503760D03*
Y583957D03*
Y636752D03*
X255767Y60709D03*
Y150197D03*
X279360Y368760D03*
Y421555D03*
Y501752D03*
Y550020D03*
X358129Y60709D03*
Y150197D03*
X508130Y60709D03*
Y150197D03*
X610492Y60709D03*
Y150197D03*
X712854Y60709D03*
Y150197D03*
X815216Y60709D03*
Y150197D03*
X965216Y60709D03*
Y150197D03*
X1067578Y60709D03*
Y150197D03*
X1169940Y60709D03*
Y150197D03*
X1272302Y60709D03*
Y150197D03*
X1422303Y60709D03*
Y150197D03*
X1524665Y60709D03*
Y150197D03*
X1561585Y455492D03*
X1627027Y60709D03*
Y150197D03*
X1650620Y368760D03*
Y421555D03*
Y501752D03*
X1729389Y60709D03*
Y150197D03*
G54D22*
X563706Y1056423D03*
X559518Y1066535D03*
X563706Y1076647D03*
X583930Y1056423D03*
X573818Y1052235D03*
X583930Y1076647D03*
X588118Y1066535D03*
X573818Y1080835D03*
X760433Y1480906D03*
X756274Y1490945D03*
X760433Y1500984D03*
X780511Y1480906D03*
X770472Y1476747D03*
Y1505143D03*
X780511Y1500984D03*
X799926Y1253274D03*
X795738Y1263386D03*
X799926Y1273498D03*
X784670Y1490945D03*
X810040Y378544D03*
X805881Y388583D03*
X810040Y398622D03*
X810038Y1249086D03*
Y1277686D03*
X820079Y374385D03*
X830118Y378544D03*
X820079Y402781D03*
X830118Y398622D03*
X820150Y1253274D03*
X824338Y1263386D03*
X820150Y1273498D03*
X834277Y388583D03*
X1010827Y378544D03*
X1006668Y388583D03*
X1010827Y398622D03*
X1020866Y374385D03*
Y402781D03*
X1020793Y1056423D03*
X1016605Y1066535D03*
X1020793Y1076647D03*
X1030905Y378544D03*
X1035064Y388583D03*
X1030905Y398622D03*
X1041017Y1056423D03*
X1030905Y1052235D03*
X1041017Y1076647D03*
X1030905Y1080835D03*
X1045205Y1066535D03*
X1060433Y1480906D03*
X1056274Y1490945D03*
X1060433Y1500984D03*
X1070472Y1476747D03*
Y1505143D03*
X1080511Y1480906D03*
X1084670Y1490945D03*
X1080511Y1500984D03*
X1477879Y1056423D03*
X1473691Y1066535D03*
X1477879Y1076647D03*
X1498103Y1056423D03*
X1487991Y1052235D03*
X1498103Y1076647D03*
X1487991Y1080835D03*
X1502291Y1066535D03*
X1709912Y1263386D03*
X1724212Y1249086D03*
X1714100Y1253274D03*
Y1273498D03*
X1724212Y1277686D03*
X1734324Y1253274D03*
X1738512Y1263386D03*
X1734324Y1273498D03*
G54D32*
G01X925462Y857891D02*
X937377Y869806D01*
X941625D01*
X942425Y870606D01*
Y879207D01*
X936848Y884784D01*
X932962D01*
X932238Y885508D01*
X932118D01*
X930947Y886679D01*
Y886799D01*
X929181Y888565D01*
Y895029D01*
G54D23*
X849441Y1367717D03*
G54D14*
X56348Y1727941D03*
Y1737941D03*
X308448D03*
Y1727941D03*
X629861Y1751765D03*
Y1761765D03*
X881911Y1751765D03*
Y1761765D03*
G54D33*
G01X1372012Y895100D02*
Y885913D01*
X1371096Y884997D01*
X1368882D01*
X1367298Y883413D01*
G01X886600Y862624D02*
X916663D01*
X917579Y863540D01*
Y864480D01*
X917598Y864499D01*
Y864838D01*
X918514Y865754D01*
X919055D01*
X919074Y865773D01*
X919812D01*
X920728Y866689D01*
Y867427D01*
X920748Y867447D01*
Y867987D01*
X921664Y868903D01*
X922204D01*
X922224Y868923D01*
X922962D01*
X923878Y869839D01*
Y870577D01*
X923897Y870596D01*
Y871137D01*
X924813Y872053D01*
X925354D01*
X925374Y872073D01*
X926111D01*
X927027Y872989D01*
Y873726D01*
X927047Y873746D01*
Y874287D01*
X927963Y875203D01*
X928504D01*
X928523Y875222D01*
X929261D01*
X930177Y876138D01*
Y884671D01*
X928612Y886236D01*
G01X880000Y865773D02*
X916663D01*
X917579Y866689D01*
Y867878D01*
X917598Y867897D01*
Y867987D01*
X918514Y868903D01*
X918604D01*
X918624Y868923D01*
X919812D01*
X920728Y869839D01*
Y871027D01*
X920748Y871047D01*
Y871137D01*
X921664Y872053D01*
X921754D01*
X921774Y872073D01*
X922962D01*
X923878Y872989D01*
Y881521D01*
X922313Y883086D01*
G01X1376747Y886562D02*
X1378312Y888127D01*
Y895200D01*
G01X1332654Y889712D02*
X1331073Y891293D01*
Y896282D01*
G01X1373597Y886562D02*
X1375163Y888128D01*
Y895200D01*
G01X1376747Y880263D02*
X1378312Y878698D01*
X1383895D01*
G01X1385929Y884978D02*
X1379247D01*
X1378312Y884043D01*
Y882764D01*
X1377396Y881848D01*
X1375182D01*
X1373597Y880263D01*
G01X879700Y868923D02*
X916663D01*
X917579Y869839D01*
Y875203D01*
X919163Y876787D01*
G01X916014Y873638D02*
X914439Y872063D01*
X879300D01*
G01X1367298Y889712D02*
X1368882Y891296D01*
Y895100D01*
G01X1334222Y897000D02*
Y891293D01*
X1335803Y889712D01*
G01X916014Y873638D02*
X914440Y875212D01*
X912288D01*
X911289Y876211D01*
Y881400D01*
G01X1365713Y894400D02*
Y888127D01*
X1364148Y886562D01*
G01X1360999Y889712D02*
X1362564Y891277D01*
Y894336D01*
G01X1373597Y877114D02*
X1375162Y875549D01*
X1383895D01*
G01X916014Y876787D02*
X917588Y878361D01*
Y884288D01*
G01X1356264Y894300D02*
Y884978D01*
X1354699Y883413D01*
G01X1381481Y893783D02*
Y888127D01*
X1383046Y886562D01*
G01X1384774Y881828D02*
X1381461D01*
X1379896Y880263D01*
G01X1342103Y845619D02*
Y844735D01*
X1340530Y843162D01*
Y841286D01*
X1340130Y840886D01*
X1328743D01*
X1327937Y841692D01*
Y843535D01*
X1327426Y844046D01*
X1315600D01*
G01X1310275Y834591D02*
X1324776D01*
X1326355Y836170D01*
G01X1317298Y847184D02*
X1327201D01*
X1327937Y846448D01*
Y844892D01*
X1328786Y844043D01*
X1339747D01*
X1340518Y844814D01*
Y846311D01*
X1341391Y847184D01*
X1343667D01*
X1345252Y848769D01*
G01X1342103Y889712D02*
X1340527Y888136D01*
Y882773D01*
X1339588Y881834D01*
X1315388D01*
G01X1376747Y845619D02*
X1375182Y844054D01*
X1356554D01*
X1356268Y844340D01*
Y846513D01*
X1355593Y847188D01*
X1350148D01*
X1347014Y844054D01*
X1344139D01*
X1343678Y843593D01*
Y838143D01*
X1343276Y837741D01*
X1328805D01*
X1327936Y838610D01*
Y840301D01*
X1327348Y840889D01*
X1314490D01*
G01X1318900Y872389D02*
X1331079D01*
X1332654Y873964D01*
G01X1338953Y886562D02*
X1337379Y884988D01*
X1315602D01*
G01X1332654Y855068D02*
X1331051Y856671D01*
X1311970D01*
G01X1323205Y892862D02*
X1321630Y891287D01*
X1315600D01*
G01X1379896Y873964D02*
X1381461Y872399D01*
X1383899D01*
G01X1335803Y886562D02*
X1334238Y888127D01*
X1313999D01*
G01X1390921Y840897D02*
X1353821D01*
X1353126Y841592D01*
Y843697D01*
X1352770Y844053D01*
X1350185D01*
X1346998Y840866D01*
Y835311D01*
X1346283Y834596D01*
X1328680D01*
X1327936Y835340D01*
Y836818D01*
X1327015Y837739D01*
X1318475D01*
X1316906Y836170D01*
G01X1392215Y859801D02*
X1372661D01*
X1372032Y859172D01*
Y853978D01*
X1371549Y853495D01*
X1350459D01*
X1347302Y850338D01*
X1341262D01*
X1340533Y849609D01*
Y848106D01*
X1339619Y847192D01*
X1328776D01*
X1327937Y848031D01*
Y849797D01*
X1327396Y850338D01*
X1315325D01*
X1313756Y848769D01*
G01X1315055Y878690D02*
X1342744D01*
X1343668Y879614D01*
Y891297D01*
X1342103Y892862D01*
G01X1368865Y862141D02*
Y857121D01*
X1368384Y856640D01*
X1350197D01*
X1347040Y853483D01*
X1341371D01*
X1340518Y852630D01*
Y851159D01*
X1339697Y850338D01*
X1328837D01*
X1327257Y851918D01*
X1326355D01*
G01X1365719Y862373D02*
Y860359D01*
X1365161Y859801D01*
X1349532D01*
X1346374Y856643D01*
X1341338D01*
X1340517Y855822D01*
Y854133D01*
X1339867Y853483D01*
X1334219D01*
X1332654Y851918D01*
G01X1387845Y847198D02*
X1359420D01*
X1357849Y848769D01*
G01X1354699D02*
X1356264Y850334D01*
X1388766D01*
G01X1383766Y856633D02*
X1375164D01*
X1373598Y855067D01*
G54D24*
X843012Y1592787D03*
Y1602787D03*
Y1612787D03*
Y1622787D03*
X853012Y1592787D03*
Y1602787D03*
Y1612787D03*
Y1622787D03*
X878012Y1592787D03*
Y1602787D03*
Y1612787D03*
Y1622787D03*
X888012Y1592787D03*
Y1602787D03*
Y1612787D03*
Y1622787D03*
X913012Y1592787D03*
Y1602787D03*
Y1612787D03*
Y1622787D03*
X923012Y1592787D03*
Y1602787D03*
Y1612787D03*
Y1622787D03*
X948012Y1592787D03*
Y1602787D03*
Y1612787D03*
Y1622787D03*
X958012Y1592787D03*
Y1602787D03*
Y1612787D03*
Y1622787D03*
X983012Y1592787D03*
X993012D03*
X983012Y1602787D03*
Y1612787D03*
X993012Y1602787D03*
Y1612787D03*
X983012Y1622787D03*
X993012D03*
X1018012Y1592787D03*
X1028012D03*
X1018012Y1602787D03*
Y1612787D03*
X1028012Y1602787D03*
Y1612787D03*
X1018012Y1622787D03*
X1028012D03*
G54D15*
G01X34565Y699082D02*
X27620Y706027D01*
Y813070D01*
X41768Y827218D01*
X56049D01*
G01X73734Y1031812D02*
X73776Y1031854D01*
G01D02*
X87864D01*
X94586Y1025132D01*
Y1023900D01*
G01X95244Y1010303D02*
X94400Y1011147D01*
G01D02*
Y1019497D01*
X97186Y1022283D01*
Y1026806D01*
X90450Y1033542D01*
G01X378119Y953696D02*
X379396Y952419D01*
G01D02*
X386164D01*
X390047Y948536D01*
X392910D01*
G01X406725Y186629D02*
X411164Y191068D01*
Y203138D01*
X412890Y204864D01*
X414658D01*
G01X471876Y937236D02*
X476973D01*
X480922Y933287D01*
X501498D01*
X511821Y943610D01*
X529222D01*
X531525Y941307D01*
X573103D01*
G01X515422Y753455D02*
X523672Y745205D01*
X547375D01*
X556114Y753944D01*
X568433D01*
X570038Y752339D01*
G01X551673Y1023900D02*
X549342Y1026231D01*
X524531D01*
X514566Y1016266D01*
G01X551632Y690280D02*
Y685292D01*
X558724Y678200D01*
X571600D01*
X606593Y713193D01*
X714624D01*
X718781Y709036D01*
Y704621D01*
X716623Y702463D01*
G01X829784Y705489D02*
X826980D01*
X825687Y706782D01*
X795379D01*
X763180Y738981D01*
X721163D01*
G01X871713Y176665D02*
X880475D01*
X882550Y178740D01*
Y199614D01*
X877300Y204864D01*
X871745D01*
G01X1039499Y1098758D02*
X1034500D01*
X1029797Y1103461D01*
Y1220921D01*
G01X1138173Y547075D02*
Y549600D01*
X1138373Y549800D01*
G01X1159535Y542712D02*
X1155172Y547075D01*
X1138173D01*
G01X1629302Y334402D02*
X1606504Y357200D01*
X1508800D01*
X1503800Y362200D01*
X1455001D01*
X1448636Y368565D01*
X1443581D01*
X1441783Y366767D01*
X1426803D01*
X1412553Y381017D01*
Y385222D01*
X1403175Y394600D01*
X1344299D01*
X1334599Y404300D01*
X1332000D01*
X1328400Y400700D01*
Y395500D01*
X1327500Y394600D01*
X1325300D01*
X1321600Y390900D01*
X1320600D01*
X1318068Y388368D01*
Y385268D01*
X1305797Y372997D01*
Y369683D01*
X1307524Y367956D01*
X1310172D01*
G01X1328799Y176665D02*
X1337655D01*
X1339710Y178720D01*
Y199540D01*
X1334386Y204864D01*
X1328831D01*
X80290Y1345691D03*
Y1350683D03*
X75334Y1345691D03*
Y1350683D03*
X80290Y1357603D03*
Y1362595D03*
X75334Y1357603D03*
Y1362595D03*
X80290Y1381801D03*
Y1369889D03*
Y1374881D03*
X75334Y1381801D03*
Y1374881D03*
Y1369889D03*
X80290Y1386793D03*
X75334D03*
X87574Y1345691D03*
Y1350683D03*
X99814D03*
Y1345691D03*
X92530D03*
Y1350683D03*
X87574Y1362595D03*
Y1357603D03*
X99814Y1362595D03*
Y1357603D03*
X92530Y1362595D03*
Y1357603D03*
X87574Y1374881D03*
Y1369795D03*
Y1381801D03*
X99814D03*
Y1374881D03*
Y1369889D03*
X92530Y1374881D03*
Y1369795D03*
Y1381801D03*
X87574Y1399079D03*
Y1393993D03*
Y1386793D03*
X99814Y1399079D03*
Y1394087D03*
Y1386793D03*
X92530Y1393993D03*
Y1399079D03*
Y1386793D03*
X87574Y1410991D03*
Y1405999D03*
X99814Y1410991D03*
Y1405999D03*
X92530Y1410991D03*
Y1405999D03*
X104770Y1350683D03*
Y1345691D03*
X112054D03*
Y1350683D03*
X117010Y1345691D03*
Y1350683D03*
X104770Y1362595D03*
Y1357603D03*
X112054Y1362595D03*
Y1357603D03*
X117010Y1362595D03*
Y1357603D03*
Y1369889D03*
Y1374881D03*
Y1381801D03*
X104770D03*
Y1374881D03*
Y1369889D03*
X112054D03*
Y1374881D03*
Y1381801D03*
X104770Y1399079D03*
Y1394087D03*
Y1386793D03*
X112054Y1399079D03*
Y1394087D03*
Y1386793D03*
X117010Y1394087D03*
Y1399079D03*
Y1386793D03*
X104770Y1410991D03*
Y1405999D03*
X112054Y1410991D03*
Y1405999D03*
X117010Y1410991D03*
Y1405999D03*
X124294Y1350683D03*
Y1345691D03*
X129250Y1350683D03*
Y1345691D03*
X124294Y1362595D03*
Y1357603D03*
X129250D03*
Y1362595D03*
X124294Y1374881D03*
Y1369889D03*
Y1381801D03*
X129250Y1374881D03*
Y1369889D03*
Y1381801D03*
X124294Y1394087D03*
Y1399079D03*
Y1386793D03*
X129250Y1394087D03*
Y1399079D03*
Y1386793D03*
X124294Y1405999D03*
Y1410991D03*
X129250Y1405999D03*
Y1410991D03*
X141490Y1345691D03*
Y1350683D03*
X136534D03*
Y1345691D03*
X148774Y1350683D03*
Y1345691D03*
X141490Y1357603D03*
Y1362595D03*
X136534D03*
Y1357603D03*
X148774D03*
Y1362595D03*
X141490Y1369889D03*
Y1374881D03*
Y1381801D03*
X136534Y1369889D03*
Y1381801D03*
Y1374881D03*
X148774Y1369889D03*
Y1381801D03*
Y1374881D03*
X141490Y1386793D03*
Y1394087D03*
Y1399079D03*
X136534D03*
Y1394087D03*
Y1386793D03*
X148774Y1394087D03*
Y1399079D03*
Y1386793D03*
X141490Y1405999D03*
Y1410991D03*
X136534D03*
Y1405999D03*
X148774D03*
Y1410991D03*
X161014Y1345691D03*
Y1350683D03*
X153730Y1345691D03*
Y1350683D03*
X165970Y1345691D03*
Y1350683D03*
X161014Y1362595D03*
Y1357603D03*
X153730Y1362595D03*
Y1357603D03*
X165970Y1362595D03*
Y1357603D03*
X161014Y1381801D03*
Y1369889D03*
Y1374881D03*
X153730Y1369889D03*
Y1381801D03*
Y1374881D03*
X165970D03*
Y1381801D03*
Y1369889D03*
X161014Y1394087D03*
Y1386793D03*
X153730Y1394087D03*
Y1386793D03*
X165970Y1394087D03*
Y1386793D03*
X161014Y1399079D03*
X153730D03*
X165970D03*
X161014Y1410991D03*
Y1405999D03*
X153730D03*
Y1410991D03*
X165970D03*
Y1405999D03*
X173254Y1345691D03*
Y1350683D03*
X178210Y1345691D03*
Y1350683D03*
X173254Y1362595D03*
Y1357603D03*
X178210D03*
Y1362595D03*
X173254Y1374881D03*
Y1369889D03*
Y1381801D03*
X178210Y1374881D03*
Y1369889D03*
Y1381801D03*
X173254Y1394087D03*
Y1386793D03*
X178210Y1394087D03*
Y1386793D03*
X173254Y1399079D03*
X178210D03*
X173254Y1405999D03*
Y1410991D03*
X178210Y1405999D03*
Y1410991D03*
X185494Y1345597D03*
Y1350683D03*
X190450Y1345597D03*
Y1350683D03*
X185494Y1362595D03*
Y1357603D03*
X197734Y1362595D03*
Y1357603D03*
X190450Y1362595D03*
Y1357603D03*
X185494Y1374881D03*
Y1381801D03*
Y1369889D03*
X197734D03*
Y1381801D03*
Y1374881D03*
X190450Y1369889D03*
Y1374881D03*
Y1381801D03*
X185494Y1393993D03*
Y1386793D03*
X190450Y1393993D03*
Y1386793D03*
X197734Y1394087D03*
Y1386793D03*
X185494Y1399079D03*
X190450D03*
X197734D03*
X185494Y1410991D03*
Y1405999D03*
X190450Y1410991D03*
Y1405999D03*
X197734D03*
Y1410991D03*
X202690Y1362595D03*
Y1357603D03*
Y1369889D03*
Y1381801D03*
Y1374881D03*
Y1394087D03*
Y1386793D03*
Y1399079D03*
X211473Y1446675D03*
Y1451631D03*
Y1462631D03*
Y1457675D03*
X216465Y1446675D03*
Y1451631D03*
Y1462631D03*
Y1457675D03*
X241623Y1348187D03*
X245023D03*
Y1360099D03*
X241623D03*
X253863Y1372385D03*
X257263D03*
X253863Y1384297D03*
X257263D03*
X269503Y1348187D03*
X266103D03*
Y1360099D03*
X269503D03*
X278343Y1372385D03*
Y1384297D03*
X269503Y1396583D03*
X266103D03*
X269503Y1408495D03*
X266103D03*
X293983Y1348187D03*
X290583D03*
X293983Y1360099D03*
X290583D03*
X281743Y1372385D03*
Y1384297D03*
X293983Y1396583D03*
X290583D03*
X293983Y1408495D03*
X290583D03*
X306223Y1372385D03*
X302823D03*
X306223Y1384297D03*
X302823D03*
X315063Y1348187D03*
X318463D03*
X315063Y1360099D03*
X318463D03*
X327303Y1372385D03*
Y1384297D03*
X315063Y1396583D03*
X318463D03*
Y1408495D03*
X315063D03*
X339543Y1348187D03*
X342943D03*
Y1360099D03*
X339543D03*
X330703Y1372385D03*
Y1384297D03*
X339543Y1396583D03*
X342943D03*
Y1408495D03*
X339543D03*
X351783Y1372385D03*
X355183D03*
Y1384297D03*
X351783D03*
X364023Y1348187D03*
X367423D03*
Y1360099D03*
X364023D03*
Y1396583D03*
X367423D03*
X364023Y1408495D03*
X367423D03*
X440402Y1348187D03*
Y1360099D03*
X443802Y1348187D03*
Y1360099D03*
X452642Y1372385D03*
X456042D03*
X452642Y1384297D03*
X456042D03*
X468282Y1348187D03*
X464882D03*
X468282Y1360099D03*
X464882D03*
X468282Y1396583D03*
X464882D03*
Y1408495D03*
X468282D03*
X489362Y1348187D03*
Y1360099D03*
X477122Y1372385D03*
X480522D03*
Y1384297D03*
X477122D03*
X489362Y1396583D03*
Y1408495D03*
X492762Y1348187D03*
Y1360099D03*
X505002Y1372385D03*
X501602D03*
X505002Y1384297D03*
X501602D03*
X492762Y1396583D03*
Y1408495D03*
X517242Y1348187D03*
X513842D03*
Y1360099D03*
X517242D03*
Y1396583D03*
X513842D03*
X517242Y1408495D03*
X513842D03*
X529493Y697443D03*
Y694943D03*
X538322Y1348187D03*
Y1360099D03*
X529482Y1372385D03*
Y1384297D03*
X526082Y1372385D03*
Y1384297D03*
X538322Y1396583D03*
Y1408495D03*
X541722Y1348187D03*
Y1360099D03*
X550562Y1372385D03*
X553962Y1384297D03*
X550562D03*
X553962Y1372385D03*
X541722Y1396583D03*
Y1408495D03*
X562802Y1348187D03*
X566202D03*
Y1360099D03*
X562802D03*
X566202Y1396583D03*
X562802D03*
X566202Y1408495D03*
X562802D03*
X630466Y1394087D03*
X625510Y1399079D03*
Y1394087D03*
X630466Y1399079D03*
X625510Y1405999D03*
X630466D03*
X625510Y1410991D03*
X630466D03*
X649990Y1350683D03*
Y1345691D03*
Y1357603D03*
Y1362595D03*
Y1381801D03*
X642706Y1374881D03*
Y1381801D03*
Y1369889D03*
X649990Y1374881D03*
Y1369889D03*
X637750Y1374881D03*
Y1381801D03*
Y1369889D03*
X649990Y1399079D03*
Y1394087D03*
X642706Y1386793D03*
X649990D03*
X637750Y1399079D03*
X642706Y1394087D03*
X637750D03*
X642706Y1399079D03*
X637750Y1386793D03*
X649990Y1405999D03*
Y1410991D03*
X637750D03*
X642706D03*
Y1405999D03*
X637750D03*
X654946Y1350683D03*
X662230D03*
X667186D03*
Y1345691D03*
X654946D03*
X662230D03*
X654946Y1357603D03*
Y1362595D03*
X662230Y1357603D03*
Y1362595D03*
X667186Y1357603D03*
Y1362595D03*
X662230Y1369889D03*
X667186Y1374881D03*
Y1381801D03*
Y1369889D03*
X662230Y1374881D03*
Y1381801D03*
X654946D03*
Y1369889D03*
Y1374881D03*
X667186Y1399079D03*
Y1393993D03*
X662230D03*
Y1399079D03*
X655046D03*
Y1394087D03*
X667186Y1386793D03*
X662230D03*
X654946D03*
X667186Y1410991D03*
Y1405999D03*
X662230D03*
Y1410991D03*
X655046Y1405999D03*
Y1410991D03*
X679426Y1350683D03*
X674470Y1345691D03*
X679426D03*
X674470Y1350683D03*
Y1357603D03*
Y1362595D03*
X679426Y1357603D03*
Y1362595D03*
Y1374881D03*
X674470D03*
Y1381801D03*
X679426D03*
Y1369889D03*
X674470D03*
X679426Y1399079D03*
X674470Y1394087D03*
X679426D03*
X674470Y1399079D03*
Y1386793D03*
X679426D03*
X674470Y1405999D03*
X679426D03*
X674470Y1410991D03*
X679426D03*
X698950Y1350683D03*
Y1345597D03*
X686710Y1350683D03*
X691666D03*
X686710Y1345691D03*
X691666D03*
X698950Y1362595D03*
Y1357603D03*
X686710D03*
Y1362595D03*
X691666Y1357603D03*
Y1362595D03*
X698950Y1374881D03*
Y1381801D03*
Y1369889D03*
X691666D03*
Y1374881D03*
Y1381801D03*
X686710Y1374881D03*
Y1369889D03*
Y1381801D03*
X698950Y1399079D03*
Y1394087D03*
X686710D03*
Y1399079D03*
X691666Y1394087D03*
Y1399079D03*
X698950Y1386793D03*
X691666D03*
X686710D03*
X698950Y1405999D03*
Y1410991D03*
X686710D03*
X691666D03*
X686710Y1405999D03*
X691666D03*
X716146Y1350683D03*
X711190D03*
X716146Y1345691D03*
X711190D03*
X703906Y1350683D03*
Y1345597D03*
X716146Y1357603D03*
X711190D03*
Y1362595D03*
X716146D03*
X703906Y1357603D03*
Y1362595D03*
X716146Y1374881D03*
Y1381801D03*
Y1369889D03*
X711190D03*
Y1374881D03*
Y1381801D03*
X703906D03*
Y1369889D03*
Y1374881D03*
X716146Y1399079D03*
X711190D03*
X716146Y1393993D03*
X711190D03*
X703906Y1394087D03*
Y1399079D03*
X716146Y1386793D03*
X711190D03*
X703906D03*
X716146Y1405999D03*
X711190D03*
X716146Y1410991D03*
X711190D03*
X703906Y1405999D03*
Y1410991D03*
X723430Y1350683D03*
X728386Y1345691D03*
X723430D03*
X728386Y1350683D03*
Y1357603D03*
Y1362595D03*
X723430Y1357603D03*
Y1362595D03*
X728386Y1381801D03*
Y1374881D03*
Y1369889D03*
X723430D03*
Y1381801D03*
Y1374881D03*
X728386Y1386793D03*
X723430D03*
X728386Y1398985D03*
Y1393993D03*
X723430Y1398985D03*
Y1393993D03*
X728386Y1410897D03*
Y1405905D03*
X723430Y1410897D03*
Y1405905D03*
X747910Y1345691D03*
Y1350683D03*
X735670D03*
X740626D03*
X735670Y1345691D03*
X740626D03*
X747910Y1357603D03*
Y1362595D03*
X735670Y1357603D03*
Y1362595D03*
X740626Y1357603D03*
Y1362595D03*
X747910Y1374881D03*
Y1381801D03*
Y1369889D03*
X740626Y1381801D03*
Y1369889D03*
Y1374881D03*
X735670Y1381801D03*
Y1369889D03*
Y1374881D03*
X747910Y1386793D03*
X735670Y1393993D03*
X740626D03*
Y1398985D03*
X735670D03*
X740626Y1386793D03*
X735670D03*
Y1405905D03*
Y1410897D03*
X740626Y1405905D03*
Y1410897D03*
X765106Y1350683D03*
Y1345597D03*
X760150D03*
Y1350683D03*
X752866Y1345691D03*
Y1350683D03*
X765106Y1362595D03*
Y1357603D03*
X760150D03*
Y1362595D03*
X752866Y1357603D03*
Y1362595D03*
X765106Y1374881D03*
Y1381801D03*
Y1369889D03*
X760150Y1374881D03*
Y1381801D03*
Y1369889D03*
X752866Y1374881D03*
Y1381801D03*
Y1369889D03*
X765106Y1386793D03*
X760150D03*
X752866D03*
X772390Y1350683D03*
X777346D03*
Y1345691D03*
X772390D03*
Y1357603D03*
Y1362595D03*
X777346Y1357603D03*
Y1362595D03*
X884519Y879937D03*
X912864D03*
X925462Y851592D03*
Y857891D03*
X916014Y873638D03*
Y876787D03*
X919163D03*
X922313Y883086D03*
Y886236D03*
X925462D03*
X928612D03*
X1058891Y1345691D03*
Y1350683D03*
X1053935Y1345691D03*
Y1350683D03*
X1058891Y1362595D03*
X1053935D03*
X1058891Y1357603D03*
X1053935D03*
X1058891Y1381801D03*
Y1374881D03*
Y1369889D03*
X1053935Y1381801D03*
Y1374881D03*
Y1369889D03*
X1058891Y1386793D03*
X1053935D03*
X1066175Y1350683D03*
Y1345691D03*
X1071131Y1350683D03*
Y1345691D03*
X1066175Y1357603D03*
Y1362595D03*
X1071131Y1357603D03*
Y1362595D03*
X1066175Y1381801D03*
Y1369795D03*
Y1374881D03*
X1071131Y1381801D03*
Y1369795D03*
Y1374881D03*
X1066175Y1393993D03*
Y1399079D03*
Y1386793D03*
X1071131Y1399079D03*
Y1393993D03*
Y1386793D03*
X1066175Y1405999D03*
Y1410991D03*
X1071131Y1405999D03*
Y1410991D03*
X1090655Y1350683D03*
Y1345691D03*
X1083371D03*
Y1350683D03*
X1078415Y1345691D03*
Y1350683D03*
X1090655Y1357603D03*
Y1362595D03*
X1083371Y1357603D03*
Y1362595D03*
X1078415D03*
Y1357603D03*
X1090655Y1381801D03*
Y1374881D03*
Y1369889D03*
X1083371D03*
Y1374881D03*
Y1381801D03*
X1078415Y1369889D03*
Y1374881D03*
Y1381801D03*
X1090655Y1394087D03*
Y1399079D03*
Y1386793D03*
X1083371D03*
Y1399079D03*
Y1394087D03*
X1078415Y1386793D03*
Y1394087D03*
Y1399079D03*
X1090655Y1405999D03*
Y1410991D03*
X1083371Y1405999D03*
Y1410991D03*
X1078415Y1405999D03*
Y1410991D03*
X1107851Y1345691D03*
X1102895Y1350683D03*
Y1345691D03*
X1107851Y1350683D03*
X1095611D03*
Y1345691D03*
X1107851Y1357603D03*
X1102895Y1362595D03*
Y1357603D03*
X1107851Y1362595D03*
X1095611Y1357603D03*
Y1362595D03*
X1107851Y1369889D03*
Y1374881D03*
Y1381801D03*
X1102895Y1374881D03*
Y1369889D03*
Y1381801D03*
X1095611D03*
Y1374881D03*
Y1369889D03*
X1107851Y1386793D03*
Y1394087D03*
Y1399079D03*
X1102895Y1386793D03*
Y1394087D03*
Y1399079D03*
X1095611D03*
Y1394087D03*
Y1386793D03*
X1107851Y1405999D03*
Y1410991D03*
X1102895Y1405999D03*
Y1410991D03*
X1095611Y1405999D03*
Y1410991D03*
X1115135Y1345691D03*
Y1350683D03*
X1120091Y1345691D03*
Y1350683D03*
X1115135Y1357603D03*
Y1362595D03*
X1120091Y1357603D03*
Y1362595D03*
X1115135Y1374881D03*
Y1381801D03*
Y1369889D03*
X1120091D03*
Y1374881D03*
Y1381801D03*
X1115135Y1394087D03*
Y1399079D03*
Y1386793D03*
X1120091Y1399079D03*
Y1394087D03*
Y1386793D03*
X1115135Y1405999D03*
Y1410991D03*
X1120091Y1405999D03*
Y1410991D03*
X1139615Y1350683D03*
Y1345691D03*
X1132331D03*
Y1350683D03*
X1127375D03*
Y1345691D03*
X1139615Y1357603D03*
Y1362595D03*
X1132331D03*
Y1357603D03*
X1127375D03*
Y1362595D03*
X1139615Y1374881D03*
Y1369889D03*
Y1381801D03*
X1132331Y1369889D03*
Y1381801D03*
Y1374881D03*
X1127375Y1369889D03*
Y1381801D03*
Y1374881D03*
X1139615Y1394087D03*
Y1399079D03*
Y1386793D03*
X1132331D03*
Y1394087D03*
Y1399079D03*
X1127375Y1386793D03*
Y1394087D03*
Y1399079D03*
X1139615Y1405999D03*
Y1410991D03*
X1132331Y1405999D03*
Y1410991D03*
X1127375Y1405999D03*
Y1410991D03*
X1156811Y1350683D03*
Y1345691D03*
X1151855D03*
Y1350683D03*
X1144571D03*
Y1345691D03*
X1156811Y1357603D03*
Y1362595D03*
X1151855D03*
Y1357603D03*
X1144571D03*
Y1362595D03*
X1156811Y1374881D03*
Y1369889D03*
Y1381801D03*
X1151855Y1374881D03*
Y1369889D03*
Y1381801D03*
X1144571Y1369889D03*
Y1381801D03*
Y1374881D03*
X1156811Y1386793D03*
Y1399079D03*
Y1394087D03*
X1151855Y1386793D03*
Y1399079D03*
Y1394087D03*
X1144571D03*
Y1399079D03*
Y1386793D03*
X1156811Y1405999D03*
Y1410991D03*
X1151855Y1405999D03*
Y1410991D03*
X1144571Y1405999D03*
Y1410991D03*
X1169051Y1345597D03*
Y1350683D03*
X1164095D03*
Y1345597D03*
X1169051Y1357603D03*
Y1362595D03*
X1164095Y1357603D03*
Y1362595D03*
X1169051Y1381801D03*
Y1374881D03*
Y1369889D03*
X1164095D03*
Y1381801D03*
Y1374881D03*
X1169051Y1393993D03*
Y1399079D03*
Y1386793D03*
X1164095Y1393993D03*
Y1399079D03*
Y1386793D03*
X1169051Y1410991D03*
Y1405999D03*
X1164095D03*
Y1410991D03*
X1181291Y1350683D03*
Y1345691D03*
X1176335D03*
Y1350683D03*
X1181291Y1362595D03*
Y1357603D03*
X1176335Y1362595D03*
Y1357603D03*
X1181291Y1369889D03*
Y1381801D03*
Y1374881D03*
X1176335Y1369889D03*
Y1381801D03*
Y1374881D03*
X1181291Y1386793D03*
Y1399079D03*
Y1394087D03*
X1176335Y1386793D03*
Y1399079D03*
Y1394087D03*
X1181291Y1405999D03*
Y1410991D03*
X1176335Y1405999D03*
Y1410991D03*
X1230326Y1348187D03*
X1233726D03*
X1230326Y1360099D03*
X1233726D03*
X1254806Y1348187D03*
Y1360099D03*
X1242566Y1372385D03*
X1245966D03*
X1242566Y1384297D03*
X1245966D03*
X1254806Y1396583D03*
Y1408495D03*
X1258206Y1348187D03*
Y1360099D03*
X1270446Y1372385D03*
X1267046D03*
X1270446Y1384297D03*
X1267046D03*
X1258206Y1396583D03*
Y1408495D03*
X1282686Y1348187D03*
X1279286D03*
Y1360099D03*
X1282686D03*
X1279286Y1396583D03*
X1282686D03*
X1279286Y1408495D03*
X1282686D03*
X1291526Y1372385D03*
X1294926D03*
X1291526Y1384297D03*
X1294926D03*
X1313756Y848769D03*
X1316906Y836170D03*
Y855068D03*
X1307166Y1348187D03*
X1303766D03*
X1307166Y1360099D03*
X1303766D03*
X1316006Y1372385D03*
X1319406D03*
X1316006Y1384297D03*
X1319406D03*
X1303766Y1396583D03*
X1307166D03*
Y1408495D03*
X1303766D03*
X1326355Y836170D03*
X1335803Y833021D03*
X1332654Y855068D03*
Y861367D03*
X1326355Y851918D03*
X1332654D03*
Y873964D03*
X1329504Y892862D03*
X1332654Y889712D03*
X1335803Y892862D03*
Y889712D03*
X1320055Y892862D03*
X1323205D03*
X1335803Y886562D03*
X1328246Y1348187D03*
X1331646D03*
X1328246Y1360099D03*
X1331646D03*
Y1396583D03*
X1328246D03*
X1331646Y1408495D03*
X1328246D03*
X1342103Y845619D03*
X1345252Y848769D03*
X1351550Y842470D03*
X1345252Y880263D03*
Y883413D03*
X1342103Y892862D03*
Y889712D03*
X1338953Y886562D03*
X1343886Y1372385D03*
X1340486D03*
Y1384297D03*
X1343886D03*
X1354699Y848769D03*
X1357849D03*
Y833021D03*
Y836170D03*
X1367298Y867665D03*
Y883413D03*
Y889712D03*
X1364148Y886562D03*
X1357849Y892862D03*
X1360999Y889712D03*
X1354699Y883413D03*
X1356126Y1348187D03*
X1352726D03*
X1356126Y1360099D03*
X1352726D03*
X1356126Y1396583D03*
X1352726D03*
Y1408495D03*
X1356126D03*
X1376747Y845619D03*
X1373598Y855067D03*
X1376747Y880263D03*
X1373597D03*
X1379896D03*
X1373597Y877114D03*
X1379896Y873964D03*
X1376747Y886562D03*
X1373597D03*
X1383046D03*
X1379896Y892862D03*
X1464770Y1348187D03*
X1461370D03*
X1464770Y1360099D03*
X1461370D03*
X1473610Y1372385D03*
X1477010D03*
X1473610Y1384297D03*
X1477010D03*
X1489250Y1348187D03*
X1485850D03*
Y1360099D03*
X1489250D03*
X1498090Y1372385D03*
Y1384297D03*
X1485850Y1396583D03*
X1489250D03*
Y1408495D03*
X1485850D03*
X1513730Y1348187D03*
X1510330D03*
Y1360099D03*
X1513730D03*
X1501490Y1372385D03*
Y1384297D03*
X1510330Y1396583D03*
X1513730D03*
X1510330Y1408495D03*
X1513730D03*
X1525970Y1372385D03*
X1522570D03*
X1525970Y1384297D03*
X1522570D03*
X1538210Y1348187D03*
X1534810D03*
X1538210Y1360099D03*
X1534810D03*
X1547050Y1372385D03*
Y1384297D03*
X1538210Y1396583D03*
X1534810D03*
X1538210Y1408495D03*
X1534810D03*
X1559290Y1348187D03*
X1562690D03*
X1559290Y1360099D03*
X1562690D03*
X1550450Y1372385D03*
Y1384297D03*
X1562690Y1396583D03*
X1559290D03*
Y1408495D03*
X1562690D03*
X1574930Y1372385D03*
X1571530D03*
Y1384297D03*
X1574930D03*
X1587170Y1348187D03*
X1583770D03*
X1587170Y1360099D03*
X1583770D03*
Y1396583D03*
X1587170D03*
X1583770Y1408495D03*
X1587170D03*
X1622860Y1350683D03*
Y1345691D03*
X1627816Y1350683D03*
Y1345691D03*
X1622860Y1357603D03*
Y1362595D03*
X1627816Y1357603D03*
Y1362595D03*
X1622860Y1381801D03*
Y1369795D03*
Y1374881D03*
X1627816Y1381801D03*
Y1369795D03*
Y1374881D03*
X1615576Y1381801D03*
Y1374881D03*
Y1369889D03*
Y1386793D03*
X1622860D03*
Y1393993D03*
Y1399079D03*
X1627816Y1386793D03*
Y1399079D03*
Y1393993D03*
X1622860Y1405999D03*
Y1410991D03*
X1627816Y1405999D03*
Y1410991D03*
X1640056Y1345691D03*
Y1350683D03*
X1635100Y1345691D03*
Y1350683D03*
X1640056Y1357603D03*
Y1362595D03*
X1635100D03*
Y1357603D03*
X1640056Y1369889D03*
Y1374881D03*
Y1381801D03*
X1635100Y1369889D03*
Y1374881D03*
Y1381801D03*
X1640056Y1399079D03*
Y1394087D03*
Y1386793D03*
X1635100Y1394087D03*
Y1399079D03*
Y1386793D03*
Y1405999D03*
Y1410991D03*
X1640056Y1405999D03*
Y1410991D03*
X1647340Y1350683D03*
Y1345691D03*
X1652296Y1350683D03*
Y1345691D03*
X1659580Y1350683D03*
Y1345691D03*
X1647340Y1357603D03*
Y1362595D03*
X1652296Y1357603D03*
Y1362595D03*
X1659580D03*
Y1357603D03*
X1647340Y1381801D03*
Y1374881D03*
Y1369889D03*
X1652296Y1381801D03*
Y1374881D03*
Y1369889D03*
X1659580Y1374881D03*
Y1369889D03*
Y1381801D03*
X1647340Y1386793D03*
Y1394087D03*
Y1399079D03*
X1652296Y1386793D03*
Y1399079D03*
Y1394087D03*
X1659580D03*
Y1399079D03*
Y1386793D03*
X1647340Y1405999D03*
Y1410991D03*
X1652296Y1405999D03*
Y1410991D03*
X1659580Y1405999D03*
Y1410991D03*
X1664536Y1350683D03*
Y1345691D03*
X1671820D03*
Y1350683D03*
X1676776Y1345691D03*
Y1350683D03*
X1664536Y1357603D03*
Y1362595D03*
X1671820Y1357603D03*
Y1362595D03*
X1676776Y1357603D03*
Y1362595D03*
X1664536Y1374881D03*
Y1369889D03*
Y1381801D03*
X1671820Y1374881D03*
Y1381801D03*
Y1369889D03*
X1676776D03*
Y1374881D03*
Y1381801D03*
X1664536Y1394087D03*
Y1399079D03*
Y1386793D03*
X1671820D03*
Y1394087D03*
Y1399079D03*
X1676776Y1386793D03*
Y1399079D03*
Y1394087D03*
X1664536Y1405999D03*
Y1410991D03*
X1671820Y1405999D03*
Y1410991D03*
X1676776Y1405999D03*
Y1410991D03*
X1689016Y1345691D03*
Y1350683D03*
X1684060D03*
Y1345691D03*
X1689016Y1362595D03*
Y1357603D03*
X1684060D03*
Y1362595D03*
X1689016Y1369889D03*
Y1381801D03*
Y1374881D03*
X1684060Y1369889D03*
Y1381801D03*
Y1374881D03*
X1689016Y1394087D03*
Y1399079D03*
Y1386793D03*
X1684060Y1394087D03*
Y1399079D03*
Y1386793D03*
X1689016Y1405999D03*
Y1410991D03*
X1684060Y1405999D03*
Y1410991D03*
X1696300Y1350683D03*
Y1345691D03*
X1701256Y1350683D03*
Y1345691D03*
X1708540D03*
Y1350683D03*
X1696300Y1357603D03*
Y1362595D03*
X1701256Y1357603D03*
Y1362595D03*
X1708540D03*
Y1357603D03*
X1696300Y1374881D03*
Y1369889D03*
Y1381801D03*
X1701256Y1369889D03*
Y1381801D03*
Y1374881D03*
X1708540D03*
Y1369889D03*
Y1381801D03*
X1696300Y1386793D03*
Y1394087D03*
Y1399079D03*
X1701256Y1386793D03*
Y1394087D03*
Y1399079D03*
X1708540D03*
Y1394087D03*
Y1386793D03*
X1696300Y1405999D03*
Y1410991D03*
X1701256Y1405999D03*
Y1410991D03*
X1708540Y1405999D03*
Y1410991D03*
X1713496Y1350683D03*
Y1345691D03*
X1720780Y1350683D03*
Y1345597D03*
X1725736Y1350683D03*
Y1345597D03*
X1713496Y1357603D03*
Y1362595D03*
X1720780Y1357603D03*
Y1362595D03*
X1725736Y1357603D03*
Y1362595D03*
X1713496Y1374881D03*
Y1369889D03*
Y1381801D03*
X1720780Y1369889D03*
Y1381801D03*
Y1374881D03*
X1725736Y1381801D03*
Y1374881D03*
Y1369889D03*
X1713496Y1399079D03*
Y1394087D03*
Y1386793D03*
X1720780D03*
Y1393993D03*
Y1399079D03*
X1725736Y1386793D03*
Y1399079D03*
Y1393993D03*
X1713496Y1405999D03*
Y1410991D03*
X1720780Y1405999D03*
Y1410991D03*
X1725736Y1405999D03*
Y1410991D03*
X1737976Y1350683D03*
Y1345691D03*
X1733020D03*
Y1350683D03*
X1737976Y1362595D03*
Y1357603D03*
X1733020Y1362595D03*
Y1357603D03*
X1737976Y1369889D03*
Y1374881D03*
X1733020Y1369889D03*
Y1381801D03*
Y1374881D03*
X1737976Y1381801D03*
Y1399079D03*
Y1394087D03*
Y1386793D03*
X1733020Y1399079D03*
Y1394087D03*
Y1386793D03*
X1737976Y1405999D03*
Y1410991D03*
X1733020Y1405999D03*
Y1410991D03*
G54D34*
G01X140062Y1131869D02*
X140092Y1131839D01*
X140149D01*
X140314Y1131674D01*
X151534D01*
X152184Y1132324D01*
Y1132819D01*
X151834Y1133169D01*
X150689D01*
G01X154429D02*
X153284D01*
X152934Y1132819D01*
Y1132013D01*
X151845Y1130924D01*
X140314D01*
X140149Y1130759D01*
X140062D01*
G01X136518Y1136257D02*
X136560D01*
X136600Y1136217D01*
X136832Y1136218D01*
X138450Y1134600D01*
X144300D01*
X145453Y1135753D01*
Y1136559D01*
X145803Y1136909D01*
X146948D01*
G01X137303Y1137042D02*
X137364Y1136981D01*
Y1136747D01*
X138761Y1135350D01*
X143989D01*
X144703Y1136064D01*
Y1136559D01*
X144353Y1136909D01*
X143208D01*
G01X165649Y1133169D02*
X164504D01*
X164154Y1132819D01*
Y1132013D01*
X163065Y1130924D01*
X160602D01*
X159664Y1131862D01*
Y1137875D01*
X159135Y1138404D01*
X140896D01*
X138660Y1140640D01*
X138404D01*
X138343Y1140701D01*
G01X161909Y1133169D02*
X163054D01*
X163404Y1132819D01*
Y1132324D01*
X162754Y1131674D01*
X160913D01*
X160414Y1132173D01*
Y1138186D01*
X159446Y1139154D01*
X141207D01*
X139188Y1141173D01*
X139189Y1141425D01*
X139128Y1141486D01*
G01X140301Y1146076D02*
Y1145989D01*
X140466Y1145824D01*
Y1143377D01*
X141689Y1142154D01*
X166784D01*
X167144Y1141794D01*
Y1135873D01*
X168353Y1134664D01*
X170545D01*
X171634Y1135753D01*
Y1136559D01*
X171984Y1136909D01*
X173129D01*
G01X169389D02*
X170534D01*
X170884Y1136559D01*
Y1136064D01*
X170234Y1135414D01*
X168664D01*
X167894Y1136184D01*
Y1142105D01*
X167095Y1142904D01*
X142000D01*
X141216Y1143688D01*
Y1145824D01*
X141381Y1145989D01*
Y1146046D01*
X141411Y1146076D01*
G01X177425Y1260455D02*
Y1260368D01*
X177245Y1260188D01*
Y1227548D01*
X177745Y1227048D01*
X178390D01*
X178740Y1227398D01*
Y1228543D01*
G01X168834Y1260555D02*
Y1260468D01*
X169014Y1260288D01*
Y1227286D01*
X170002Y1226298D01*
X170909D01*
X171259Y1225948D01*
Y1224803D01*
G01X181165Y1260643D02*
Y1260556D01*
X180985Y1260376D01*
Y1235028D01*
X181485Y1234528D01*
X182130D01*
X182480Y1234878D01*
Y1236023D01*
G01X180055Y1260643D02*
Y1260556D01*
X180235Y1260376D01*
Y1234717D01*
X181174Y1233778D01*
X182130D01*
X182480Y1233428D01*
Y1232283D01*
G01X172574Y1260543D02*
Y1260456D01*
X172754Y1260276D01*
Y1234717D01*
X173693Y1233778D01*
X174649D01*
X174999Y1233428D01*
Y1232283D01*
G01X169944Y1260555D02*
Y1260468D01*
X169764Y1260288D01*
Y1227597D01*
X170313Y1227048D01*
X170909D01*
X171259Y1227398D01*
Y1228543D01*
G01X176315Y1260455D02*
Y1260368D01*
X176495Y1260188D01*
Y1227237D01*
X177434Y1226298D01*
X178390D01*
X178740Y1225948D01*
Y1224803D01*
G01X173684Y1260543D02*
Y1260456D01*
X173504Y1260276D01*
Y1235028D01*
X174004Y1234528D01*
X174649D01*
X174999Y1234878D01*
Y1236023D01*
G01X196125Y1260425D02*
Y1260338D01*
X195945Y1260158D01*
Y1235117D01*
X196534Y1234528D01*
X197090D01*
X197440Y1234878D01*
Y1236023D01*
G01X183795Y1260627D02*
Y1260540D01*
X183975Y1260360D01*
Y1227238D01*
X184915Y1226298D01*
X185870D01*
X186220Y1225948D01*
Y1224803D01*
G01X192385Y1260355D02*
Y1260268D01*
X192205Y1260088D01*
Y1227548D01*
X192705Y1227048D01*
X193350D01*
X193700Y1227398D01*
Y1228543D01*
G01X195015Y1260425D02*
Y1260338D01*
X195195Y1260158D01*
Y1234806D01*
X196223Y1233778D01*
X197090D01*
X197440Y1233428D01*
Y1232283D01*
G01X188645Y1260343D02*
Y1260256D01*
X188465Y1260076D01*
Y1235028D01*
X188965Y1234528D01*
X189610D01*
X189960Y1234878D01*
Y1236023D01*
G01X184905Y1260627D02*
Y1260540D01*
X184725Y1260360D01*
Y1227549D01*
X185226Y1227048D01*
X185870D01*
X186220Y1227398D01*
Y1228543D01*
G01X191275Y1260355D02*
Y1260268D01*
X191455Y1260088D01*
Y1227237D01*
X192394Y1226298D01*
X193350D01*
X193700Y1225948D01*
Y1224803D01*
G01X187535Y1260343D02*
Y1260256D01*
X187715Y1260076D01*
Y1234717D01*
X188654Y1233778D01*
X189610D01*
X189960Y1233428D01*
Y1232283D01*
G01X204921D02*
Y1233428D01*
X204571Y1233778D01*
X203616D01*
X202676Y1234718D01*
Y1260585D01*
X202496Y1260765D01*
Y1260852D01*
G01X198756Y1260555D02*
Y1260468D01*
X198936Y1260288D01*
Y1227237D01*
X199875Y1226298D01*
X200831D01*
X201181Y1225948D01*
Y1224803D01*
G01X212401Y1232283D02*
Y1233428D01*
X212051Y1233778D01*
X211096D01*
X210156Y1234718D01*
Y1260557D01*
X209976Y1260737D01*
Y1260824D01*
G01X207346Y1261000D02*
Y1260913D01*
X207166Y1260733D01*
Y1227548D01*
X207666Y1227048D01*
X208311D01*
X208661Y1227398D01*
Y1228543D01*
G01X212401Y1236023D02*
Y1234878D01*
X212051Y1234528D01*
X211407D01*
X210906Y1235029D01*
Y1260557D01*
X211086Y1260737D01*
Y1260824D01*
G01X213716Y1260672D02*
Y1260585D01*
X213896Y1260405D01*
Y1227238D01*
X214836Y1226298D01*
X215791D01*
X216141Y1225948D01*
Y1224803D01*
G01X206236Y1261000D02*
Y1260913D01*
X206416Y1260733D01*
Y1227237D01*
X207355Y1226298D01*
X208311D01*
X208661Y1225948D01*
Y1224803D01*
G01X199866Y1260555D02*
Y1260468D01*
X199686Y1260288D01*
Y1227548D01*
X200186Y1227048D01*
X200831D01*
X201181Y1227398D01*
Y1228543D01*
G01X204921Y1236023D02*
Y1234878D01*
X204571Y1234528D01*
X203927D01*
X203426Y1235029D01*
Y1260585D01*
X203606Y1260765D01*
Y1260852D01*
G01X217456Y1260381D02*
Y1260294D01*
X217636Y1260114D01*
Y1234717D01*
X218575Y1233778D01*
X219531D01*
X219881Y1233428D01*
Y1232283D01*
G01X218566Y1260381D02*
Y1260294D01*
X218386Y1260114D01*
Y1235028D01*
X218886Y1234528D01*
X219531D01*
X219881Y1234878D01*
Y1236023D01*
G01X221197Y1260683D02*
Y1260596D01*
X221377Y1260416D01*
Y1227237D01*
X222316Y1226298D01*
X223272D01*
X223622Y1225948D01*
Y1224803D01*
G01X227362Y1232283D02*
Y1233428D01*
X227012Y1233778D01*
X226057D01*
X225117Y1234718D01*
Y1260358D01*
X224937Y1260538D01*
Y1260625D01*
G01X222307Y1260683D02*
Y1260596D01*
X222127Y1260416D01*
Y1227548D01*
X222627Y1227048D01*
X223272D01*
X223622Y1227398D01*
Y1228543D01*
G01X214826Y1260672D02*
Y1260585D01*
X214646Y1260405D01*
Y1227549D01*
X215147Y1227048D01*
X215791D01*
X216141Y1227398D01*
Y1228543D01*
G01X227362Y1236023D02*
Y1234878D01*
X227012Y1234528D01*
X226368D01*
X225867Y1235029D01*
Y1260358D01*
X226047Y1260538D01*
Y1260625D01*
G01X628346Y1224803D02*
Y1225848D01*
X627896Y1226298D01*
X626948D01*
X626101Y1227145D01*
Y1259824D01*
X625921Y1260004D01*
Y1260091D01*
G01X628346Y1228543D02*
Y1227498D01*
X627896Y1227048D01*
X627259D01*
X626851Y1227456D01*
Y1259824D01*
X627031Y1260004D01*
Y1260091D01*
G01X632086Y1232283D02*
Y1233328D01*
X631636Y1233778D01*
X630661D01*
X629841Y1234598D01*
Y1259824D01*
X629661Y1260004D01*
Y1260091D01*
G01X632086Y1236023D02*
Y1234978D01*
X631636Y1234528D01*
X630972D01*
X630591Y1234909D01*
Y1259824D01*
X630771Y1260004D01*
Y1260091D01*
G01X635827Y1224803D02*
Y1225848D01*
X635377Y1226298D01*
X634429D01*
X633582Y1227145D01*
Y1259824D01*
X633402Y1260004D01*
Y1260091D01*
G01X639567Y1236023D02*
Y1234978D01*
X639117Y1234528D01*
X638480D01*
X638072Y1234936D01*
Y1259824D01*
X638252Y1260004D01*
Y1260091D01*
G01X639567Y1232283D02*
Y1233328D01*
X639117Y1233778D01*
X638169D01*
X637322Y1234625D01*
Y1259824D01*
X637142Y1260004D01*
Y1260091D01*
G01X635827Y1228543D02*
Y1227498D01*
X635377Y1227048D01*
X634740D01*
X634332Y1227456D01*
Y1259824D01*
X634512Y1260004D01*
Y1260091D01*
G01X643307Y1224803D02*
Y1225848D01*
X642857Y1226298D01*
X641909D01*
X641062Y1227145D01*
Y1259824D01*
X640882Y1260004D01*
Y1260091D01*
G01X647047Y1232283D02*
Y1233328D01*
X646597Y1233778D01*
X645649D01*
X644802Y1234625D01*
Y1259824D01*
X644622Y1260004D01*
Y1260091D01*
G01X643307Y1228543D02*
Y1227498D01*
X642857Y1227048D01*
X642220D01*
X641812Y1227456D01*
Y1259824D01*
X641992Y1260004D01*
Y1260091D01*
G01X650787Y1224803D02*
Y1225848D01*
X650337Y1226298D01*
X649544D01*
X648542Y1227300D01*
Y1259824D01*
X648362Y1260004D01*
Y1260091D01*
G01X647047Y1236023D02*
Y1234978D01*
X646597Y1234528D01*
X645960D01*
X645552Y1234936D01*
Y1259824D01*
X645732Y1260004D01*
Y1260091D01*
G01X650787Y1228543D02*
Y1227498D01*
X650337Y1227048D01*
X649855D01*
X649292Y1227611D01*
Y1259824D01*
X649472Y1260004D01*
Y1260091D01*
G01X654527Y1236023D02*
Y1234978D01*
X654077Y1234528D01*
X653440D01*
X653032Y1234936D01*
Y1259824D01*
X653212Y1260004D01*
Y1260091D01*
G01X654527Y1232283D02*
Y1233328D01*
X654077Y1233778D01*
X653129D01*
X652282Y1234625D01*
Y1259824D01*
X652102Y1260004D01*
Y1260091D01*
G01X716795Y1260112D02*
Y1260000D01*
X716615Y1259820D01*
Y1227456D01*
X717023Y1227048D01*
X717660D01*
X718110Y1227498D01*
Y1228543D01*
G01X721850Y1236023D02*
Y1234978D01*
X721400Y1234528D01*
X720763D01*
X720355Y1234936D01*
Y1259824D01*
X720535Y1260004D01*
Y1260091D01*
G01X721850Y1232283D02*
Y1233328D01*
X721400Y1233778D01*
X720452D01*
X719605Y1234625D01*
Y1259824D01*
X719425Y1260004D01*
Y1260091D01*
G01X715685Y1260112D02*
Y1260000D01*
X715865Y1259820D01*
Y1227145D01*
X716712Y1226298D01*
X717660D01*
X718110Y1225848D01*
Y1224803D01*
G01X725590Y1228543D02*
Y1227498D01*
X725140Y1227048D01*
X724503D01*
X724095Y1227456D01*
Y1259824D01*
X724275Y1260004D01*
Y1260091D01*
G01X725590Y1224803D02*
Y1225848D01*
X725140Y1226298D01*
X724192D01*
X723345Y1227145D01*
Y1259824D01*
X723165Y1260004D01*
Y1260091D01*
G01X726906D02*
Y1260004D01*
X727086Y1259824D01*
Y1234625D01*
X727933Y1233778D01*
X728881D01*
X729331Y1233328D01*
Y1232283D01*
G01X733071Y1224803D02*
Y1225848D01*
X732621Y1226298D01*
X731673D01*
X730826Y1227145D01*
Y1259824D01*
X730646Y1260004D01*
Y1260091D01*
G01X728016D02*
Y1260004D01*
X727836Y1259824D01*
Y1234936D01*
X728244Y1234528D01*
X728881D01*
X729331Y1234978D01*
Y1236023D01*
G01X733071Y1228543D02*
Y1227498D01*
X732621Y1227048D01*
X731984D01*
X731576Y1227456D01*
Y1259824D01*
X731756Y1260004D01*
Y1260091D01*
G01X736811Y1232283D02*
Y1233328D01*
X736361Y1233778D01*
X735413D01*
X734566Y1234625D01*
Y1259824D01*
X734386Y1260004D01*
Y1260091D01*
G01X736811Y1236023D02*
Y1234978D01*
X736361Y1234528D01*
X735724D01*
X735316Y1234936D01*
Y1259824D01*
X735496Y1260004D01*
Y1260091D01*
G01X738126D02*
Y1260004D01*
X738306Y1259824D01*
Y1227145D01*
X739153Y1226298D01*
X740101D01*
X740551Y1225848D01*
Y1224803D01*
G01X739236Y1260091D02*
Y1260004D01*
X739056Y1259824D01*
Y1227456D01*
X739464Y1227048D01*
X740101D01*
X740551Y1227498D01*
Y1228543D01*
G01X742976Y1260091D02*
Y1260004D01*
X742796Y1259824D01*
Y1234936D01*
X743204Y1234528D01*
X743841D01*
X744291Y1234978D01*
Y1236023D01*
G01X741866Y1260091D02*
Y1260004D01*
X742046Y1259824D01*
Y1234625D01*
X742893Y1233778D01*
X743841D01*
X744291Y1233328D01*
Y1232283D01*
G01X1086747Y1259824D02*
Y1259712D01*
X1086927Y1259532D01*
Y1234625D01*
X1087774Y1233778D01*
X1088722D01*
X1089172Y1233328D01*
Y1232283D01*
G01X1090488Y1259824D02*
Y1259712D01*
X1090668Y1259532D01*
Y1227200D01*
X1091570Y1226298D01*
X1092463D01*
X1092913Y1225848D01*
Y1224803D01*
G01X1087857Y1259824D02*
Y1259712D01*
X1087677Y1259532D01*
Y1234936D01*
X1088085Y1234528D01*
X1088722D01*
X1089172Y1234978D01*
Y1236023D01*
G01X1091598Y1259824D02*
Y1259712D01*
X1091418Y1259532D01*
Y1227511D01*
X1091881Y1227048D01*
X1092463D01*
X1092913Y1227498D01*
Y1228543D01*
G01X1083007Y1259824D02*
Y1259712D01*
X1083187Y1259532D01*
Y1227145D01*
X1084034Y1226298D01*
X1084982D01*
X1085432Y1225848D01*
Y1224803D01*
G01X1084117Y1259824D02*
Y1259712D01*
X1083937Y1259532D01*
Y1227456D01*
X1084345Y1227048D01*
X1084982D01*
X1085432Y1227498D01*
Y1228543D01*
G01X1099078Y1259824D02*
Y1259712D01*
X1098898Y1259532D01*
Y1227456D01*
X1099306Y1227048D01*
X1099943D01*
X1100393Y1227498D01*
Y1228543D01*
G01X1104133Y1236023D02*
Y1234978D01*
X1103683Y1234528D01*
X1103046D01*
X1102638Y1234936D01*
Y1259532D01*
X1102818Y1259712D01*
Y1259824D01*
G01X1101708D02*
Y1259712D01*
X1101888Y1259532D01*
Y1234625D01*
X1102735Y1233778D01*
X1103683D01*
X1104133Y1233328D01*
Y1232283D01*
G01X1105448Y1259824D02*
Y1259712D01*
X1105628Y1259532D01*
Y1227200D01*
X1106530Y1226298D01*
X1107423D01*
X1107873Y1225848D01*
Y1224803D01*
G01X1095338Y1259824D02*
Y1259712D01*
X1095158Y1259532D01*
Y1234936D01*
X1095566Y1234528D01*
X1096203D01*
X1096653Y1234978D01*
Y1236023D01*
G01X1097968Y1259824D02*
Y1259712D01*
X1098148Y1259532D01*
Y1227145D01*
X1098995Y1226298D01*
X1099943D01*
X1100393Y1225848D01*
Y1224803D01*
G01X1106558Y1259824D02*
Y1259712D01*
X1106378Y1259532D01*
Y1227511D01*
X1106841Y1227048D01*
X1107423D01*
X1107873Y1227498D01*
Y1228543D01*
G01X1094228Y1259824D02*
Y1259712D01*
X1094408Y1259532D01*
Y1234625D01*
X1095255Y1233778D01*
X1096203D01*
X1096653Y1233328D01*
Y1232283D01*
G01X1120409Y1259824D02*
Y1259712D01*
X1120589Y1259532D01*
Y1227400D01*
X1121691Y1226298D01*
X1122384D01*
X1122834Y1225848D01*
Y1224803D01*
G01X1116669Y1259824D02*
Y1259712D01*
X1116849Y1259532D01*
Y1234625D01*
X1117696Y1233778D01*
X1118644D01*
X1119094Y1233328D01*
Y1232283D01*
G01X1114039Y1259824D02*
Y1259712D01*
X1113859Y1259532D01*
Y1227456D01*
X1114267Y1227048D01*
X1114904D01*
X1115354Y1227498D01*
Y1228543D01*
G01X1109188Y1259824D02*
Y1259712D01*
X1109368Y1259532D01*
Y1234625D01*
X1110215Y1233778D01*
X1111163D01*
X1111613Y1233328D01*
Y1232283D01*
G01X1119094Y1236023D02*
Y1234978D01*
X1118644Y1234528D01*
X1118007D01*
X1117599Y1234936D01*
Y1259532D01*
X1117779Y1259712D01*
Y1259824D01*
G01X1112929D02*
Y1259712D01*
X1113109Y1259532D01*
Y1227145D01*
X1113956Y1226298D01*
X1114904D01*
X1115354Y1225848D01*
Y1224803D01*
G01X1110298Y1259824D02*
Y1259712D01*
X1110118Y1259532D01*
Y1234936D01*
X1110526Y1234528D01*
X1111163D01*
X1111613Y1234978D01*
Y1236023D01*
G01X1122834Y1228543D02*
Y1227498D01*
X1122384Y1227048D01*
X1122002D01*
X1121339Y1227711D01*
Y1259532D01*
X1121519Y1259712D01*
Y1259824D01*
G01X1134054Y1236023D02*
Y1234978D01*
X1133604Y1234528D01*
X1132967D01*
X1132559Y1234936D01*
Y1259732D01*
X1132739Y1259912D01*
Y1260024D01*
G01X1136479Y1259824D02*
Y1259712D01*
X1136299Y1259532D01*
Y1227457D01*
X1136708Y1227048D01*
X1137345D01*
X1137795Y1227498D01*
Y1228543D01*
G01X1131629Y1260024D02*
Y1259912D01*
X1131809Y1259732D01*
Y1234625D01*
X1132656Y1233778D01*
X1133604D01*
X1134054Y1233328D01*
Y1232283D01*
G01X1142980Y1259790D02*
X1142868D01*
X1142688Y1259970D01*
X1140969D01*
X1140040Y1259041D01*
Y1234936D01*
X1140448Y1234528D01*
X1141085D01*
X1141535Y1234978D01*
Y1236023D01*
G01X1124149Y1259824D02*
Y1259712D01*
X1124329Y1259532D01*
Y1234625D01*
X1125176Y1233778D01*
X1126124D01*
X1126574Y1233328D01*
Y1232283D01*
G01X1125259Y1259824D02*
Y1259712D01*
X1125079Y1259532D01*
Y1234936D01*
X1125487Y1234528D01*
X1126124D01*
X1126574Y1234978D01*
Y1236023D01*
G01X1135369Y1259824D02*
Y1259712D01*
X1135549Y1259532D01*
Y1227146D01*
X1136397Y1226298D01*
X1137345D01*
X1137795Y1225848D01*
Y1224803D01*
G01X1128999Y1260024D02*
Y1259912D01*
X1128819Y1259732D01*
Y1227456D01*
X1129227Y1227048D01*
X1129864D01*
X1130314Y1227498D01*
Y1228543D01*
G01X1142980Y1260900D02*
X1142923D01*
X1142743Y1260720D01*
X1140658D01*
X1139290Y1259352D01*
Y1234625D01*
X1140137Y1233778D01*
X1141085D01*
X1141535Y1233328D01*
Y1232283D01*
G01X1127889Y1260024D02*
Y1259912D01*
X1128069Y1259732D01*
Y1227145D01*
X1128916Y1226298D01*
X1129864D01*
X1130314Y1225848D01*
Y1224803D01*
G01X1541204Y1259630D02*
Y1259543D01*
X1541024Y1259363D01*
Y1227456D01*
X1541432Y1227048D01*
X1542069D01*
X1542519Y1227498D01*
Y1228543D01*
G01X1540094Y1259630D02*
Y1259543D01*
X1540274Y1259363D01*
Y1227145D01*
X1541121Y1226298D01*
X1542069D01*
X1542519Y1225848D01*
Y1224803D01*
G01X1543834Y1259924D02*
Y1259812D01*
X1544014Y1259632D01*
Y1234625D01*
X1544861Y1233778D01*
X1545809D01*
X1546259Y1233328D01*
Y1232283D01*
G01X1544944Y1259924D02*
Y1259812D01*
X1544764Y1259632D01*
Y1234936D01*
X1545172Y1234528D01*
X1545809D01*
X1546259Y1234978D01*
Y1236023D01*
G01X1548684Y1260024D02*
Y1259912D01*
X1548504Y1259732D01*
Y1227457D01*
X1548913Y1227048D01*
X1549550D01*
X1550000Y1227498D01*
Y1228543D01*
G01X1547574Y1260024D02*
Y1259912D01*
X1547754Y1259732D01*
Y1227146D01*
X1548602Y1226298D01*
X1549550D01*
X1550000Y1225848D01*
Y1224803D01*
G01X1551315Y1260024D02*
Y1259912D01*
X1551495Y1259732D01*
Y1234625D01*
X1552342Y1233778D01*
X1553290D01*
X1553740Y1233328D01*
Y1232283D01*
G01X1552425Y1260024D02*
Y1259912D01*
X1552245Y1259732D01*
Y1234936D01*
X1552653Y1234528D01*
X1553290D01*
X1553740Y1234978D01*
Y1236023D01*
G01X1556165Y1260024D02*
Y1259912D01*
X1555985Y1259732D01*
Y1227456D01*
X1556393Y1227048D01*
X1557030D01*
X1557480Y1227498D01*
Y1228543D01*
G01X1555055Y1260024D02*
Y1259912D01*
X1555235Y1259732D01*
Y1227145D01*
X1556082Y1226298D01*
X1557030D01*
X1557480Y1225848D01*
Y1224803D01*
G01X1559905Y1260024D02*
Y1259912D01*
X1559725Y1259732D01*
Y1234936D01*
X1560133Y1234528D01*
X1560770D01*
X1561220Y1234978D01*
Y1236023D01*
G01X1558795Y1260024D02*
Y1259912D01*
X1558975Y1259732D01*
Y1234625D01*
X1559822Y1233778D01*
X1560770D01*
X1561220Y1233328D01*
Y1232283D01*
G01X1562535Y1260024D02*
Y1259912D01*
X1562715Y1259732D01*
Y1227145D01*
X1563562Y1226298D01*
X1564510D01*
X1564960Y1225848D01*
Y1224803D01*
G01X1563645Y1260024D02*
Y1259912D01*
X1563465Y1259732D01*
Y1227456D01*
X1563873Y1227048D01*
X1564510D01*
X1564960Y1227498D01*
Y1228543D01*
G01X1566275Y1260024D02*
Y1259912D01*
X1566455Y1259732D01*
Y1234625D01*
X1567302Y1233778D01*
X1568250D01*
X1568700Y1233328D01*
Y1232283D01*
G01X1567385Y1260024D02*
Y1259912D01*
X1567205Y1259732D01*
Y1234936D01*
X1567613Y1234528D01*
X1568250D01*
X1568700Y1234978D01*
Y1236023D01*
G01X1632283Y1224803D02*
Y1225848D01*
X1631833Y1226298D01*
X1630940D01*
X1630038Y1227200D01*
Y1259732D01*
X1629858Y1259912D01*
Y1260024D01*
G01X1630968D02*
Y1259912D01*
X1630788Y1259732D01*
Y1227511D01*
X1631251Y1227048D01*
X1631833D01*
X1632283Y1227498D01*
Y1228543D01*
G01X1634708Y1260024D02*
Y1259912D01*
X1634528Y1259732D01*
Y1234936D01*
X1634936Y1234528D01*
X1635573D01*
X1636023Y1234978D01*
Y1236023D01*
G01X1633598Y1260024D02*
Y1259912D01*
X1633778Y1259732D01*
Y1234625D01*
X1634625Y1233778D01*
X1635573D01*
X1636023Y1233328D01*
Y1232283D01*
G01X1637338Y1260024D02*
Y1259912D01*
X1637518Y1259732D01*
Y1227145D01*
X1638365Y1226298D01*
X1639313D01*
X1639763Y1225848D01*
Y1224803D01*
G01X1641079Y1260024D02*
Y1259912D01*
X1641259Y1259732D01*
Y1234625D01*
X1642106Y1233778D01*
X1643054D01*
X1643504Y1233328D01*
Y1232283D01*
G01X1642189Y1260024D02*
Y1259912D01*
X1642009Y1259732D01*
Y1234936D01*
X1642417Y1234528D01*
X1643054D01*
X1643504Y1234978D01*
Y1236023D01*
G01X1638448Y1260024D02*
Y1259912D01*
X1638268Y1259732D01*
Y1227456D01*
X1638676Y1227048D01*
X1639313D01*
X1639763Y1227498D01*
Y1228543D01*
G01X1645929Y1260024D02*
Y1259912D01*
X1645749Y1259732D01*
Y1227456D01*
X1646157Y1227048D01*
X1646794D01*
X1647244Y1227498D01*
Y1228543D01*
G01X1644819Y1260024D02*
Y1259912D01*
X1644999Y1259732D01*
Y1227145D01*
X1645846Y1226298D01*
X1646794D01*
X1647244Y1225848D01*
Y1224803D01*
G01X1648559Y1260024D02*
Y1259912D01*
X1648739Y1259732D01*
Y1234625D01*
X1649586Y1233778D01*
X1650534D01*
X1650984Y1233328D01*
Y1232283D01*
G01X1649669Y1260024D02*
Y1259912D01*
X1649489Y1259732D01*
Y1234936D01*
X1649897Y1234528D01*
X1650534D01*
X1650984Y1234978D01*
Y1236023D01*
G01X1653409Y1260024D02*
Y1259912D01*
X1653229Y1259732D01*
Y1227456D01*
X1653637Y1227048D01*
X1654274D01*
X1654724Y1227498D01*
Y1228543D01*
G01X1652299Y1260024D02*
Y1259912D01*
X1652479Y1259732D01*
Y1227145D01*
X1653326Y1226298D01*
X1654274D01*
X1654724Y1225848D01*
Y1224803D01*
G01X1656039Y1260024D02*
Y1259912D01*
X1656219Y1259732D01*
Y1234625D01*
X1657066Y1233778D01*
X1658014D01*
X1658464Y1233328D01*
Y1232283D01*
G01X1657149Y1260024D02*
Y1259912D01*
X1656969Y1259732D01*
Y1234936D01*
X1657377Y1234528D01*
X1658014D01*
X1658464Y1234978D01*
Y1236023D01*
G54D25*
X895384Y228740D03*
Y276772D03*
X923336Y226772D03*
G54D16*
X73872Y1348187D03*
X81752D03*
X73872Y1360099D03*
X81752D03*
X73872Y1384297D03*
Y1372385D03*
X81752Y1384297D03*
Y1372385D03*
X86112Y1348187D03*
X98352D03*
X93992D03*
X86112Y1360099D03*
X98352D03*
X93992D03*
X86112Y1384297D03*
Y1372385D03*
X98352Y1384297D03*
Y1372385D03*
X93992D03*
Y1384297D03*
X86112Y1396583D03*
X93992D03*
X98352D03*
X86112Y1408495D03*
X93992D03*
X98352D03*
X110592Y1348187D03*
X106232D03*
X110592Y1360099D03*
X106232D03*
X110592Y1384297D03*
X106232D03*
Y1372385D03*
X110592D03*
Y1396583D03*
X106232D03*
X110592Y1408495D03*
X106232D03*
X118472Y1348187D03*
X122832D03*
X130712D03*
X118472Y1360099D03*
X122832D03*
X130712D03*
X118472Y1384297D03*
Y1372385D03*
X122832Y1384297D03*
Y1372385D03*
X130712Y1384297D03*
Y1372385D03*
X118472Y1396583D03*
X122832D03*
X130712D03*
X118472Y1408495D03*
X122832D03*
X130712D03*
X146948Y1136909D03*
X143208D03*
X135072Y1348187D03*
X142952D03*
X147312D03*
X135072Y1360099D03*
X147312D03*
X142952D03*
X135072Y1384297D03*
Y1372385D03*
X147312Y1384297D03*
Y1372385D03*
X142952Y1384297D03*
Y1372385D03*
X135072Y1396583D03*
X147312D03*
X142952D03*
X135072Y1408495D03*
X147312D03*
X142952D03*
X150689Y1133169D03*
X165649D03*
X161909D03*
X154429D03*
X159552Y1348187D03*
X155192D03*
X159552Y1360099D03*
X155192D03*
X159552Y1372385D03*
Y1384297D03*
X155192D03*
Y1372385D03*
X159552Y1396583D03*
X155192D03*
X159552Y1408495D03*
X155192D03*
X173129Y1136909D03*
X169389D03*
X178740Y1228543D03*
X171259Y1224803D03*
X182480Y1236023D03*
Y1232283D03*
X174999D03*
X171259Y1228543D03*
X178740Y1224803D03*
X174999Y1236023D03*
X167432Y1348187D03*
X171792D03*
X179672D03*
X167432Y1360099D03*
X171792D03*
X179672D03*
X167432Y1384297D03*
Y1372385D03*
X171792Y1384297D03*
Y1372385D03*
X179672Y1384297D03*
Y1372385D03*
X171792Y1396583D03*
X179672D03*
X167432D03*
Y1408495D03*
X171792D03*
X179672D03*
X195570Y1148129D03*
Y1155610D03*
X184350Y1151870D03*
X188090Y1148129D03*
X195570Y1166830D03*
Y1181791D03*
Y1174310D03*
X197440Y1236023D03*
X186220Y1224803D03*
X193700Y1228543D03*
X197440Y1232283D03*
X189960Y1236023D03*
X186220Y1228543D03*
X193700Y1224803D03*
X189960Y1232283D03*
X184032Y1348187D03*
X191912D03*
X184032Y1360099D03*
X196272D03*
X191912D03*
X184032Y1384297D03*
Y1372385D03*
X196272Y1384297D03*
Y1372385D03*
X191912Y1384297D03*
Y1372385D03*
X184032Y1396583D03*
X191912D03*
X196272D03*
X184032Y1408495D03*
X191912D03*
X196272D03*
X210531Y1155610D03*
X203051D03*
X214271Y1170570D03*
X210531Y1166830D03*
X214271Y1159350D03*
X206791Y1170570D03*
X203051Y1166830D03*
X199311Y1170570D03*
X206791Y1159350D03*
X199311D03*
X203051Y1174310D03*
X210531D03*
X204921Y1232283D03*
X201181Y1224803D03*
X212401Y1232283D03*
X208661Y1228543D03*
X212401Y1236023D03*
X208661Y1224803D03*
X201181Y1228543D03*
X204921Y1236023D03*
X204152Y1360099D03*
Y1384297D03*
Y1372385D03*
Y1396583D03*
X213969Y1445013D03*
Y1453293D03*
Y1456013D03*
Y1464293D03*
X218011Y1155610D03*
X225492D03*
Y1166830D03*
X221751Y1170570D03*
X218011Y1166830D03*
X221751Y1159350D03*
X229232Y1170570D03*
Y1159350D03*
X225492Y1174310D03*
X218011D03*
X219881Y1232283D03*
Y1236023D03*
X216141Y1224803D03*
X223622D03*
X227362Y1232283D03*
X223622Y1228543D03*
X216141D03*
X227362Y1236023D03*
X236712Y1155610D03*
X244192D03*
X236712Y1166830D03*
X240452Y1170570D03*
Y1159350D03*
X244192Y1166830D03*
X236712Y1174310D03*
X244192D03*
X251673Y1155610D03*
X259153D03*
X251673Y1166830D03*
X255413Y1170570D03*
X247933D03*
X255413Y1159350D03*
X247933D03*
X259153Y1166830D03*
X251673Y1174310D03*
X259153D03*
X266633Y1155610D03*
Y1174310D03*
X600295Y1084547D03*
Y1092027D03*
X604035Y1077066D03*
Y1080806D03*
Y1084547D03*
Y1092027D03*
Y1103247D03*
X600295D03*
Y1095767D03*
X604035D03*
X600295Y1110728D03*
Y1118208D03*
X604035Y1110728D03*
Y1118208D03*
X600295Y1125688D03*
X604035D03*
X611516Y1073326D03*
X618996D03*
Y1088287D03*
Y1092027D03*
X607775Y1077066D03*
X611516D03*
X615256Y1080807D03*
X607776D03*
X615256Y1084547D03*
X607776D03*
X615256Y1088287D03*
X611516D03*
X607776D03*
X611516Y1092027D03*
X618996Y1077066D03*
X611516Y1106988D03*
X607776D03*
X611516Y1095767D03*
X615256Y1099507D03*
X607776D03*
X615256Y1103247D03*
X607776D03*
X615256Y1106988D03*
X618996Y1095767D03*
Y1106988D03*
X615256Y1110728D03*
Y1114468D03*
X611516D03*
X607776D03*
X615256Y1118208D03*
Y1121948D03*
X611516D03*
X607776D03*
X618996Y1114468D03*
X615256Y1125688D03*
Y1129429D03*
X611516D03*
X607776D03*
X618996Y1125688D03*
Y1129429D03*
X626476Y1073326D03*
X635827Y1075196D03*
X628346D03*
X632085Y1071455D03*
X626476Y1077066D03*
Y1088287D03*
Y1092027D03*
X622736Y1080807D03*
Y1084547D03*
Y1088287D03*
X635827Y1090157D03*
X628346Y1078936D03*
Y1090157D03*
X635827Y1078936D03*
X632086Y1090157D03*
Y1082677D03*
Y1086417D03*
X630216Y1099507D03*
X622736D03*
Y1103247D03*
X626476Y1106988D03*
X622736D03*
X626476Y1095767D03*
Y1099507D03*
X630216Y1103247D03*
X635827Y1093897D03*
X632086Y1101377D03*
Y1105117D03*
X628346Y1097637D03*
Y1093897D03*
X635827Y1097637D03*
X633957Y1110728D03*
X630216D03*
X626476D03*
X622736Y1114468D03*
X630216Y1118208D03*
X626476D03*
Y1121948D03*
X633957Y1114468D03*
Y1118208D03*
Y1121948D03*
X635827Y1108858D03*
X632086D03*
X633957Y1125688D03*
Y1129429D03*
X630216Y1129428D03*
X626476D03*
X622736Y1129429D03*
X628346Y1224803D03*
Y1228543D03*
X635827D03*
X632086Y1232283D03*
Y1236023D03*
X635827Y1224803D03*
X636288Y1372385D03*
Y1384297D03*
X631928Y1396583D03*
X636288D03*
X624048D03*
X631928Y1408495D03*
X636288D03*
X624048D03*
X643307Y1075196D03*
X647046Y1071455D03*
X639566D03*
X643307Y1090157D03*
X639567D03*
X647047Y1082677D03*
Y1086417D03*
X643307Y1078936D03*
X647047Y1090157D03*
X639567Y1086417D03*
Y1082677D03*
Y1101377D03*
Y1105117D03*
X647047D03*
Y1101377D03*
X643307Y1097637D03*
Y1093897D03*
X637697Y1114468D03*
X648917Y1118208D03*
X645177D03*
X641437D03*
X637697D03*
X648917Y1121948D03*
X645177D03*
X641437D03*
X637697D03*
Y1110728D03*
X647047Y1108858D03*
X643307D03*
X639567D03*
X648917Y1125688D03*
X645177D03*
X641437D03*
X637697D03*
X645177Y1129429D03*
X641437D03*
X637697D03*
X652657Y1148129D03*
Y1155610D03*
X648917Y1144389D03*
Y1151869D03*
Y1159350D03*
Y1170570D03*
X652657Y1166830D03*
X648917Y1185531D03*
Y1178051D03*
X652657Y1181791D03*
Y1174310D03*
X639567Y1236023D03*
X647047D03*
X639567Y1232283D03*
X643307Y1224803D03*
X647047Y1232283D03*
X643307Y1228543D03*
X650787D03*
Y1224803D03*
X648528Y1348187D03*
Y1360099D03*
X644168Y1384297D03*
Y1372385D03*
X648528D03*
Y1384297D03*
X644168Y1396583D03*
X648528D03*
X644168Y1408495D03*
X648528D03*
X660138Y1155610D03*
X667618D03*
X663878Y1170570D03*
X660138Y1166830D03*
X656398Y1170570D03*
X663878Y1159350D03*
X656398D03*
X667618Y1166830D03*
Y1174310D03*
X660138D03*
X663878Y1193011D03*
X660138D03*
X656398D03*
X667618D03*
X654527Y1236023D03*
Y1232283D03*
X660768Y1348187D03*
X668648D03*
X656408D03*
X660768Y1360099D03*
X668648D03*
X656408D03*
Y1384297D03*
Y1372385D03*
X668648D03*
X660768D03*
X668648Y1384297D03*
X660768D03*
X668648Y1396583D03*
X656408D03*
X660768D03*
X668648Y1408495D03*
X656408D03*
X660768D03*
X682579Y1155610D03*
X675098D03*
X682579Y1166830D03*
X678838Y1170570D03*
X671358D03*
X675098Y1166830D03*
X671358Y1159350D03*
X678838D03*
X682579Y1174310D03*
X675098D03*
X682579Y1193011D03*
X678838D03*
X675098D03*
X671358D03*
X680888Y1348187D03*
X673008D03*
X685248D03*
X680888Y1360099D03*
X673008D03*
X685248D03*
Y1372385D03*
Y1384297D03*
X673008Y1372385D03*
Y1384297D03*
X680888Y1372385D03*
Y1384297D03*
Y1396583D03*
X685248D03*
X673008D03*
X680888Y1408495D03*
X685248D03*
X673008D03*
X701279Y1155610D03*
X693799D03*
Y1166830D03*
X697539Y1170570D03*
Y1159350D03*
X701279Y1166830D03*
X686319Y1170570D03*
Y1159350D03*
X701279Y1174310D03*
X693799D03*
X701279Y1193011D03*
X697539D03*
X693799D03*
X686319D03*
X693128Y1348187D03*
X697488D03*
X693128Y1360099D03*
X697488D03*
Y1384297D03*
Y1372385D03*
X693128D03*
Y1384297D03*
Y1396583D03*
X697488D03*
X693128Y1408495D03*
X697488D03*
X708760Y1155610D03*
X716240D03*
Y1166830D03*
X705020Y1159350D03*
X712500D03*
X705020Y1170570D03*
X712500D03*
X708760Y1166830D03*
X716240Y1174310D03*
X708760D03*
Y1193011D03*
X712500D03*
X705020D03*
X716240D03*
X718110Y1228543D03*
Y1224803D03*
X705368Y1348187D03*
X717608D03*
X709728D03*
X705368Y1360099D03*
X717608D03*
X709728D03*
Y1384297D03*
Y1372385D03*
X705368D03*
Y1384297D03*
X717608Y1372385D03*
Y1384297D03*
Y1396583D03*
X705368D03*
X709728D03*
X717608Y1408495D03*
X705368D03*
X709728D03*
X723720Y1155610D03*
X734941D03*
Y1159350D03*
Y1166830D03*
Y1170570D03*
X723720Y1174310D03*
X734941D03*
X719980Y1193011D03*
X723720D03*
X725590Y1228543D03*
X733071D03*
X721850Y1236023D03*
X733071Y1224803D03*
X721850Y1232283D03*
X725590Y1224803D03*
X729331Y1236023D03*
Y1232283D03*
X734208Y1348187D03*
X729848D03*
X721968D03*
X734208Y1360099D03*
X729848D03*
X721968D03*
X729848Y1372385D03*
Y1384297D03*
X721968D03*
Y1372385D03*
X734208D03*
Y1384297D03*
X729848Y1396489D03*
X721968D03*
X734208D03*
X729848Y1408401D03*
X721968D03*
X734208D03*
X744291Y1236023D03*
X736811Y1232283D03*
X744291D03*
X736811Y1236023D03*
X740551Y1224803D03*
Y1228543D03*
X746448Y1348187D03*
X742088D03*
X746448Y1360099D03*
X742088D03*
Y1384297D03*
Y1372385D03*
X746448D03*
Y1384297D03*
X742088Y1396489D03*
Y1408401D03*
X764862Y1166830D03*
X761122D03*
Y1159350D03*
X759252Y1228543D03*
X755512Y1232283D03*
Y1236023D03*
X766732Y1228543D03*
X762992Y1232283D03*
Y1236023D03*
X751772Y1228543D03*
X755512Y1250984D03*
Y1254724D03*
X759252Y1247243D03*
Y1243503D03*
X762992Y1250984D03*
Y1254724D03*
X766732Y1247243D03*
Y1243503D03*
X755512Y1239763D03*
X759252D03*
X762992D03*
X766732D03*
X751772Y1247243D03*
Y1243503D03*
Y1239763D03*
X766732Y1258465D03*
X759252D03*
X751772D03*
X766568Y1348187D03*
X758688D03*
X754328D03*
X766568Y1360099D03*
X758688D03*
X754328D03*
Y1372385D03*
Y1384297D03*
X758688Y1372385D03*
X766568D03*
X758688Y1384297D03*
X766568D03*
X774212Y1228543D03*
X770472Y1236023D03*
Y1232283D03*
X781693D03*
X777953D03*
Y1236023D03*
X781693D03*
X770472Y1250984D03*
Y1254724D03*
X781693Y1250984D03*
X777953D03*
X774212Y1247243D03*
Y1243503D03*
X777953D03*
X781693D03*
X770472Y1239763D03*
X774212D03*
X777953Y1254724D03*
X774212Y1258465D03*
X778808Y1348187D03*
X770928D03*
X778808Y1360099D03*
X770928D03*
X785434Y1228543D03*
Y1247243D03*
Y1239762D03*
X1057381Y1092027D03*
Y1084547D03*
Y1095767D03*
Y1103247D03*
Y1110728D03*
X1059251Y1202362D03*
Y1209842D03*
Y1217322D03*
X1055510Y1221063D03*
Y1213583D03*
Y1206103D03*
X1059251Y1232283D03*
Y1236023D03*
Y1224803D03*
X1055510Y1228542D03*
X1059251Y1243503D03*
Y1250984D03*
X1055509Y1239762D03*
Y1247242D03*
X1052473Y1348187D03*
Y1360099D03*
Y1384297D03*
Y1372385D03*
X1068602Y1073326D03*
X1072342Y1088287D03*
Y1084547D03*
Y1080807D03*
X1064861Y1077066D03*
X1061121Y1092027D03*
X1068602D03*
X1064862Y1088287D03*
X1068602D03*
X1061121Y1084547D03*
X1064862D03*
Y1080807D03*
X1061121Y1080806D03*
Y1077066D03*
X1068602D03*
X1072342Y1099507D03*
Y1106988D03*
Y1103247D03*
X1061121Y1095767D03*
X1068602D03*
X1064862Y1106988D03*
X1068602D03*
X1061121Y1103247D03*
X1064862D03*
Y1099507D03*
X1072342Y1121948D03*
Y1118208D03*
Y1114468D03*
Y1110728D03*
X1064862Y1114468D03*
X1068602D03*
X1061121Y1110728D03*
X1074212Y1202362D03*
X1062991D03*
X1074212Y1206102D03*
X1066732D03*
X1070472D03*
X1074212Y1217322D03*
Y1209842D03*
Y1213582D03*
X1070472D03*
X1066732D03*
X1062991Y1209842D03*
Y1217322D03*
X1074212Y1221062D03*
X1066732D03*
X1070472D03*
Y1236023D03*
Y1232283D03*
X1066732Y1228543D03*
Y1224803D03*
X1074212D03*
Y1228543D03*
X1062991Y1236023D03*
Y1232283D03*
Y1224803D03*
X1070472Y1250984D03*
Y1254724D03*
X1066732Y1247243D03*
X1074212D03*
X1066732Y1239763D03*
Y1243503D03*
X1070472Y1239763D03*
X1074212D03*
Y1243503D03*
X1062991Y1250984D03*
Y1254724D03*
Y1243503D03*
X1074212Y1258465D03*
X1066732D03*
X1072593Y1348187D03*
X1064713D03*
X1060353D03*
X1072593Y1360099D03*
X1064713D03*
X1060353D03*
X1072593Y1384297D03*
Y1372385D03*
X1064713D03*
Y1384297D03*
X1060353D03*
Y1372385D03*
X1072593Y1396583D03*
X1064713D03*
X1072593Y1408495D03*
X1064713D03*
X1083562Y1073326D03*
X1076082D03*
X1083562Y1092027D03*
Y1088287D03*
Y1077066D03*
X1079822Y1088287D03*
Y1084547D03*
Y1080807D03*
X1076082Y1092027D03*
Y1088287D03*
Y1077066D03*
X1089172Y1082677D03*
Y1086417D03*
Y1090157D03*
X1083562Y1099507D03*
Y1095767D03*
X1087302Y1106988D03*
X1079822D03*
X1083562D03*
X1079822Y1103247D03*
Y1099507D03*
X1076082Y1106988D03*
Y1095767D03*
X1089172Y1101377D03*
Y1105117D03*
X1083562Y1121948D03*
Y1118208D03*
X1087302D03*
X1079822Y1114468D03*
X1083562Y1110728D03*
X1087302D03*
X1091043D03*
Y1121948D03*
Y1118208D03*
Y1114468D03*
X1076082D03*
X1089172Y1108858D03*
X1091043Y1125688D03*
X1079822Y1129429D03*
X1083562Y1129428D03*
X1087302D03*
X1091043Y1133169D03*
Y1129429D03*
X1076082Y1125688D03*
X1085432Y1202362D03*
X1089172D03*
X1077952Y1206102D03*
Y1213582D03*
X1081692Y1206102D03*
Y1213582D03*
X1085432Y1209842D03*
X1089172D03*
X1077952Y1221062D03*
X1089172Y1217322D03*
X1085432D03*
X1089172Y1232283D03*
Y1236023D03*
X1085432Y1224803D03*
Y1228543D03*
X1089193Y1348187D03*
X1084833D03*
X1076953D03*
X1089193Y1360099D03*
X1084833D03*
X1076953D03*
X1089193Y1384297D03*
Y1372385D03*
X1084833Y1384297D03*
Y1372385D03*
X1076953Y1384297D03*
Y1372385D03*
X1089193Y1396583D03*
X1084833D03*
X1076953D03*
X1089193Y1408495D03*
X1084833D03*
X1076953D03*
X1092913Y1075196D03*
Y1078936D03*
Y1090157D03*
X1096653Y1082677D03*
Y1086417D03*
Y1090157D03*
X1092913Y1093897D03*
Y1097637D03*
X1096653Y1101377D03*
Y1105117D03*
X1094783Y1110728D03*
Y1121948D03*
X1098523D03*
X1094783Y1118208D03*
X1098523D03*
X1094783Y1114468D03*
X1096653Y1108858D03*
X1092913D03*
X1094783Y1133169D03*
X1098523D03*
X1094783Y1129429D03*
X1098523D03*
X1094783Y1125688D03*
X1098523D03*
X1106003Y1136909D03*
X1098523Y1151870D03*
X1102263Y1148129D03*
X1098523Y1159350D03*
Y1170570D03*
Y1178051D03*
X1102263Y1181791D03*
X1106003Y1200491D03*
Y1204232D03*
X1102263D03*
X1098523D03*
Y1200491D03*
X1102263D03*
X1092913Y1202362D03*
X1098523Y1207972D03*
X1102263D03*
X1106003D03*
Y1211712D03*
X1102263D03*
X1098523D03*
X1092913Y1206102D03*
Y1209842D03*
Y1213582D03*
Y1217322D03*
X1100393Y1228543D03*
X1104133Y1236023D03*
X1092913Y1224803D03*
X1104133Y1232283D03*
X1107873Y1224803D03*
X1096653Y1236023D03*
X1100393Y1224803D03*
X1107873Y1228543D03*
X1096653Y1232283D03*
X1092913Y1228543D03*
X1101433Y1348187D03*
X1097073D03*
X1101433Y1360099D03*
X1097073D03*
X1101433Y1384297D03*
Y1372385D03*
X1097073D03*
Y1384297D03*
X1101433Y1396583D03*
X1097073D03*
X1101433Y1408495D03*
X1097073D03*
X1124704Y1155610D03*
X1109743D03*
Y1148129D03*
X1117224Y1155610D03*
X1113484Y1159350D03*
X1120964D03*
X1109743Y1166830D03*
X1113484Y1170570D03*
X1117224Y1166830D03*
X1120964Y1170570D03*
X1124704Y1166830D03*
X1109743Y1174310D03*
Y1181791D03*
X1117224Y1174310D03*
X1124704D03*
X1122834Y1224803D03*
X1119094Y1232283D03*
X1115354Y1228543D03*
X1111613Y1232283D03*
X1119094Y1236023D03*
X1115354Y1224803D03*
X1111613Y1236023D03*
X1122834Y1228543D03*
X1113673Y1348187D03*
X1121553D03*
X1109313D03*
X1113673Y1360099D03*
X1121553D03*
X1109313D03*
X1113673Y1372385D03*
Y1384297D03*
X1121553Y1372385D03*
Y1384297D03*
X1109313D03*
Y1372385D03*
X1113673Y1396583D03*
X1121553D03*
X1109313D03*
X1113673Y1408495D03*
X1121553D03*
X1109313D03*
X1139665Y1155610D03*
X1132184D03*
X1139665Y1166830D03*
X1135924Y1170570D03*
X1128444D03*
X1132184Y1166830D03*
X1128444Y1159350D03*
X1135924D03*
X1139665Y1174310D03*
X1132184D03*
X1134054Y1236023D03*
X1137795Y1228543D03*
X1134054Y1232283D03*
X1126574D03*
Y1236023D03*
X1137795Y1224803D03*
X1130314Y1228543D03*
Y1224803D03*
X1138153Y1348187D03*
X1133793D03*
X1125913D03*
X1138153Y1360099D03*
X1133793D03*
X1125913D03*
X1138153Y1384297D03*
Y1372385D03*
X1133793Y1384297D03*
Y1372385D03*
X1125913Y1384297D03*
Y1372385D03*
X1138153Y1396583D03*
X1133793D03*
X1125913D03*
X1138153Y1408495D03*
X1133793D03*
X1125913D03*
X1150885Y1155610D03*
X1143405Y1170570D03*
X1154625Y1159350D03*
X1143405D03*
X1150885Y1166830D03*
X1154625Y1170570D03*
X1150885Y1174310D03*
X1141535Y1236023D03*
Y1232283D03*
X1150393Y1348187D03*
X1146033D03*
X1150393Y1360099D03*
X1146033D03*
X1150393Y1384297D03*
Y1372385D03*
X1146033D03*
Y1384297D03*
X1150393Y1396583D03*
X1146033D03*
X1150393Y1408495D03*
X1146033D03*
X1173326Y1155610D03*
X1165846D03*
X1158365D03*
X1173326Y1166830D03*
X1165846D03*
X1169586Y1170570D03*
X1158365Y1166830D03*
X1162106Y1170570D03*
X1169586Y1159350D03*
X1162106D03*
X1165846Y1174310D03*
X1158365D03*
X1173326D03*
X1162633Y1348187D03*
X1170513D03*
X1158273D03*
X1162633Y1360099D03*
X1170513D03*
X1158273D03*
X1162633Y1372385D03*
Y1384297D03*
X1170513Y1372385D03*
Y1384297D03*
X1158273D03*
Y1372385D03*
X1162633Y1396583D03*
X1170513D03*
X1158273D03*
X1162633Y1408495D03*
X1170513D03*
X1158273D03*
X1180806Y1155610D03*
Y1174310D03*
X1182753Y1348187D03*
X1174873D03*
X1182753Y1360099D03*
X1174873D03*
X1182753Y1384297D03*
Y1372385D03*
X1174873Y1384297D03*
Y1372385D03*
X1182753Y1396583D03*
X1174873D03*
X1182753Y1408495D03*
X1174873D03*
X1514468Y1084547D03*
Y1092027D03*
Y1095767D03*
Y1103247D03*
Y1110728D03*
Y1118208D03*
Y1125688D03*
X1525689Y1073326D03*
X1521948Y1077066D03*
X1525689D03*
X1518208D03*
Y1080806D03*
X1529429Y1080807D03*
X1521949D03*
X1529429Y1084547D03*
X1521949D03*
X1518208D03*
X1529429Y1088287D03*
X1525689D03*
X1521949D03*
X1525689Y1092027D03*
X1518208D03*
X1521949Y1103247D03*
X1518208D03*
X1529429Y1106988D03*
X1525689D03*
X1521949D03*
X1525689Y1095767D03*
X1518208D03*
X1529429Y1099507D03*
X1521949D03*
X1529429Y1103247D03*
Y1110728D03*
X1518208D03*
X1529429Y1114468D03*
X1525689D03*
X1521949D03*
X1529429Y1118208D03*
X1518208D03*
X1529429Y1121948D03*
X1525689D03*
X1521949D03*
X1529429Y1125688D03*
X1518208D03*
X1529429Y1129429D03*
X1525689D03*
X1521949D03*
X1533169Y1073326D03*
X1540649D03*
X1546258Y1071455D03*
X1540649Y1088287D03*
X1533169Y1077066D03*
X1536909Y1080807D03*
Y1084547D03*
Y1088287D03*
X1533169D03*
Y1092027D03*
X1540649Y1077066D03*
Y1092027D03*
X1546259Y1082677D03*
Y1086417D03*
Y1090157D03*
X1544389Y1099507D03*
X1533169Y1095767D03*
X1536909Y1099507D03*
Y1103247D03*
X1540649Y1106988D03*
X1536909D03*
X1533169D03*
X1544389D03*
X1540649Y1095767D03*
Y1099507D03*
X1546259Y1101377D03*
Y1105117D03*
X1544389Y1118208D03*
X1540649D03*
Y1121948D03*
X1544389Y1110728D03*
X1540649D03*
X1536909Y1114468D03*
X1533169D03*
Y1125688D03*
X1544389Y1129428D03*
X1540649D03*
X1536909Y1129429D03*
X1533169D03*
X1546259Y1232283D03*
X1542519Y1228543D03*
X1546259Y1236023D03*
X1542519Y1224803D03*
X1557480Y1075196D03*
X1550000D03*
X1561219Y1071455D03*
X1553739D03*
X1561220Y1086417D03*
Y1090157D03*
Y1082677D03*
X1557480Y1078936D03*
Y1090157D03*
X1553740Y1082677D03*
Y1086417D03*
Y1090157D03*
X1550000Y1078936D03*
Y1090157D03*
X1561220Y1105117D03*
X1553740D03*
X1561220Y1101377D03*
X1557480Y1097637D03*
Y1093897D03*
X1553740Y1101377D03*
X1550000Y1093897D03*
Y1097637D03*
X1551870Y1114468D03*
X1548130D03*
X1563090Y1118208D03*
X1559350D03*
X1555610D03*
X1551870D03*
X1548130D03*
X1563090Y1121948D03*
X1559350D03*
X1555610D03*
X1551870D03*
X1548130D03*
Y1110728D03*
X1561220Y1108858D03*
X1557480D03*
X1553740D03*
X1550000D03*
X1551870Y1110728D03*
X1563090Y1125688D03*
X1559350D03*
X1555610D03*
X1551870D03*
X1548130D03*
X1559350Y1129429D03*
X1555610D03*
X1551870D03*
X1548130D03*
X1563090Y1144389D03*
Y1151869D03*
Y1159350D03*
Y1170570D03*
Y1185531D03*
Y1178051D03*
X1553740Y1232283D03*
X1550000Y1228543D03*
X1553740Y1236023D03*
X1550000Y1224803D03*
X1557480Y1228543D03*
X1561220Y1236023D03*
Y1232283D03*
X1557480Y1224803D03*
X1574311Y1129429D03*
X1570571D03*
X1578051D03*
X1574311Y1155610D03*
X1566830Y1148129D03*
Y1155610D03*
X1578051Y1170570D03*
X1574311Y1166830D03*
X1570571Y1170570D03*
X1566830Y1166830D03*
X1578051Y1159350D03*
X1570571D03*
X1574311Y1174310D03*
X1566830Y1181791D03*
Y1174310D03*
X1570571Y1200491D03*
X1578051D03*
X1574311D03*
X1568700Y1236023D03*
X1564960Y1224803D03*
Y1228543D03*
X1568700Y1232283D03*
X1589271Y1129429D03*
X1585531D03*
X1581791D03*
X1593011D03*
X1581791Y1155610D03*
X1589271D03*
X1593011Y1170570D03*
X1585531D03*
X1589271Y1166830D03*
X1581791D03*
X1585531Y1159350D03*
X1593011D03*
X1589271Y1174310D03*
X1581791D03*
X1589271Y1200491D03*
X1585531D03*
X1581791D03*
X1593011D03*
X1611712Y1129429D03*
X1607972D03*
X1600492D03*
X1596752D03*
Y1155610D03*
X1607972D03*
Y1166830D03*
X1611712Y1170570D03*
X1600492D03*
X1596752Y1166830D03*
X1611712Y1159350D03*
X1600492D03*
X1607972Y1174310D03*
X1596752D03*
X1600492Y1200491D03*
X1596752D03*
X1611712D03*
X1607972D03*
X1626673Y1129429D03*
X1622933D03*
X1619193D03*
X1615452D03*
X1622933Y1155610D03*
X1615452D03*
Y1166830D03*
X1619193Y1170570D03*
X1626673Y1159350D03*
X1619193D03*
X1622933Y1166830D03*
X1626673Y1170570D03*
X1622933Y1174310D03*
X1615452D03*
X1622933Y1200491D03*
X1619193D03*
X1615452D03*
X1626673D03*
X1621398Y1348187D03*
Y1360099D03*
X1617038Y1384297D03*
Y1372385D03*
X1621398D03*
Y1384297D03*
Y1396583D03*
Y1408495D03*
X1630413Y1129429D03*
X1637893D03*
X1634153D03*
X1637893Y1155610D03*
X1630413D03*
Y1166830D03*
X1637893Y1174310D03*
X1630413D03*
Y1200491D03*
X1637893D03*
X1634153D03*
X1632283Y1228543D03*
X1639763Y1224803D03*
X1636023Y1236023D03*
X1643504Y1232283D03*
X1632283Y1224803D03*
X1643504Y1236023D03*
X1636023Y1232283D03*
X1639763Y1228543D03*
X1629278Y1348187D03*
X1641518D03*
X1633638D03*
X1629278Y1360099D03*
X1641518D03*
X1633638D03*
X1629278Y1384297D03*
Y1372385D03*
X1641518Y1384297D03*
Y1372385D03*
X1633638Y1384297D03*
Y1372385D03*
X1629278Y1396583D03*
X1641518D03*
X1633638D03*
Y1408495D03*
X1629278D03*
X1641518D03*
X1656594Y1155610D03*
Y1170570D03*
Y1166830D03*
Y1159350D03*
Y1174310D03*
X1654724Y1228543D03*
X1647244D03*
X1658464Y1232283D03*
X1654724Y1224803D03*
X1658464Y1236023D03*
X1650984D03*
X1647244Y1224803D03*
X1650984Y1232283D03*
X1645878Y1348187D03*
X1653758D03*
X1658118D03*
X1645878Y1360099D03*
X1653758D03*
X1658118D03*
X1645878Y1384297D03*
Y1372385D03*
X1653758D03*
Y1384297D03*
X1658118D03*
Y1372385D03*
X1645878Y1396583D03*
X1653758D03*
X1658118D03*
X1645878Y1408495D03*
X1653758D03*
X1658118D03*
X1673425Y1228543D03*
X1669685Y1232283D03*
Y1236023D03*
X1665945Y1228543D03*
Y1247243D03*
Y1243503D03*
Y1239763D03*
X1669685Y1250984D03*
Y1254724D03*
X1673425Y1247243D03*
Y1243503D03*
X1669685Y1239763D03*
X1673425D03*
Y1258465D03*
X1665945D03*
X1665998Y1348187D03*
X1670358D03*
X1665998Y1360099D03*
X1670358D03*
X1665998Y1384297D03*
Y1372385D03*
X1670358D03*
Y1384297D03*
X1665998Y1396583D03*
X1670358D03*
X1665998Y1408495D03*
X1670358D03*
X1688385Y1228543D03*
X1684645Y1236023D03*
Y1232283D03*
X1692126D03*
Y1236023D03*
X1680905Y1228543D03*
X1677165Y1232283D03*
Y1236023D03*
X1684645Y1250984D03*
Y1254724D03*
X1692126Y1250984D03*
X1688385Y1247243D03*
Y1243503D03*
X1692126D03*
X1684645Y1239763D03*
X1688385D03*
X1692126Y1254724D03*
X1677165Y1250984D03*
Y1254724D03*
X1680905Y1247243D03*
Y1243503D03*
X1677165Y1239763D03*
X1680905D03*
X1688385Y1258465D03*
X1680905D03*
X1678238Y1348187D03*
X1690478D03*
X1682598D03*
X1678238Y1360099D03*
X1690478D03*
X1682598D03*
X1678238Y1372385D03*
Y1384297D03*
X1690478D03*
Y1372385D03*
X1682598Y1384297D03*
Y1372385D03*
X1678238Y1396583D03*
X1690478D03*
X1682598D03*
X1678238Y1408495D03*
X1690478D03*
X1682598D03*
X1695866Y1232283D03*
Y1236023D03*
X1699607Y1228543D03*
X1695866Y1250984D03*
Y1243503D03*
X1699607Y1247243D03*
Y1239762D03*
X1694838Y1348187D03*
X1702718D03*
X1707078D03*
X1702718Y1360099D03*
X1707078D03*
X1694838D03*
Y1384297D03*
Y1372385D03*
X1702718D03*
Y1384297D03*
X1707078D03*
Y1372385D03*
X1694838Y1396583D03*
X1702718D03*
X1707078D03*
X1694838Y1408495D03*
X1702718D03*
X1707078D03*
X1714958Y1348187D03*
X1719318D03*
X1714958Y1360099D03*
X1719318D03*
X1714958Y1384297D03*
Y1372385D03*
X1719318D03*
Y1384297D03*
X1714958Y1396583D03*
X1719318D03*
X1714958Y1408495D03*
X1719318D03*
X1727198Y1348187D03*
X1739438D03*
X1731558D03*
X1727198Y1360099D03*
X1739438D03*
X1731558D03*
X1739438Y1372385D03*
X1731558Y1384297D03*
Y1372385D03*
X1727198D03*
Y1384297D03*
X1739438D03*
X1727198Y1396583D03*
X1739438D03*
X1731558D03*
X1727198Y1408495D03*
X1739438D03*
X1731558D03*
G54D35*
G01X881911Y1751765D02*
Y1755601D01*
X881397Y1756115D01*
X867518D01*
X867018Y1755615D01*
Y1747808D01*
X865757Y1746547D01*
X859169D01*
X857908Y1747808D01*
Y1758629D01*
X857408Y1759129D01*
X851898D01*
X851398Y1758629D01*
Y1747808D01*
X850137Y1746547D01*
X843549D01*
X842288Y1747808D01*
Y1758629D01*
X841788Y1759129D01*
X836278D01*
X835778Y1758629D01*
Y1747808D01*
X834517Y1746547D01*
X827929D01*
X826668Y1747808D01*
Y1758629D01*
X826168Y1759129D01*
X820658D01*
X820158Y1758629D01*
Y1747808D01*
X818897Y1746547D01*
X812309D01*
X811048Y1747808D01*
Y1758629D01*
X810548Y1759129D01*
X805038D01*
X804538Y1758629D01*
Y1747808D01*
X803277Y1746547D01*
X796689D01*
X795428Y1747808D01*
Y1758629D01*
X794928Y1759129D01*
X789418D01*
X788918Y1758629D01*
Y1747808D01*
X787657Y1746547D01*
X781069D01*
X779808Y1747808D01*
Y1758629D01*
X779308Y1759129D01*
X773798D01*
X773298Y1758629D01*
Y1747808D01*
X772037Y1746547D01*
X765449D01*
X764188Y1747808D01*
Y1758629D01*
X763688Y1759129D01*
X758178D01*
X757678Y1758629D01*
Y1747808D01*
X756417Y1746547D01*
X749829D01*
X748568Y1747808D01*
Y1758629D01*
X748068Y1759129D01*
X742558D01*
X742058Y1758629D01*
Y1747808D01*
X740797Y1746547D01*
X734209D01*
X732948Y1747808D01*
Y1758629D01*
X732448Y1759129D01*
X726938D01*
X726438Y1758629D01*
Y1747808D01*
X725177Y1746547D01*
X718589D01*
X717328Y1747808D01*
Y1758629D01*
X716828Y1759129D01*
X711318D01*
X710818Y1758629D01*
Y1747808D01*
X709557Y1746547D01*
X702969D01*
X701708Y1747808D01*
Y1758629D01*
X701208Y1759129D01*
X695698D01*
X695198Y1758629D01*
Y1747808D01*
X693937Y1746547D01*
X687349D01*
X686088Y1747808D01*
Y1758629D01*
X685588Y1759129D01*
X680078D01*
X679578Y1758629D01*
Y1747808D01*
X678317Y1746547D01*
X671729D01*
X670468Y1747808D01*
Y1758629D01*
X669968Y1759129D01*
X664458D01*
X663958Y1758629D01*
Y1747808D01*
X662697Y1746547D01*
X656109D01*
X654848Y1747808D01*
Y1758491D01*
X654348Y1758991D01*
X648838D01*
X648338Y1758491D01*
Y1747808D01*
X647077Y1746547D01*
X640489D01*
X639228Y1747808D01*
Y1755615D01*
X638728Y1756115D01*
X630361D01*
X629861Y1755615D01*
Y1751765D01*
G01X881911Y1761765D02*
Y1757837D01*
X881489Y1757415D01*
X866979D01*
X865718Y1756154D01*
Y1748347D01*
X865218Y1747847D01*
X859708D01*
X859208Y1748347D01*
Y1759168D01*
X857947Y1760429D01*
X851359D01*
X850098Y1759168D01*
Y1748347D01*
X849598Y1747847D01*
X844088D01*
X843588Y1748347D01*
Y1759168D01*
X842327Y1760429D01*
X835739D01*
X834478Y1759168D01*
Y1748347D01*
X833978Y1747847D01*
X828468D01*
X827968Y1748347D01*
Y1759168D01*
X826707Y1760429D01*
X820119D01*
X818858Y1759168D01*
Y1748347D01*
X818358Y1747847D01*
X812848D01*
X812348Y1748347D01*
Y1759168D01*
X811087Y1760429D01*
X804499D01*
X803238Y1759168D01*
Y1748347D01*
X802738Y1747847D01*
X797228D01*
X796728Y1748347D01*
Y1759168D01*
X795467Y1760429D01*
X788879D01*
X787618Y1759168D01*
Y1748347D01*
X787118Y1747847D01*
X781608D01*
X781108Y1748347D01*
Y1759168D01*
X779847Y1760429D01*
X773259D01*
X771998Y1759168D01*
Y1748347D01*
X771498Y1747847D01*
X765988D01*
X765488Y1748347D01*
Y1759168D01*
X764227Y1760429D01*
X757639D01*
X756378Y1759168D01*
Y1748347D01*
X755878Y1747847D01*
X750368D01*
X749868Y1748347D01*
Y1759168D01*
X748607Y1760429D01*
X742019D01*
X740758Y1759168D01*
Y1748347D01*
X740258Y1747847D01*
X734748D01*
X734248Y1748347D01*
Y1759168D01*
X732987Y1760429D01*
X726399D01*
X725138Y1759168D01*
Y1748347D01*
X724638Y1747847D01*
X719128D01*
X718628Y1748347D01*
Y1759168D01*
X717367Y1760429D01*
X710779D01*
X709518Y1759168D01*
Y1748347D01*
X709018Y1747847D01*
X703508D01*
X703008Y1748347D01*
Y1759168D01*
X701747Y1760429D01*
X695159D01*
X693898Y1759168D01*
Y1748347D01*
X693398Y1747847D01*
X687888D01*
X687388Y1748347D01*
Y1759168D01*
X686127Y1760429D01*
X679539D01*
X678278Y1759168D01*
Y1748347D01*
X677778Y1747847D01*
X672268D01*
X671768Y1748347D01*
Y1759168D01*
X670507Y1760429D01*
X663919D01*
X662658Y1759168D01*
Y1748347D01*
X662158Y1747847D01*
X656648D01*
X656148Y1748347D01*
Y1759030D01*
X654887Y1760291D01*
X648299D01*
X647038Y1759030D01*
Y1748347D01*
X646538Y1747847D01*
X641028D01*
X640528Y1748347D01*
Y1756154D01*
X639267Y1757415D01*
X630361D01*
X629861Y1757915D01*
Y1761765D01*
G54D17*
X109882Y1453504D03*
Y1468859D03*
Y1484213D03*
Y1499567D03*
Y1514922D03*
Y1555867D03*
Y1571221D03*
Y1586575D03*
Y1601930D03*
Y1617284D03*
X127205Y1453504D03*
X118543Y1457835D03*
X127205Y1468859D03*
X118543Y1473189D03*
X127205Y1484213D03*
X118543Y1488544D03*
X127205Y1499567D03*
Y1514922D03*
X118543Y1503898D03*
Y1519252D03*
X127205Y1555867D03*
X118543Y1560197D03*
X127205Y1571221D03*
X118543Y1575552D03*
X127205Y1586575D03*
X118543Y1590906D03*
X127205Y1601930D03*
X118543Y1606260D03*
X127205Y1617284D03*
X118543Y1621615D03*
X144528Y1453504D03*
X135866Y1457835D03*
X144528Y1468859D03*
X135866Y1473189D03*
X144528Y1484213D03*
X135866Y1488544D03*
X144528Y1499567D03*
Y1514922D03*
X135866Y1503898D03*
Y1519252D03*
X144528Y1555867D03*
X135866Y1560197D03*
X144528Y1571221D03*
X135866Y1575552D03*
X144528Y1586575D03*
X135866Y1590906D03*
X144528Y1601930D03*
X135866Y1606260D03*
X144528Y1617284D03*
X135866Y1621615D03*
X161850Y1453504D03*
X153189Y1457835D03*
X161850Y1468859D03*
X153189Y1473189D03*
X161850Y1484213D03*
X153189Y1488544D03*
X161850Y1499567D03*
Y1514922D03*
X153189Y1503898D03*
Y1519252D03*
X161850Y1555867D03*
X153189Y1560197D03*
X161850Y1571221D03*
X153189Y1575552D03*
X161850Y1586575D03*
X153189Y1590906D03*
X161850Y1601930D03*
X153189Y1606260D03*
X161850Y1617284D03*
X153189Y1621615D03*
X170512Y1457835D03*
Y1473189D03*
X179173Y1484213D03*
X170512Y1488544D03*
X179173Y1499567D03*
Y1514922D03*
X170512Y1503898D03*
Y1519252D03*
X179173Y1555867D03*
X170512Y1560197D03*
X179173Y1571221D03*
X170512Y1575552D03*
X179173Y1586575D03*
X170512Y1590906D03*
X179173Y1601930D03*
X170512Y1606260D03*
X179173Y1617284D03*
X170512Y1621615D03*
X187835Y1488544D03*
Y1503898D03*
Y1519252D03*
Y1560197D03*
Y1575552D03*
Y1590906D03*
Y1606260D03*
Y1621615D03*
X361063Y1457835D03*
Y1473189D03*
Y1488544D03*
Y1503898D03*
Y1519252D03*
Y1560197D03*
Y1575552D03*
Y1590906D03*
Y1606260D03*
Y1621615D03*
X629567Y1453504D03*
X638228Y1457835D03*
X629567Y1468859D03*
X638228Y1473189D03*
X629567Y1484213D03*
X638228Y1488544D03*
X629567Y1499567D03*
X638228Y1503898D03*
X629567Y1514922D03*
X638228Y1519252D03*
X629567Y1555867D03*
X638228Y1560197D03*
X629567Y1571221D03*
X638228Y1575552D03*
X629567Y1586575D03*
X638228Y1590906D03*
X629567Y1601930D03*
X638228Y1606260D03*
X629567Y1617284D03*
X638228Y1621615D03*
X646890Y1453504D03*
Y1468859D03*
Y1484213D03*
Y1499567D03*
Y1514922D03*
Y1555867D03*
Y1571221D03*
Y1586575D03*
Y1601930D03*
Y1617284D03*
X664213Y1453504D03*
X655551Y1457835D03*
X664213Y1468859D03*
X655551Y1473189D03*
X664213Y1484213D03*
X655551Y1488544D03*
X664213Y1499567D03*
Y1514922D03*
X655551Y1503898D03*
Y1519252D03*
X664213Y1555867D03*
X655551Y1560197D03*
X664213Y1571221D03*
X655551Y1575552D03*
X664213Y1586575D03*
X655551Y1590906D03*
X664213Y1601930D03*
X655551Y1606260D03*
X664213Y1617284D03*
X655551Y1621615D03*
X681535Y1453504D03*
X672874Y1457835D03*
X681535Y1468859D03*
X672874Y1473189D03*
X681535Y1484213D03*
X672874Y1488544D03*
X681535Y1499567D03*
Y1514922D03*
X672874Y1503898D03*
Y1519252D03*
X681535Y1555867D03*
X672874Y1560197D03*
X681535Y1571221D03*
X672874Y1575552D03*
X681535Y1586575D03*
X672874Y1590906D03*
X681535Y1601930D03*
X672874Y1606260D03*
X681535Y1617284D03*
X672874Y1621615D03*
X698858Y1453504D03*
X690197Y1457835D03*
X698858Y1468859D03*
X690197Y1473189D03*
X698858Y1484213D03*
X690197Y1488544D03*
X698858Y1499567D03*
Y1514922D03*
X690197Y1503898D03*
Y1519252D03*
X698858Y1555867D03*
X690197Y1560197D03*
X698858Y1571221D03*
X690197Y1575552D03*
X698858Y1586575D03*
X690197Y1590906D03*
X698858Y1601930D03*
X690197Y1606260D03*
X698858Y1617284D03*
X690197Y1621615D03*
X707520Y1457835D03*
Y1473189D03*
Y1488544D03*
Y1503898D03*
Y1519252D03*
Y1560197D03*
Y1575552D03*
Y1590906D03*
Y1606260D03*
Y1621615D03*
X1131850Y1453504D03*
X1140511Y1457835D03*
X1131850Y1468859D03*
X1140511Y1473189D03*
X1131850Y1484213D03*
X1140511Y1488544D03*
X1131850Y1499567D03*
X1140511Y1503898D03*
X1131850Y1514922D03*
X1140511Y1519252D03*
X1131850Y1555867D03*
X1140511Y1560197D03*
X1131850Y1571221D03*
X1140511Y1575552D03*
X1131850Y1586575D03*
X1140511Y1590906D03*
X1131850Y1601930D03*
X1140511Y1606260D03*
X1131850Y1617284D03*
X1140511Y1621615D03*
X1149173Y1453504D03*
X1157834Y1457835D03*
X1149173Y1468859D03*
X1157834Y1473189D03*
X1149173Y1484213D03*
X1157834Y1488544D03*
X1149173Y1499567D03*
X1157834Y1503898D03*
X1149173Y1514922D03*
X1157834Y1519252D03*
X1149173Y1555867D03*
X1157834Y1560197D03*
X1149173Y1571221D03*
X1157834Y1575552D03*
X1149173Y1586575D03*
X1157834Y1590906D03*
X1149173Y1601930D03*
X1157834Y1606260D03*
X1149173Y1617284D03*
X1157834Y1621615D03*
X1166496Y1453504D03*
Y1468859D03*
Y1484213D03*
Y1499567D03*
Y1514922D03*
Y1555867D03*
Y1571221D03*
Y1586575D03*
Y1601930D03*
Y1617284D03*
X1183818Y1453504D03*
X1175157Y1457835D03*
X1183818Y1468859D03*
X1175157Y1473189D03*
X1183818Y1484213D03*
X1175157Y1488544D03*
X1183818Y1499567D03*
Y1514922D03*
X1175157Y1503898D03*
Y1519252D03*
X1183818Y1555867D03*
X1175157Y1560197D03*
X1183818Y1571221D03*
X1175157Y1575552D03*
X1183818Y1586575D03*
X1175157Y1590906D03*
X1183818Y1601930D03*
X1175157Y1606260D03*
X1183818Y1617284D03*
X1175157Y1621615D03*
X1201141Y1453504D03*
X1192480Y1457835D03*
X1201141Y1468859D03*
X1192480Y1473189D03*
X1201141Y1484213D03*
X1192480Y1488544D03*
X1201141Y1499567D03*
Y1514922D03*
X1192480Y1503898D03*
Y1519252D03*
X1201141Y1555867D03*
X1192480Y1560197D03*
X1201141Y1571221D03*
X1192480Y1575552D03*
X1201141Y1586575D03*
X1192480Y1590906D03*
X1201141Y1601930D03*
X1192480Y1606260D03*
X1201141Y1617284D03*
X1192480Y1621615D03*
X1209803Y1457835D03*
Y1473189D03*
Y1488544D03*
Y1503898D03*
Y1519252D03*
Y1560197D03*
Y1575552D03*
Y1590906D03*
Y1606260D03*
Y1621615D03*
X1383032Y1457835D03*
Y1473189D03*
Y1488544D03*
Y1503898D03*
Y1519252D03*
Y1560197D03*
Y1575552D03*
Y1590906D03*
Y1606260D03*
Y1621615D03*
X1651535Y1453504D03*
X1660196Y1457835D03*
X1651535Y1468859D03*
X1660196Y1473189D03*
X1651535Y1484213D03*
X1660196Y1488544D03*
X1651535Y1499567D03*
X1660196Y1503898D03*
X1651535Y1514922D03*
X1660196Y1519252D03*
X1651535Y1555867D03*
X1660196Y1560197D03*
X1651535Y1571221D03*
X1660196Y1575552D03*
X1651535Y1586575D03*
X1660196Y1590906D03*
X1651535Y1601930D03*
X1660196Y1606260D03*
X1651535Y1617284D03*
X1660196Y1621615D03*
X1668858Y1453504D03*
X1677519Y1457835D03*
X1668858Y1468859D03*
X1677519Y1473189D03*
X1668858Y1484213D03*
X1677519Y1488544D03*
X1668858Y1499567D03*
X1677519Y1503898D03*
X1668858Y1514922D03*
X1677519Y1519252D03*
X1668858Y1555867D03*
X1677519Y1560197D03*
X1668858Y1571221D03*
X1677519Y1575552D03*
X1668858Y1586575D03*
X1677519Y1590906D03*
X1668858Y1601930D03*
X1677519Y1606260D03*
X1668858Y1617284D03*
X1677519Y1621615D03*
X1686181Y1453504D03*
Y1468859D03*
Y1484213D03*
Y1499567D03*
Y1514922D03*
Y1555867D03*
Y1571221D03*
Y1586575D03*
Y1601930D03*
Y1617284D03*
X1703503Y1453504D03*
X1694842Y1457835D03*
X1703503Y1468859D03*
X1694842Y1473189D03*
X1703503Y1484213D03*
X1694842Y1488544D03*
X1703503Y1499567D03*
Y1514922D03*
X1694842Y1503898D03*
Y1519252D03*
X1703503Y1555867D03*
X1694842Y1560197D03*
X1703503Y1571221D03*
X1694842Y1575552D03*
X1703503Y1586575D03*
X1694842Y1590906D03*
X1703503Y1601930D03*
X1694842Y1606260D03*
X1703503Y1617284D03*
X1694842Y1621615D03*
X1720826Y1453504D03*
X1712165Y1457835D03*
X1720826Y1468859D03*
X1712165Y1473189D03*
X1720826Y1484213D03*
X1712165Y1488544D03*
X1720826Y1499567D03*
Y1514922D03*
X1712165Y1503898D03*
Y1519252D03*
X1720826Y1555867D03*
X1712165Y1560197D03*
X1720826Y1571221D03*
X1712165Y1575552D03*
X1720826Y1586575D03*
X1712165Y1590906D03*
X1720826Y1601930D03*
X1712165Y1606260D03*
X1720826Y1617284D03*
X1712165Y1621615D03*
X1729488Y1457835D03*
Y1473189D03*
Y1488544D03*
Y1503898D03*
Y1519252D03*
Y1560197D03*
Y1575552D03*
Y1590906D03*
Y1606260D03*
Y1621615D03*
G54D26*
X1250048Y1768377D03*
Y1778377D03*
G54D36*
G01X66856Y104249D02*
X67997Y105390D01*
X71860D01*
X72860Y106390D01*
X83960D01*
X103710Y126140D01*
Y138840D01*
X145356Y180486D01*
X150510Y232821D01*
Y287910D01*
X162190Y299590D01*
X350060D01*
X356460Y305990D01*
X407910D01*
X413610Y300290D01*
X416377D01*
X418032Y301945D01*
Y303325D01*
X419177Y304470D01*
G01X66856Y107649D02*
X68005Y106500D01*
X71400D01*
X72400Y107500D01*
X83500D01*
X84992Y108992D01*
Y109628D01*
X86372Y111008D01*
X87008D01*
X88386Y112386D01*
Y113023D01*
X89766Y114403D01*
X90403D01*
X91781Y115781D01*
Y116418D01*
X93161Y117798D01*
X93798D01*
X95176Y119176D01*
Y119813D01*
X96556Y121193D01*
X97193D01*
X102600Y126600D01*
Y139300D01*
X144290Y180990D01*
X149400Y232876D01*
Y288370D01*
X161730Y300700D01*
X349600D01*
X356000Y307100D01*
X408370D01*
X414070Y301400D01*
X415917D01*
X416922Y302405D01*
Y303325D01*
X415777Y304470D01*
G01X56348Y1727941D02*
Y1731736D01*
X56998Y1732386D01*
X65603D01*
X67553Y1734336D01*
Y1736310D01*
X68853Y1737610D01*
X70913D01*
X72213Y1736310D01*
Y1729112D01*
X74163Y1727162D01*
X77143D01*
X79093Y1729112D01*
Y1736310D01*
X80393Y1737610D01*
X82453D01*
X83753Y1736310D01*
Y1729112D01*
X85703Y1727162D01*
X88683D01*
X90633Y1729112D01*
Y1736310D01*
X91933Y1737610D01*
X93993D01*
X95293Y1736310D01*
Y1729112D01*
X97243Y1727162D01*
X100223D01*
X102173Y1729112D01*
Y1736310D01*
X103473Y1737610D01*
X105533D01*
X106833Y1736310D01*
Y1729112D01*
X108783Y1727162D01*
X111763D01*
X113713Y1729112D01*
Y1736310D01*
X115013Y1737610D01*
X117073D01*
X118373Y1736310D01*
Y1729112D01*
X120323Y1727162D01*
X123303D01*
X125253Y1729112D01*
Y1736310D01*
X126553Y1737610D01*
X128613D01*
X129913Y1736310D01*
Y1729112D01*
X131863Y1727162D01*
X134843D01*
X136793Y1729112D01*
Y1736310D01*
X138093Y1737610D01*
X140153D01*
X141453Y1736310D01*
Y1729112D01*
X143403Y1727162D01*
X146383D01*
X148333Y1729112D01*
Y1736310D01*
X149633Y1737610D01*
X151693D01*
X152993Y1736310D01*
Y1729112D01*
X154943Y1727162D01*
X157923D01*
X159873Y1729112D01*
Y1736310D01*
X161173Y1737610D01*
X163233D01*
X164533Y1736310D01*
Y1729112D01*
X166483Y1727162D01*
X169463D01*
X171413Y1729112D01*
Y1736310D01*
X172713Y1737610D01*
X174773D01*
X176073Y1736310D01*
Y1729112D01*
X178023Y1727162D01*
X181003D01*
X182953Y1729112D01*
Y1736310D01*
X184253Y1737610D01*
X186313D01*
X187613Y1736310D01*
Y1729112D01*
X189563Y1727162D01*
X192543D01*
X194493Y1729112D01*
Y1736310D01*
X195793Y1737610D01*
X197853D01*
X199153Y1736310D01*
Y1729112D01*
X201103Y1727162D01*
X204083D01*
X206033Y1729112D01*
Y1736310D01*
X207333Y1737610D01*
X209393D01*
X210693Y1736310D01*
Y1729112D01*
X212643Y1727162D01*
X215623D01*
X217573Y1729112D01*
Y1736310D01*
X218873Y1737610D01*
X220933D01*
X222233Y1736310D01*
Y1729112D01*
X224183Y1727162D01*
X227163D01*
X229113Y1729112D01*
Y1736310D01*
X230413Y1737610D01*
X232473D01*
X233773Y1736310D01*
Y1729112D01*
X235723Y1727162D01*
X238703D01*
X240653Y1729112D01*
Y1736310D01*
X241953Y1737610D01*
X244013D01*
X245313Y1736310D01*
Y1729112D01*
X247263Y1727162D01*
X250243D01*
X252193Y1729112D01*
Y1736310D01*
X253493Y1737610D01*
X255553D01*
X256853Y1736310D01*
Y1729112D01*
X258803Y1727162D01*
X261783D01*
X263733Y1729112D01*
Y1736310D01*
X265033Y1737610D01*
X267093D01*
X268393Y1736310D01*
Y1729112D01*
X270343Y1727162D01*
X273323D01*
X275273Y1729112D01*
Y1736310D01*
X276573Y1737610D01*
X278633D01*
X279933Y1736310D01*
Y1729112D01*
X281883Y1727162D01*
X284863D01*
X286813Y1729112D01*
Y1736310D01*
X288113Y1737610D01*
X290173D01*
X291473Y1736310D01*
Y1729112D01*
X293423Y1727162D01*
X296403D01*
X298353Y1729112D01*
Y1731086D01*
X299653Y1732386D01*
X307798D01*
X308448Y1731736D01*
Y1727941D01*
G01X56348Y1737941D02*
Y1734146D01*
X56998Y1733496D01*
X65143D01*
X66443Y1734796D01*
Y1736770D01*
X68393Y1738720D01*
X71373D01*
X73323Y1736770D01*
Y1729572D01*
X74623Y1728272D01*
X76683D01*
X77983Y1729572D01*
Y1736770D01*
X79933Y1738720D01*
X82913D01*
X84863Y1736770D01*
Y1729572D01*
X86163Y1728272D01*
X88223D01*
X89523Y1729572D01*
Y1736770D01*
X91473Y1738720D01*
X94453D01*
X96403Y1736770D01*
Y1729572D01*
X97703Y1728272D01*
X99763D01*
X101063Y1729572D01*
Y1736770D01*
X103013Y1738720D01*
X105993D01*
X107943Y1736770D01*
Y1729572D01*
X109243Y1728272D01*
X111303D01*
X112603Y1729572D01*
Y1736770D01*
X114553Y1738720D01*
X117533D01*
X119483Y1736770D01*
Y1729572D01*
X120783Y1728272D01*
X122843D01*
X124143Y1729572D01*
Y1736770D01*
X126093Y1738720D01*
X129073D01*
X131023Y1736770D01*
Y1729572D01*
X132323Y1728272D01*
X134383D01*
X135683Y1729572D01*
Y1736770D01*
X137633Y1738720D01*
X140613D01*
X142563Y1736770D01*
Y1729572D01*
X143863Y1728272D01*
X145923D01*
X147223Y1729572D01*
Y1736770D01*
X149173Y1738720D01*
X152153D01*
X154103Y1736770D01*
Y1729572D01*
X155403Y1728272D01*
X157463D01*
X158763Y1729572D01*
Y1736770D01*
X160713Y1738720D01*
X163693D01*
X165643Y1736770D01*
Y1729572D01*
X166943Y1728272D01*
X169003D01*
X170303Y1729572D01*
Y1736770D01*
X172253Y1738720D01*
X175233D01*
X177183Y1736770D01*
Y1729572D01*
X178483Y1728272D01*
X180543D01*
X181843Y1729572D01*
Y1736770D01*
X183793Y1738720D01*
X186773D01*
X188723Y1736770D01*
Y1729572D01*
X190023Y1728272D01*
X192083D01*
X193383Y1729572D01*
Y1736770D01*
X195333Y1738720D01*
X198313D01*
X200263Y1736770D01*
Y1729572D01*
X201563Y1728272D01*
X203623D01*
X204923Y1729572D01*
Y1736770D01*
X206873Y1738720D01*
X209853D01*
X211803Y1736770D01*
Y1729572D01*
X213103Y1728272D01*
X215163D01*
X216463Y1729572D01*
Y1736770D01*
X218413Y1738720D01*
X221393D01*
X223343Y1736770D01*
Y1729572D01*
X224643Y1728272D01*
X226703D01*
X228003Y1729572D01*
Y1736770D01*
X229953Y1738720D01*
X232933D01*
X234883Y1736770D01*
Y1729572D01*
X236183Y1728272D01*
X238243D01*
X239543Y1729572D01*
Y1736770D01*
X241493Y1738720D01*
X244473D01*
X246423Y1736770D01*
Y1729572D01*
X247723Y1728272D01*
X249783D01*
X251083Y1729572D01*
Y1736770D01*
X253033Y1738720D01*
X256013D01*
X257963Y1736770D01*
Y1729572D01*
X259263Y1728272D01*
X261323D01*
X262623Y1729572D01*
Y1736770D01*
X264573Y1738720D01*
X267553D01*
X269503Y1736770D01*
Y1729572D01*
X270803Y1728272D01*
X272863D01*
X274163Y1729572D01*
Y1736770D01*
X276113Y1738720D01*
X279093D01*
X281043Y1736770D01*
Y1729572D01*
X282343Y1728272D01*
X284403D01*
X285703Y1729572D01*
Y1736770D01*
X287653Y1738720D01*
X290633D01*
X292583Y1736770D01*
Y1729572D01*
X293883Y1728272D01*
X295943D01*
X297243Y1729572D01*
Y1731546D01*
X299193Y1733496D01*
X307798D01*
X308448Y1734146D01*
Y1737941D01*
G01X179173Y1479095D02*
Y1477591D01*
X179673Y1477091D01*
X182353D01*
X183503Y1475941D01*
Y1453567D01*
X184677Y1449576D01*
X198375Y1428290D01*
X198372Y1428241D01*
X201045Y1423305D01*
X215380Y1391293D01*
Y1366338D01*
X207443Y1347175D01*
X204406Y1343085D01*
X125040Y1297420D01*
X102127Y1282111D01*
X94725Y1274709D01*
X92543Y1269441D01*
Y1253932D01*
X96639Y1233338D01*
X97110Y1233024D01*
X97490Y1231110D01*
X97176Y1230640D01*
X97556Y1228728D01*
X98027Y1228414D01*
X98407Y1226500D01*
X98093Y1226030D01*
X98473Y1224118D01*
X98944Y1223803D01*
X99325Y1221890D01*
X99010Y1221419D01*
X100221Y1215331D01*
X106418Y1200369D01*
X110725Y1196062D01*
X115800Y1183809D01*
Y1153026D01*
X117110Y1149863D01*
X117633Y1149646D01*
X118381Y1147844D01*
X118164Y1147321D01*
X118910Y1145520D01*
X119433Y1145304D01*
X120180Y1143501D01*
X119964Y1142979D01*
X121996Y1138074D01*
X123078Y1136992D01*
X128586Y1134710D01*
X133774D01*
X136615Y1131869D01*
X140062D01*
G01Y1130759D02*
X136155D01*
X133314Y1133600D01*
X128365D01*
X122449Y1136051D01*
X121055Y1137445D01*
X114690Y1152805D01*
Y1183588D01*
X109784Y1195433D01*
X105477Y1199740D01*
X99153Y1215007D01*
X91433Y1253822D01*
Y1269662D01*
X93784Y1275338D01*
X101419Y1282973D01*
X124454Y1298364D01*
X203652Y1343932D01*
X206470Y1347727D01*
X208873Y1353530D01*
X208657Y1354053D01*
X209404Y1355855D01*
X209926Y1356072D01*
X210672Y1357873D01*
X210456Y1358396D01*
X211203Y1360198D01*
X211725Y1360415D01*
X212471Y1362216D01*
X212254Y1362739D01*
X213002Y1364541D01*
X213524Y1364758D01*
X214270Y1366559D01*
Y1368509D01*
X213870Y1368909D01*
Y1370859D01*
X214270Y1371259D01*
Y1391055D01*
X200049Y1422813D01*
X197396Y1427712D01*
X197404Y1427746D01*
X183656Y1449109D01*
X182393Y1453407D01*
Y1475481D01*
X181893Y1475981D01*
X179673D01*
X179173Y1475481D01*
Y1473977D01*
G01X187835Y1478308D02*
Y1479812D01*
X188335Y1480312D01*
X190759D01*
X191680Y1479391D01*
Y1465776D01*
X218300Y1391380D01*
Y1365063D01*
X216689Y1360676D01*
X216175Y1360438D01*
X215502Y1358607D01*
X215740Y1358093D01*
X212664Y1349718D01*
X207067Y1341022D01*
X197388Y1335889D01*
X124461Y1293218D01*
X103659Y1279325D01*
X97091Y1272755D01*
X95210Y1268215D01*
Y1259645D01*
X103162Y1219665D01*
X106760Y1210980D01*
X109881Y1207859D01*
X118732Y1186492D01*
Y1153269D01*
X126108Y1145893D01*
X129054Y1138782D01*
X130306Y1137530D01*
X135245D01*
X136518Y1136257D01*
G01X187835Y1483426D02*
Y1481922D01*
X188335Y1481422D01*
X191219D01*
X192790Y1479851D01*
Y1465969D01*
X219410Y1391573D01*
Y1364865D01*
X213664Y1349220D01*
X207844Y1340177D01*
X197929Y1334919D01*
X125051Y1292276D01*
X104367Y1278463D01*
X98032Y1272126D01*
X96320Y1267993D01*
Y1259755D01*
X104230Y1219989D01*
X107701Y1211609D01*
X110822Y1208488D01*
X119842Y1186713D01*
Y1171175D01*
X120242Y1170775D01*
Y1168825D01*
X119842Y1168425D01*
Y1166475D01*
X120242Y1166075D01*
Y1164125D01*
X119842Y1163725D01*
Y1161775D01*
X120242Y1161375D01*
Y1159425D01*
X119842Y1159025D01*
Y1153729D01*
X123725Y1149846D01*
X124291D01*
X125671Y1148466D01*
Y1147900D01*
X127049Y1146522D01*
X129995Y1139411D01*
X130766Y1138640D01*
X135705D01*
X137303Y1137042D01*
G01X138343Y1140701D02*
X136371Y1142673D01*
Y1156871D01*
X128830Y1164412D01*
X126403Y1170273D01*
Y1174527D01*
X127490Y1177152D01*
Y1178810D01*
X127290Y1179010D01*
Y1191383D01*
X128065Y1194967D01*
X128066Y1194968D01*
X129883Y1203351D01*
X130084Y1212890D01*
X131829Y1223911D01*
X131745Y1238336D01*
X134636Y1255216D01*
X141024Y1266493D01*
X141025D01*
X147612Y1278124D01*
X173348Y1309642D01*
X192315Y1325049D01*
X212203Y1337756D01*
X220644Y1351351D01*
X223822Y1361648D01*
Y1393081D01*
X223852Y1393111D01*
Y1393174D01*
X225524Y1402852D01*
X225198Y1403314D01*
X225530Y1405237D01*
X225993Y1405563D01*
X226324Y1407484D01*
X225998Y1407946D01*
X226330Y1409869D01*
X226794Y1410195D01*
X226793D01*
X229424Y1425422D01*
X232202Y1444992D01*
Y1447707D01*
X231311Y1448598D01*
X228394D01*
X227249Y1447453D01*
G01X139128Y1141486D02*
X137481Y1143133D01*
Y1157331D01*
X129771Y1165041D01*
X127513Y1170494D01*
Y1174306D01*
X128600Y1176931D01*
Y1179270D01*
X128400Y1179470D01*
Y1191264D01*
X129053Y1194281D01*
X129530Y1194587D01*
X129943Y1196494D01*
X129637Y1196970D01*
X130991Y1203220D01*
X131193Y1212791D01*
X132940Y1223827D01*
X132856Y1238245D01*
X133963Y1244711D01*
X134426Y1245037D01*
X134755Y1246960D01*
X134429Y1247422D01*
X135698Y1254837D01*
X140635Y1263552D01*
X141180Y1263703D01*
X142142Y1265401D01*
X141991Y1265946D01*
X148532Y1277494D01*
X167833Y1301132D01*
X168395Y1301189D01*
X169630Y1302700D01*
X169573Y1303263D01*
X174136Y1308852D01*
X192966Y1324147D01*
X213013Y1336956D01*
X221663Y1350887D01*
X224932Y1361480D01*
Y1393056D01*
X224952Y1393076D01*
X224962D01*
X230521Y1425249D01*
X230523Y1425266D01*
X233312Y1444913D01*
Y1448167D01*
X231771Y1449708D01*
X228394D01*
X227249Y1450853D01*
G01Y1458453D02*
X228394Y1459598D01*
X231101D01*
X236154Y1454545D01*
Y1445619D01*
X236153Y1445618D01*
X234921Y1434392D01*
Y1434391D01*
X233689Y1423167D01*
X232938Y1418817D01*
X232475Y1418491D01*
X232143Y1416568D01*
X232469Y1416106D01*
X232138Y1414185D01*
X231675Y1413859D01*
X231343Y1411936D01*
X231669Y1411474D01*
X228056Y1390542D01*
Y1360563D01*
X225875Y1349248D01*
X214615Y1334205D01*
X192233Y1319881D01*
X180371Y1310316D01*
X150682Y1273960D01*
X138225Y1251970D01*
X137967Y1250980D01*
X138056Y1230101D01*
X138633Y1226725D01*
X138433Y1220695D01*
X137724Y1217750D01*
X136977Y1195822D01*
X137874Y1191311D01*
Y1166975D01*
X140301Y1161113D01*
Y1146076D01*
G01X141411D02*
Y1161453D01*
X141327Y1161537D01*
X138984Y1167196D01*
Y1191421D01*
X138091Y1195913D01*
X138830Y1217600D01*
X139539Y1220545D01*
X139747Y1226801D01*
X139166Y1230198D01*
X139078Y1250840D01*
X139263Y1251549D01*
X145315Y1262233D01*
X145861Y1262384D01*
X146823Y1264082D01*
X146672Y1264627D01*
X147633Y1266323D01*
X148178Y1266474D01*
X149140Y1268172D01*
X148989Y1268717D01*
X151602Y1273330D01*
X160133Y1283777D01*
X160696Y1283834D01*
X161930Y1285345D01*
X161873Y1285908D01*
X181158Y1309524D01*
X192883Y1318978D01*
X215384Y1333378D01*
X226917Y1348787D01*
X229166Y1360456D01*
Y1390446D01*
X234789Y1423012D01*
X236025Y1434270D01*
Y1434271D01*
X237264Y1445557D01*
Y1455005D01*
X231561Y1460708D01*
X228394D01*
X227249Y1461853D01*
G01X169218Y107649D02*
X170367Y106500D01*
X172582D01*
X179824Y107940D01*
X184518Y109886D01*
X191343Y111243D01*
X198100Y118000D01*
Y132400D01*
X199478Y133778D01*
Y134415D01*
X200858Y135795D01*
X201495D01*
X202873Y137173D01*
Y137810D01*
X204253Y139190D01*
X204890D01*
X206268Y140568D01*
Y141205D01*
X207648Y142585D01*
X208285D01*
X209663Y143963D01*
Y144600D01*
X211043Y145980D01*
X211680D01*
X248599Y182899D01*
X250600Y223631D01*
Y286500D01*
X261200Y297100D01*
X355500D01*
X360500Y302100D01*
X407000D01*
X411290Y297810D01*
X421140D01*
X424796Y301466D01*
Y306325D01*
X423651Y307470D01*
G01X169218Y104249D02*
X170359Y105390D01*
X172692D01*
X180148Y106872D01*
X184842Y108818D01*
X191890Y110220D01*
X199210Y117540D01*
Y131940D01*
X249687Y182417D01*
X251710Y223603D01*
Y286040D01*
X261660Y295990D01*
X355960D01*
X360960Y300990D01*
X406540D01*
X410830Y296700D01*
X421600D01*
X425906Y301006D01*
Y306325D01*
X427051Y307470D01*
G01X269503Y1348187D02*
X268358Y1347042D01*
Y1344364D01*
X267098Y1342261D01*
X203595Y1308316D01*
X198111Y1306045D01*
X183761Y1291695D01*
X177425Y1276399D01*
Y1260455D01*
G01X241623Y1348187D02*
X242768Y1347042D01*
Y1343700D01*
X215608Y1325553D01*
X193702Y1313843D01*
X176075Y1296215D01*
X168834Y1278734D01*
Y1260555D01*
G01X269503Y1396583D02*
X268358Y1395438D01*
Y1392726D01*
X274478Y1386606D01*
Y1341898D01*
X205562Y1305060D01*
X200239Y1302855D01*
X186968Y1289584D01*
X181165Y1275574D01*
Y1260643D01*
G01X266103Y1396583D02*
X267248Y1395438D01*
Y1392266D01*
X273368Y1386146D01*
Y1342564D01*
X205087Y1306065D01*
X199610Y1303796D01*
X186027Y1290213D01*
X180055Y1275795D01*
Y1260643D01*
G01X253863Y1372385D02*
X255008Y1371240D01*
Y1368502D01*
X261128Y1362382D01*
Y1346940D01*
X259193Y1343712D01*
X202110Y1313200D01*
X195739Y1310561D01*
X179392Y1294214D01*
X172574Y1277753D01*
Y1260543D01*
G01X245023Y1348187D02*
X243878Y1347042D01*
Y1343106D01*
X216180Y1324599D01*
X194371Y1312941D01*
X177016Y1295586D01*
X169944Y1278513D01*
Y1260555D01*
G01X266103Y1348187D02*
X267248Y1347042D01*
Y1344672D01*
X266303Y1343096D01*
X203120Y1309321D01*
X197482Y1306986D01*
X182820Y1292324D01*
X176315Y1276620D01*
Y1260455D01*
G01X257263Y1372385D02*
X256118Y1371240D01*
Y1368962D01*
X262238Y1362842D01*
Y1346632D01*
X259988Y1342877D01*
X202585Y1312195D01*
X196368Y1309620D01*
X180333Y1293585D01*
X173684Y1277532D01*
Y1260543D01*
G01X306223Y1372385D02*
X305078Y1371240D01*
Y1368962D01*
X311198Y1362842D01*
Y1346865D01*
X308625Y1342573D01*
X216302Y1293226D01*
X208756Y1290100D01*
X200919Y1282263D01*
X196125Y1270689D01*
Y1260425D01*
G01X278343Y1372385D02*
X279488Y1371240D01*
Y1368502D01*
X285608Y1362382D01*
Y1345773D01*
X284664Y1344200D01*
X246251Y1323667D01*
Y1323668D01*
X207838Y1303134D01*
X201740Y1300608D01*
X189338Y1288206D01*
X183795Y1274824D01*
Y1260627D01*
G01X293983Y1396583D02*
X292838Y1395438D01*
Y1392726D01*
X298958Y1386606D01*
Y1344433D01*
X296653Y1340588D01*
X213452Y1296116D01*
X206627Y1293289D01*
X197347Y1284009D01*
X192385Y1272029D01*
Y1260355D01*
G01X302823Y1372385D02*
X303968Y1371240D01*
Y1368502D01*
X310088Y1362382D01*
Y1347173D01*
X307830Y1343408D01*
X215827Y1294231D01*
X208127Y1291041D01*
X199978Y1282892D01*
X195015Y1270910D01*
Y1260425D01*
G01X293983Y1348187D02*
X292838Y1347042D01*
Y1343766D01*
X292200Y1342701D01*
X209952Y1298737D01*
X204498Y1296478D01*
X193919Y1285899D01*
X188645Y1273166D01*
Y1260343D01*
G01X281743Y1372385D02*
X280598Y1371240D01*
Y1368962D01*
X286718Y1362842D01*
Y1345465D01*
X285459Y1343365D01*
X208313Y1302129D01*
X202369Y1299667D01*
X190279Y1287577D01*
X184905Y1274603D01*
Y1260627D01*
G01X290583Y1396583D02*
X291728Y1395438D01*
Y1392266D01*
X297848Y1386146D01*
Y1344741D01*
X295858Y1341423D01*
X212977Y1297121D01*
X205998Y1294230D01*
X196406Y1284638D01*
X191275Y1272250D01*
Y1260355D01*
G01X290583Y1348187D02*
X291728Y1347042D01*
Y1344074D01*
X291405Y1343536D01*
X209477Y1299742D01*
X203869Y1297419D01*
X192978Y1286528D01*
X187535Y1273387D01*
Y1260343D01*
G01X202496Y1260852D02*
Y1268241D01*
X207116Y1279394D01*
X212384Y1284662D01*
X226081Y1290336D01*
X318484Y1339729D01*
X322328Y1346141D01*
Y1386146D01*
X316208Y1392266D01*
Y1395438D01*
X315063Y1396583D01*
G01Y1348187D02*
X316208Y1347042D01*
Y1345106D01*
X314371Y1342044D01*
X222389Y1292877D01*
X210255Y1287851D01*
X203477Y1281073D01*
X198756Y1269675D01*
Y1260555D01*
G01X209976Y1260824D02*
Y1266460D01*
X213623Y1275265D01*
X216641Y1278283D01*
X245958Y1290426D01*
X335320Y1338192D01*
X340688Y1343559D01*
Y1347042D01*
X339543Y1348187D01*
G01X330703Y1372385D02*
X329558Y1371240D01*
Y1368962D01*
X335678Y1362842D01*
Y1346232D01*
X332544Y1341003D01*
X234114Y1288390D01*
X215142Y1280532D01*
X211284Y1276674D01*
X207346Y1267167D01*
Y1261000D01*
G01X211086Y1260824D02*
Y1266239D01*
X214564Y1274636D01*
X217270Y1277342D01*
X246433Y1289421D01*
X335989Y1337290D01*
X341798Y1343099D01*
Y1347042D01*
X342943Y1348187D01*
G01X339543Y1396583D02*
X340688Y1395438D01*
Y1392266D01*
X346808Y1386146D01*
Y1344341D01*
X342613Y1337343D01*
X251564Y1288678D01*
X219545Y1275415D01*
X216092Y1271962D01*
X213716Y1266223D01*
Y1260672D01*
G01X327303Y1372385D02*
X328448Y1371240D01*
Y1368502D01*
X334568Y1362382D01*
Y1346540D01*
X331749Y1341838D01*
X233639Y1289395D01*
X214513Y1281473D01*
X210343Y1277303D01*
X206236Y1267388D01*
Y1261000D01*
G01X318463Y1348187D02*
X317318Y1347042D01*
Y1344798D01*
X315166Y1341209D01*
X222864Y1291872D01*
X210884Y1286910D01*
X204418Y1280444D01*
X199866Y1269454D01*
Y1260555D01*
G01X203606Y1260852D02*
Y1268020D01*
X208057Y1278765D01*
X213013Y1283721D01*
X226556Y1289331D01*
X319279Y1338894D01*
X323438Y1345833D01*
Y1386606D01*
X317318Y1392726D01*
Y1395438D01*
X318463Y1396583D01*
G01X351783Y1372385D02*
X352928Y1371240D01*
Y1368502D01*
X359048Y1362382D01*
Y1345619D01*
X349740Y1336311D01*
X257986Y1287267D01*
X222155Y1272425D01*
X219239Y1269509D01*
X217456Y1265204D01*
Y1260381D01*
G01X355183Y1372385D02*
X354038Y1371240D01*
Y1368962D01*
X360158Y1362842D01*
Y1345158D01*
X350409Y1335409D01*
X350264Y1335331D01*
Y1335332D01*
X258461Y1286262D01*
X222784Y1271484D01*
X220180Y1268880D01*
X218566Y1264983D01*
Y1260381D01*
G01X364023Y1348187D02*
X365168Y1347042D01*
Y1343739D01*
X357230Y1335801D01*
X261672Y1284723D01*
X224425Y1269295D01*
X222456Y1267326D01*
X221197Y1264286D01*
Y1260683D01*
G01X224937Y1260625D02*
Y1263408D01*
X226811Y1266213D01*
X271284Y1284634D01*
X358457Y1331228D01*
X363872Y1336642D01*
X363871D01*
X369286Y1342056D01*
X371288Y1346889D01*
Y1386146D01*
X365168Y1392266D01*
Y1395438D01*
X364023Y1396583D01*
G01X367423Y1348187D02*
X366278Y1347042D01*
Y1343278D01*
X357899Y1334899D01*
X357754Y1334821D01*
Y1334822D01*
X262147Y1283718D01*
X225054Y1268354D01*
X223397Y1266697D01*
X222307Y1264065D01*
Y1260683D01*
G01X342943Y1396583D02*
X341798Y1395438D01*
Y1392726D01*
X347918Y1386606D01*
Y1344033D01*
X343408Y1336508D01*
X252039Y1287673D01*
X220174Y1274474D01*
X217033Y1271333D01*
X214826Y1266002D01*
Y1260672D01*
G01X226047Y1260625D02*
Y1263071D01*
X227547Y1265316D01*
X271759Y1283629D01*
X359126Y1330326D01*
X370227Y1341427D01*
X372398Y1346668D01*
Y1386606D01*
X366278Y1392726D01*
Y1395438D01*
X367423Y1396583D01*
G01X283110Y1612166D02*
Y1610662D01*
X283610Y1610162D01*
X285838D01*
X287733Y1608267D01*
Y1556059D01*
X286307Y1553391D01*
X286306D01*
X266364Y1540064D01*
X258289Y1531989D01*
X250601Y1513428D01*
X242846Y1423691D01*
X237758Y1387927D01*
Y1370012D01*
X243878Y1363892D01*
Y1361244D01*
X245023Y1360099D01*
G01X283110Y1607048D02*
Y1608552D01*
X283610Y1609052D01*
X285378D01*
X286623Y1607807D01*
Y1556338D01*
X285458Y1554160D01*
X282955Y1552487D01*
X282331Y1552611D01*
X280708Y1551527D01*
X280584Y1550903D01*
X278963Y1549820D01*
X278339Y1549944D01*
X276717Y1548859D01*
X276593Y1548235D01*
X265656Y1540926D01*
X257348Y1532618D01*
X249509Y1513695D01*
X241742Y1423817D01*
X236648Y1388006D01*
Y1369552D01*
X242768Y1363432D01*
Y1361244D01*
X241623Y1360099D01*
G01X300433Y1607048D02*
Y1608552D01*
X300933Y1609052D01*
X302701D01*
X303946Y1607807D01*
Y1554916D01*
X301837Y1552807D01*
X298427Y1550529D01*
X297803Y1550653D01*
X296181Y1549569D01*
X296057Y1548945D01*
X293262Y1547078D01*
X291543Y1546159D01*
X290934Y1546344D01*
X289213Y1545424D01*
X289028Y1544815D01*
X271016Y1535187D01*
X263675Y1527845D01*
X257451Y1512818D01*
Y1504550D01*
X258852Y1446276D01*
X260317Y1431405D01*
X261128Y1414887D01*
Y1369552D01*
X267248Y1363432D01*
Y1361244D01*
X266103Y1360099D01*
G01X300433Y1612166D02*
Y1610662D01*
X300933Y1610162D01*
X303161D01*
X305056Y1608267D01*
Y1554456D01*
X302545Y1551945D01*
X293834Y1546124D01*
X271685Y1534285D01*
X264616Y1527216D01*
X258561Y1512597D01*
Y1504564D01*
X259961Y1446344D01*
X261425Y1431487D01*
X262238Y1414915D01*
Y1370012D01*
X268358Y1363892D01*
Y1361244D01*
X269503Y1360099D01*
G01X291771Y1611378D02*
Y1612882D01*
X292271Y1613382D01*
X294347D01*
X295285Y1612444D01*
Y1560038D01*
X291873Y1553656D01*
X268097Y1537767D01*
X260382Y1530052D01*
X253251Y1512835D01*
Y1504498D01*
X250494Y1430237D01*
X248888Y1413941D01*
Y1393592D01*
X255008Y1387472D01*
Y1385442D01*
X253863Y1384297D01*
G01X257263D02*
X256118Y1385442D01*
Y1387932D01*
X249998Y1394052D01*
Y1413886D01*
X251602Y1430162D01*
X254361Y1504477D01*
Y1512614D01*
X261323Y1529423D01*
X268805Y1536905D01*
X292722Y1552887D01*
X293896Y1555083D01*
X294302Y1555207D01*
X295222Y1556927D01*
X295099Y1557333D01*
X296395Y1559759D01*
Y1612904D01*
X294807Y1614492D01*
X292271D01*
X291771Y1614992D01*
Y1616496D01*
G01X309094Y1611378D02*
Y1612882D01*
X309594Y1613382D01*
X311670D01*
X312608Y1612444D01*
Y1556508D01*
X305211Y1549111D01*
X273690Y1532261D01*
X266792Y1525362D01*
X261451Y1512466D01*
Y1504599D01*
X262714Y1452081D01*
X267248Y1421533D01*
Y1409640D01*
X266103Y1408495D01*
G01X309094Y1616496D02*
Y1614992D01*
X309594Y1614492D01*
X312130D01*
X313718Y1612904D01*
Y1556048D01*
X305880Y1548209D01*
X274359Y1531359D01*
X267733Y1524733D01*
X262561Y1512245D01*
Y1504613D01*
X263823Y1452176D01*
X268358Y1421615D01*
Y1409640D01*
X269503Y1408495D01*
G01X271580Y107649D02*
X272719Y106510D01*
X275950D01*
X281306Y107576D01*
X288677Y110627D01*
X288921Y111216D01*
X290723Y111962D01*
X291311Y111718D01*
X294051Y112852D01*
X297306Y116107D01*
Y116744D01*
X298686Y118124D01*
X299323D01*
X300701Y119502D01*
Y120139D01*
X302081Y121519D01*
X302718D01*
X304096Y122897D01*
Y123534D01*
X305476Y124914D01*
X306113D01*
X307491Y126292D01*
Y128242D01*
X307041Y128692D01*
Y130642D01*
X307491Y131092D01*
Y136482D01*
X350827Y179818D01*
X355371Y255598D01*
X354606Y291256D01*
X362022Y298672D01*
X402928D01*
X408415Y293185D01*
Y275623D01*
X409054Y274984D01*
X424870D01*
X425422Y275536D01*
Y277932D01*
X424870Y278484D01*
X416290D01*
X415050Y279724D01*
Y283084D01*
X416290Y284324D01*
X424870D01*
X425422Y284876D01*
Y287272D01*
X424870Y287824D01*
X416290D01*
X415110Y289004D01*
Y292402D01*
X416312Y293604D01*
X426434D01*
X432679Y299849D01*
Y303316D01*
X431525Y304470D01*
G01X434925D02*
X433789Y303334D01*
Y299389D01*
X426894Y292494D01*
X416772D01*
X416220Y291942D01*
Y289464D01*
X416750Y288934D01*
X425330D01*
X426532Y287732D01*
Y284416D01*
X425330Y283214D01*
X416750D01*
X416160Y282624D01*
Y280184D01*
X416750Y279594D01*
X425330D01*
X426532Y278392D01*
Y275076D01*
X425330Y273874D01*
X408594D01*
X407305Y275163D01*
Y292725D01*
X402468Y297562D01*
X362482D01*
X355726Y290806D01*
X356482Y255577D01*
X351910Y179331D01*
X308601Y136022D01*
Y125832D01*
X294680Y111911D01*
X281630Y106508D01*
X276060Y105400D01*
X272731D01*
X271580Y104249D01*
G01X317756Y1612166D02*
Y1610662D01*
X318256Y1610162D01*
X320484D01*
X322379Y1608267D01*
Y1553879D01*
X319531Y1551031D01*
X276351Y1527951D01*
X270980Y1522580D01*
X266420Y1511571D01*
Y1504659D01*
X267666Y1452939D01*
X273633Y1422937D01*
X274478Y1414362D01*
Y1394052D01*
X280598Y1387932D01*
Y1385442D01*
X281743Y1384297D01*
G01X317756Y1607048D02*
Y1608552D01*
X318256Y1609052D01*
X320024D01*
X321269Y1607807D01*
Y1554339D01*
X318862Y1551933D01*
X316784Y1550822D01*
X316175Y1551007D01*
X314454Y1550087D01*
X314269Y1549478D01*
X312550Y1548559D01*
X311941Y1548744D01*
X310220Y1547824D01*
X310035Y1547215D01*
X275682Y1528853D01*
X270039Y1523209D01*
X265310Y1511792D01*
Y1504645D01*
X266558Y1452816D01*
X272533Y1422774D01*
X273368Y1414307D01*
Y1393592D01*
X279488Y1387472D01*
Y1385442D01*
X278343Y1384297D01*
G01X293983Y1360099D02*
X292838Y1361244D01*
Y1363892D01*
X286718Y1370012D01*
Y1415617D01*
X273945Y1442619D01*
X271516Y1453430D01*
X270280Y1504708D01*
Y1510799D01*
X274253Y1520391D01*
X278642Y1524780D01*
X289236Y1529168D01*
X321529Y1546429D01*
X326398Y1551298D01*
X326822D01*
X328202Y1552678D01*
Y1553102D01*
X331040Y1555940D01*
Y1612905D01*
X329453Y1614492D01*
X326917D01*
X326417Y1614992D01*
Y1616496D01*
G01Y1611378D02*
Y1612882D01*
X326917Y1613382D01*
X328993D01*
X329930Y1612445D01*
Y1556400D01*
X320860Y1547331D01*
X304811Y1538752D01*
Y1538753D01*
X288761Y1530173D01*
X283515Y1528000D01*
X278013Y1525721D01*
X273312Y1521020D01*
X269170Y1511020D01*
Y1504694D01*
X270408Y1453294D01*
X272888Y1442255D01*
X285608Y1415367D01*
Y1369552D01*
X291728Y1363432D01*
Y1361244D01*
X290583Y1360099D01*
G01X335078Y1612166D02*
Y1610662D01*
X335578Y1610162D01*
X337806D01*
X339701Y1608267D01*
Y1554631D01*
X333854Y1548784D01*
X328827Y1545425D01*
X296173Y1527971D01*
X280772Y1521592D01*
X277463Y1518283D01*
X274040Y1510018D01*
Y1504754D01*
X275262Y1454098D01*
X277666Y1443964D01*
X292838Y1411886D01*
Y1409640D01*
X293983Y1408495D01*
G01X335078Y1607048D02*
Y1608552D01*
X335578Y1609052D01*
X337346D01*
X338591Y1607807D01*
Y1555091D01*
X333146Y1549646D01*
X328255Y1546379D01*
X322859Y1543495D01*
X322250Y1543680D01*
X320529Y1542759D01*
X320344Y1542150D01*
X318625Y1541231D01*
X318016Y1541416D01*
X316295Y1540496D01*
X316110Y1539887D01*
X311977Y1537678D01*
Y1537679D01*
X295698Y1528976D01*
X280143Y1522533D01*
X276522Y1518912D01*
X272930Y1510239D01*
Y1504740D01*
X274155Y1453955D01*
X276612Y1443594D01*
X291728Y1411636D01*
Y1409640D01*
X290583Y1408495D01*
G01X306223Y1384297D02*
X305078Y1385442D01*
Y1387932D01*
X298958Y1394052D01*
Y1409578D01*
X280893Y1447770D01*
X278982Y1455819D01*
X277800Y1504800D01*
Y1509268D01*
X280651Y1516152D01*
Y1516153D01*
X282901Y1518403D01*
X299166Y1525140D01*
X338636Y1546236D01*
X343498Y1551098D01*
X343922D01*
X345302Y1552478D01*
Y1552902D01*
X348363Y1555963D01*
Y1612905D01*
X346776Y1614492D01*
X344240D01*
X343740Y1614992D01*
Y1616496D01*
G01Y1611378D02*
Y1612882D01*
X344240Y1613382D01*
X346316D01*
X347253Y1612445D01*
Y1556423D01*
X337967Y1547138D01*
X318329Y1536642D01*
Y1536643D01*
X298691Y1526145D01*
X282272Y1519344D01*
X279710Y1516782D01*
X276690Y1509489D01*
Y1504786D01*
X277875Y1455676D01*
X279839Y1447400D01*
X297848Y1409328D01*
Y1393592D01*
X303968Y1387472D01*
Y1385442D01*
X302823Y1384297D01*
G01X315063Y1360099D02*
X316208Y1361244D01*
Y1363432D01*
X310088Y1369552D01*
Y1411174D01*
X301661Y1426051D01*
X301184Y1426183D01*
X300222Y1427881D01*
X300354Y1428358D01*
X299393Y1430054D01*
X298916Y1430186D01*
X297954Y1431884D01*
X298086Y1432361D01*
X297125Y1434057D01*
X296647Y1434189D01*
X295685Y1435886D01*
X295817Y1436363D01*
X286623Y1452593D01*
Y1505606D01*
X285539Y1506690D01*
X283610D01*
X283110Y1506190D01*
Y1504685D01*
G01Y1509804D02*
Y1508300D01*
X283610Y1507800D01*
X285999D01*
X287733Y1506066D01*
Y1452886D01*
X311198Y1411467D01*
Y1370012D01*
X317318Y1363892D01*
Y1361244D01*
X318463Y1360099D01*
G01X315063Y1408495D02*
X316208Y1409640D01*
Y1414060D01*
X306100Y1431903D01*
X305691Y1432016D01*
X304729Y1433714D01*
X304842Y1434123D01*
X303881Y1435819D01*
X303404Y1435951D01*
X302442Y1437648D01*
X302574Y1438125D01*
X295285Y1450991D01*
Y1510082D01*
X294347Y1511020D01*
X292271D01*
X291771Y1510520D01*
Y1509016D01*
G01Y1514134D02*
Y1512630D01*
X292271Y1512130D01*
X294807D01*
X296395Y1510542D01*
Y1451284D01*
X317318Y1414353D01*
Y1409640D01*
X318463Y1408495D01*
G01X327303Y1384297D02*
X328448Y1385442D01*
Y1387472D01*
X322328Y1393592D01*
Y1413150D01*
X314222Y1430288D01*
X313756Y1430455D01*
X312922Y1432219D01*
X313088Y1432685D01*
X312255Y1434447D01*
X311789Y1434614D01*
X310954Y1436378D01*
X311121Y1436844D01*
X310288Y1438606D01*
X309822Y1438773D01*
X308987Y1440537D01*
X309154Y1441003D01*
X303946Y1452013D01*
Y1505606D01*
X302862Y1506690D01*
X300933D01*
X300433Y1506190D01*
Y1504685D01*
G01Y1509804D02*
Y1508300D01*
X300933Y1507800D01*
X303322D01*
X305056Y1506066D01*
Y1452263D01*
X323438Y1413400D01*
Y1394052D01*
X329558Y1387932D01*
Y1385442D01*
X330703Y1384297D01*
G01X309094Y1514134D02*
Y1512630D01*
X309594Y1512130D01*
X312130D01*
X313718Y1510542D01*
Y1453961D01*
X329512Y1420567D01*
X335678Y1411338D01*
Y1370012D01*
X341798Y1363892D01*
Y1361244D01*
X342943Y1360099D01*
G01X309094Y1509016D02*
Y1510520D01*
X309594Y1511020D01*
X311670D01*
X312608Y1510082D01*
Y1453711D01*
X318356Y1441557D01*
X318189Y1441090D01*
X319024Y1439327D01*
X319490Y1439160D01*
X320323Y1437398D01*
X320156Y1436932D01*
X320991Y1435168D01*
X321457Y1435001D01*
X328543Y1420018D01*
X334568Y1411001D01*
Y1369552D01*
X340688Y1363432D01*
Y1361244D01*
X339543Y1360099D01*
G01X317756Y1509804D02*
Y1508300D01*
X318256Y1507800D01*
X320645D01*
X322379Y1506066D01*
Y1454873D01*
X341798Y1413816D01*
Y1409640D01*
X342943Y1408495D01*
G01X339543D02*
X340688Y1409640D01*
Y1413566D01*
X332693Y1430469D01*
X332227Y1430636D01*
X331393Y1432400D01*
X331559Y1432866D01*
X330726Y1434628D01*
X330260Y1434795D01*
X329426Y1436559D01*
X329592Y1437025D01*
X328759Y1438787D01*
X328293Y1438954D01*
X327458Y1440718D01*
X327625Y1441184D01*
X321269Y1454623D01*
Y1505606D01*
X320185Y1506690D01*
X318256D01*
X317756Y1506190D01*
Y1504685D01*
G01X326417Y1514134D02*
Y1512630D01*
X326917Y1512130D01*
X329453D01*
X331040Y1510543D01*
Y1451060D01*
X347918Y1415376D01*
Y1394052D01*
X354038Y1387932D01*
Y1385442D01*
X355183Y1384297D01*
G01X326417Y1509016D02*
Y1510520D01*
X326917Y1511020D01*
X328993D01*
X329930Y1510083D01*
Y1450810D01*
X333228Y1443838D01*
X333061Y1443372D01*
X333896Y1441608D01*
X334362Y1441441D01*
X335195Y1439679D01*
X335028Y1439213D01*
X335863Y1437449D01*
X336329Y1437282D01*
X346808Y1415126D01*
Y1393592D01*
X352928Y1387472D01*
Y1385442D01*
X351783Y1384297D01*
G01X335078Y1509804D02*
Y1508300D01*
X335578Y1507800D01*
X337967D01*
X339701Y1506066D01*
Y1453809D01*
X360158Y1410557D01*
Y1370012D01*
X366278Y1363892D01*
Y1361244D01*
X367423Y1360099D01*
G01X364023D02*
X365168Y1361244D01*
Y1363432D01*
X359048Y1369552D01*
Y1410307D01*
X348243Y1433151D01*
X347777Y1433318D01*
X346943Y1435082D01*
X347109Y1435548D01*
X346276Y1437310D01*
X345810Y1437477D01*
X344976Y1439241D01*
X345142Y1439707D01*
X344309Y1441469D01*
X343843Y1441636D01*
X343009Y1443400D01*
X343175Y1443866D01*
X338591Y1453559D01*
Y1505606D01*
X337507Y1506690D01*
X335578D01*
X335078Y1506190D01*
Y1504685D01*
G01X364023Y1408495D02*
X365168Y1409640D01*
Y1413046D01*
X352741Y1439321D01*
X352142Y1439535D01*
X351307Y1441299D01*
X351521Y1441898D01*
X347253Y1450923D01*
Y1510083D01*
X346316Y1511020D01*
X344240D01*
X343740Y1510520D01*
Y1509016D01*
G01Y1514134D02*
Y1512630D01*
X344240Y1512130D01*
X346776D01*
X348363Y1510543D01*
Y1451173D01*
X366278Y1413296D01*
Y1409640D01*
X367423Y1408495D01*
G01X373942Y104249D02*
X375072Y105379D01*
X381248D01*
X382237Y106368D01*
X387039D01*
X392054Y111383D01*
X397818D01*
X408608Y122173D01*
Y141358D01*
X426100Y174064D01*
Y206400D01*
X434080Y214380D01*
Y217566D01*
X425297Y226349D01*
Y227187D01*
X426998Y228888D01*
X427836D01*
X437059Y219665D01*
X438773D01*
X441129Y222021D01*
Y223735D01*
X431876Y232988D01*
Y233808D01*
X433595Y235527D01*
X434415D01*
X443668Y226274D01*
X445382D01*
X447738Y228630D01*
Y230344D01*
X438485Y239597D01*
Y240417D01*
X440204Y242136D01*
X441024D01*
X450277Y232883D01*
X451991D01*
X454347Y235239D01*
Y236953D01*
X445094Y246206D01*
Y246984D01*
X446825Y248715D01*
X447621D01*
X451614Y244722D01*
X453821D01*
X463789Y254690D01*
X465126D01*
X487416Y276980D01*
Y309954D01*
X470316Y327054D01*
X462079D01*
X460950Y328183D01*
Y328185D01*
G01X373942Y107649D02*
X375102Y106489D01*
X380788D01*
X381777Y107478D01*
X386579D01*
X391594Y112493D01*
X397358D01*
X407498Y122633D01*
Y127237D01*
X407048Y127687D01*
Y129637D01*
X407498Y130087D01*
Y132037D01*
X407048Y132487D01*
Y134437D01*
X407498Y134887D01*
Y136837D01*
X407048Y137287D01*
Y139237D01*
X407498Y139687D01*
Y141637D01*
X408417Y143356D01*
X408233Y143965D01*
X409153Y145686D01*
X409762Y145870D01*
X410681Y147589D01*
X410497Y148198D01*
X411417Y149919D01*
X412026Y150103D01*
X412945Y151822D01*
X412761Y152431D01*
X413681Y154152D01*
X414290Y154336D01*
X415209Y156055D01*
X415025Y156664D01*
X415945Y158385D01*
X416554Y158569D01*
X417473Y160288D01*
X417289Y160897D01*
X418209Y162618D01*
X418818Y162802D01*
X419737Y164521D01*
X419552Y165130D01*
X420473Y166851D01*
X421082Y167035D01*
X421081D01*
X424990Y174343D01*
Y206860D01*
X432970Y214840D01*
Y217106D01*
X424187Y225889D01*
Y227647D01*
X426538Y229998D01*
X428296D01*
X437519Y220775D01*
X438313D01*
X440019Y222481D01*
Y223275D01*
X430766Y232528D01*
Y234268D01*
X433135Y236637D01*
X434875D01*
X444128Y227384D01*
X444922D01*
X446628Y229090D01*
Y229884D01*
X437375Y239137D01*
Y240877D01*
X439744Y243246D01*
X441484D01*
X450737Y233993D01*
X451531D01*
X453237Y235699D01*
Y236493D01*
X443984Y245746D01*
Y247444D01*
X446365Y249825D01*
X448081D01*
X452074Y245832D01*
X453361D01*
X463329Y255800D01*
X464666D01*
X486306Y277440D01*
Y309494D01*
X469856Y325944D01*
X462109D01*
X460950Y324785D01*
G01X440402Y1360099D02*
X441547Y1361244D01*
Y1363324D01*
X435037Y1369834D01*
X422591Y1437651D01*
X422092Y1512397D01*
X425742Y1525547D01*
X432401Y1535455D01*
X435873Y1538286D01*
X435924Y1538779D01*
X437436Y1540012D01*
X437928Y1539962D01*
X439439Y1541194D01*
X439489Y1541687D01*
X441001Y1542920D01*
X441493Y1542870D01*
X443004Y1544102D01*
X443054Y1544594D01*
X444566Y1545827D01*
X445058Y1545777D01*
X449217Y1549169D01*
X458035Y1552822D01*
X459783Y1554570D01*
Y1606980D01*
X457711Y1609052D01*
X456839D01*
X456339Y1608552D01*
Y1607048D01*
G01Y1612166D02*
Y1610662D01*
X456839Y1610162D01*
X458171D01*
X460893Y1607440D01*
Y1554110D01*
X458664Y1551881D01*
X449793Y1548205D01*
X433231Y1534698D01*
X426764Y1525077D01*
X423204Y1512249D01*
X423701Y1437756D01*
X436067Y1370375D01*
X442657Y1363784D01*
Y1361244D01*
X443802Y1360099D01*
G01X431524Y370309D02*
X432669Y371454D01*
Y373769D01*
X434285Y375385D01*
X440819D01*
X458904Y357300D01*
X474360D01*
X507752Y323908D01*
X525841D01*
X535146Y314603D01*
X717525D01*
X756569Y298431D01*
X811635Y243365D01*
X812420Y235769D01*
X810196Y198698D01*
X811257Y168942D01*
X834800Y145399D01*
Y106799D01*
X833401Y105400D01*
X832180D01*
X831029Y104249D01*
G01Y107649D02*
X832168Y106510D01*
X832941D01*
X833690Y107259D01*
Y109209D01*
X833240Y109659D01*
Y111609D01*
X833690Y112059D01*
Y114009D01*
X833240Y114459D01*
Y116409D01*
X833690Y116859D01*
Y118809D01*
X833240Y119259D01*
Y121209D01*
X833690Y121659D01*
Y123609D01*
X833240Y124059D01*
Y126009D01*
X833690Y126459D01*
Y128409D01*
X833240Y128859D01*
Y130809D01*
X833690Y131259D01*
Y133209D01*
X833240Y133659D01*
Y135609D01*
X833690Y136059D01*
Y138009D01*
X833240Y138459D01*
Y140409D01*
X833690Y140859D01*
Y144939D01*
X832312Y146317D01*
X831675D01*
X830295Y147697D01*
Y148334D01*
X828917Y149712D01*
X828280D01*
X826900Y151092D01*
Y151729D01*
X810163Y168466D01*
X809084Y198712D01*
X811306Y235745D01*
X810571Y242859D01*
X755940Y297490D01*
X717304Y313493D01*
X715354D01*
X714904Y313043D01*
X712954D01*
X712504Y313493D01*
X710554D01*
X710104Y313043D01*
X708154D01*
X707704Y313493D01*
X705754D01*
X705304Y313043D01*
X703354D01*
X702904Y313493D01*
X700954D01*
X700504Y313043D01*
X698554D01*
X698104Y313493D01*
X696154D01*
X695704Y313043D01*
X693754D01*
X693304Y313493D01*
X534686D01*
X525381Y322798D01*
X507292D01*
X473900Y356190D01*
X458444D01*
X440359Y374275D01*
X434745D01*
X433779Y373309D01*
Y371454D01*
X434924Y370309D01*
G01X625921Y1260091D02*
Y1260292D01*
X621750Y1264463D01*
X611847Y1270399D01*
X579761Y1283690D01*
X574074Y1284819D01*
X555909D01*
X500583Y1307736D01*
X446623Y1336580D01*
X443393Y1339655D01*
X441547Y1342734D01*
Y1347042D01*
X440402Y1348187D01*
G01X465000Y1611378D02*
Y1612882D01*
X465500Y1613382D01*
X466372D01*
X468444Y1611310D01*
Y1555916D01*
X462489Y1549961D01*
X449763Y1544689D01*
X435182Y1532798D01*
X429255Y1523976D01*
X425968Y1512139D01*
X426446Y1440449D01*
X447610Y1393719D01*
X453787Y1387542D01*
Y1385442D01*
X452642Y1384297D01*
G01X465000Y1616496D02*
Y1614992D01*
X465500Y1614492D01*
X466832D01*
X469554Y1611770D01*
Y1555456D01*
X463118Y1549020D01*
X450339Y1543725D01*
X436012Y1532041D01*
X430277Y1523506D01*
X427080Y1511991D01*
X427555Y1440692D01*
X448538Y1394361D01*
X454897Y1388002D01*
Y1385442D01*
X456042Y1384297D01*
G01X473662Y1612166D02*
Y1610662D01*
X474162Y1610162D01*
X475494D01*
X478216Y1607440D01*
Y1555002D01*
X470832Y1547618D01*
X451155Y1539465D01*
X439181Y1529701D01*
X433919Y1521869D01*
X430960Y1511215D01*
X431410Y1443556D01*
X433557Y1439281D01*
X459837Y1412707D01*
X461017Y1409837D01*
Y1370025D01*
X467137Y1363905D01*
Y1361244D01*
X468282Y1360099D01*
G01X464882D02*
X466027Y1361244D01*
Y1363445D01*
X459907Y1369565D01*
Y1409617D01*
X458893Y1412082D01*
X432643Y1438625D01*
X430301Y1443289D01*
X429848Y1511363D01*
X432897Y1522339D01*
X438260Y1530321D01*
X438259Y1530322D01*
X438351Y1530458D01*
X444465Y1535443D01*
Y1535444D01*
X450579Y1540429D01*
X460689Y1544617D01*
X460879Y1545075D01*
X462681Y1545822D01*
X463139Y1545633D01*
X464940Y1546379D01*
X465129Y1546836D01*
X466932Y1547583D01*
X467389Y1547394D01*
X470203Y1548559D01*
X472185Y1550541D01*
Y1551036D01*
X473564Y1552415D01*
X474059D01*
X477106Y1555462D01*
Y1606980D01*
X475034Y1609052D01*
X474162D01*
X473662Y1608552D01*
Y1607048D01*
G01X482323Y1611378D02*
Y1612882D01*
X482823Y1613382D01*
X483695D01*
X485767Y1611310D01*
Y1557045D01*
X475134Y1546412D01*
Y1546411D01*
X452411Y1536998D01*
X446966Y1532558D01*
X446967D01*
X441521Y1528118D01*
X436539Y1520702D01*
X433727Y1510579D01*
X434166Y1444812D01*
X436203Y1440755D01*
X465650Y1412554D01*
X466027Y1411671D01*
Y1409640D01*
X464882Y1408495D01*
G01X468282D02*
X467137Y1409640D01*
Y1411898D01*
X466582Y1413199D01*
X437110Y1441425D01*
X435275Y1445079D01*
X434839Y1510431D01*
X437561Y1520232D01*
X442351Y1527361D01*
X452987Y1536034D01*
X475558Y1545384D01*
X475560Y1545386D01*
X475678D01*
X481944Y1551652D01*
X482368D01*
X483748Y1553032D01*
Y1553456D01*
X486877Y1556585D01*
Y1611770D01*
X484155Y1614492D01*
X482823D01*
X482323Y1614992D01*
Y1616496D01*
G01X490985Y1612166D02*
Y1610662D01*
X491485Y1610162D01*
X492817D01*
X495539Y1607440D01*
Y1554350D01*
X492528Y1551339D01*
X478678Y1542084D01*
X453812Y1531783D01*
X445521Y1525022D01*
X441203Y1518595D01*
X438718Y1509646D01*
X439139Y1447091D01*
X440653Y1444077D01*
X470996Y1415602D01*
X473257Y1410379D01*
Y1394134D01*
X479377Y1388014D01*
Y1385442D01*
X480522Y1384297D01*
G01X490985Y1607048D02*
Y1608552D01*
X491485Y1609052D01*
X492357D01*
X494429Y1606980D01*
Y1554810D01*
X491820Y1552201D01*
X489212Y1550458D01*
X488587Y1550582D01*
X486965Y1549498D01*
X486841Y1548874D01*
X485220Y1547791D01*
X484596Y1547915D01*
X482973Y1546831D01*
X482849Y1546206D01*
X478152Y1543068D01*
X453236Y1532747D01*
X448963Y1529263D01*
X448964D01*
X444691Y1525779D01*
X440181Y1519065D01*
X437606Y1509794D01*
X438030Y1446824D01*
X439749Y1443402D01*
X470068Y1414949D01*
X472147Y1410149D01*
Y1393674D01*
X478267Y1387554D01*
Y1385442D01*
X477122Y1384297D01*
G01X499646Y1611378D02*
Y1612882D01*
X500146Y1613382D01*
X501018D01*
X503090Y1611310D01*
Y1557344D01*
X496982Y1550603D01*
X481552Y1540293D01*
X455081Y1529326D01*
X447860Y1523437D01*
X443823Y1517428D01*
X441486Y1509014D01*
X441892Y1448449D01*
X443653Y1444943D01*
X482854Y1413033D01*
X484387Y1409808D01*
Y1369263D01*
X490507Y1363143D01*
Y1361244D01*
X489362Y1360099D01*
G01X627031Y1260091D02*
Y1260752D01*
X622438Y1265345D01*
X612348Y1271394D01*
X580085Y1284758D01*
X574184Y1285929D01*
X556130D01*
X501058Y1308741D01*
X447280Y1337489D01*
X445773Y1338922D01*
Y1338923D01*
X444268Y1340356D01*
X442657Y1343042D01*
Y1347042D01*
X443802Y1348187D01*
G01X629661Y1260091D02*
Y1262098D01*
X624551Y1267208D01*
X613513Y1273825D01*
X605296Y1277230D01*
X605295Y1277229D01*
X597077Y1280633D01*
X597078Y1280634D01*
X580641Y1287441D01*
X573352Y1288888D01*
X555950D01*
X507531Y1308944D01*
X473985Y1326875D01*
X468762Y1331847D01*
X468761D01*
X463540Y1336816D01*
X460732Y1341501D01*
X459907Y1344483D01*
Y1362287D01*
X453787Y1368407D01*
Y1371240D01*
X452642Y1372385D01*
G01X630771Y1260091D02*
Y1262558D01*
X625239Y1268090D01*
X614014Y1274820D01*
X580965Y1288509D01*
X573462Y1289998D01*
X556171D01*
X508006Y1309949D01*
X474642Y1327784D01*
X464415Y1337517D01*
X461762Y1341942D01*
X461017Y1344634D01*
Y1362747D01*
X454897Y1368867D01*
Y1371240D01*
X456042Y1372385D01*
G01X505002Y1384297D02*
X503857Y1385442D01*
Y1388373D01*
X497737Y1394493D01*
Y1410744D01*
X493981Y1418287D01*
X451269Y1450537D01*
X450727Y1451617D01*
X450357Y1507298D01*
X452129Y1513684D01*
X455026Y1517995D01*
X457284Y1519838D01*
X457285D01*
X459544Y1521681D01*
X493024Y1535553D01*
X507487Y1545218D01*
X507904Y1545136D01*
X509526Y1546220D01*
X509609Y1546636D01*
X514177Y1549689D01*
X520339Y1555851D01*
X521523Y1558710D01*
Y1611770D01*
X518801Y1614492D01*
X517469D01*
X516969Y1614992D01*
Y1616496D01*
G01Y1611378D02*
Y1612882D01*
X517469Y1613382D01*
X518341D01*
X520413Y1611310D01*
Y1558931D01*
X519398Y1556480D01*
X513469Y1550551D01*
X492498Y1536537D01*
X458968Y1522645D01*
X454196Y1518752D01*
X451107Y1514154D01*
X449245Y1507446D01*
X449618Y1451350D01*
X450393Y1449807D01*
X493104Y1417558D01*
X496627Y1410482D01*
Y1394033D01*
X502747Y1387913D01*
Y1385442D01*
X501602Y1384297D01*
G01X508307Y1612166D02*
Y1610662D01*
X508807Y1610162D01*
X510139D01*
X512861Y1607440D01*
Y1555939D01*
X511366Y1553142D01*
X488528Y1537882D01*
X457713Y1525114D01*
X451859Y1520340D01*
X448487Y1515321D01*
X446478Y1508084D01*
X446654Y1481692D01*
Y1481616D01*
X446865Y1449953D01*
X447878Y1447935D01*
X489216Y1416364D01*
X491617Y1411509D01*
Y1409640D01*
X492762Y1408495D01*
G01X508307Y1607048D02*
Y1608552D01*
X508807Y1609052D01*
X509679D01*
X511751Y1606980D01*
Y1556218D01*
X510517Y1553911D01*
X505367Y1550470D01*
X504743Y1550594D01*
X503121Y1549510D01*
X502996Y1548885D01*
X501375Y1547802D01*
X500751Y1547926D01*
X499129Y1546842D01*
X499004Y1546218D01*
X488002Y1538866D01*
X457137Y1526078D01*
X454083Y1523588D01*
Y1523587D01*
X451029Y1521097D01*
X449250Y1518450D01*
X449251D01*
X447465Y1515791D01*
X445366Y1508232D01*
X445756Y1449686D01*
X447001Y1447208D01*
X488336Y1415639D01*
X490507Y1411249D01*
Y1409640D01*
X489362Y1408495D01*
G01X492762Y1360099D02*
X491617Y1361244D01*
Y1363603D01*
X485497Y1369723D01*
Y1410059D01*
X483749Y1413736D01*
X444539Y1445654D01*
X443001Y1448716D01*
X442598Y1508866D01*
X444845Y1516958D01*
X448690Y1522680D01*
X455657Y1528362D01*
X482078Y1539309D01*
X497713Y1549756D01*
X500616Y1552960D01*
X501040Y1552981D01*
X502351Y1554427D01*
X502330Y1554851D01*
X504200Y1556915D01*
Y1611770D01*
X501478Y1614492D01*
X500146D01*
X499646Y1614992D01*
Y1616496D01*
G01X456339Y1489331D02*
Y1490835D01*
X456839Y1491335D01*
X457711D01*
X459783Y1489263D01*
Y1455223D01*
X461811Y1450869D01*
X498748Y1419863D01*
X498797Y1419299D01*
X500292Y1418045D01*
X500855Y1418094D01*
X502348Y1416841D01*
X502397Y1416277D01*
X503892Y1415022D01*
X504455Y1415072D01*
X507675Y1412369D01*
X508867Y1409813D01*
Y1403625D01*
X508600Y1403358D01*
Y1401042D01*
X508867Y1400775D01*
Y1369979D01*
X514987Y1363859D01*
Y1361244D01*
X513842Y1360099D01*
G01X456339Y1494449D02*
Y1492945D01*
X456839Y1492445D01*
X458171D01*
X460893Y1489723D01*
Y1455470D01*
X460894Y1455469D01*
X462714Y1451561D01*
X508578Y1413062D01*
X509977Y1410060D01*
Y1370439D01*
X516097Y1364319D01*
Y1361244D01*
X517242Y1360099D01*
G01X463950Y332659D02*
X465094Y333803D01*
X469477D01*
X491090Y312190D01*
Y302010D01*
X492444Y300656D01*
X505064D01*
X505737Y299983D01*
Y295808D01*
X505185Y295256D01*
X492329D01*
X491179Y294106D01*
Y290776D01*
X492539Y289416D01*
X505185D01*
X505737Y288864D01*
Y286468D01*
X505185Y285916D01*
X492329D01*
X491179Y284766D01*
Y281436D01*
X492539Y280076D01*
X505185D01*
X505737Y279524D01*
Y277128D01*
X505185Y276576D01*
X492329D01*
X491179Y275426D01*
Y272096D01*
X492539Y270736D01*
X505185D01*
X505737Y270184D01*
Y267788D01*
X505185Y267236D01*
X492339D01*
X491146Y266043D01*
Y262727D01*
X492417Y261456D01*
X504973D01*
X505590Y260839D01*
Y167740D01*
X511403Y161927D01*
Y161290D01*
X512783Y159910D01*
X513420D01*
X514798Y158532D01*
Y157895D01*
X516178Y156515D01*
X516815D01*
X518193Y155137D01*
Y154500D01*
X519573Y153120D01*
X520210D01*
X521588Y151742D01*
Y143442D01*
X526590Y138440D01*
Y135961D01*
X526140Y135511D01*
Y133561D01*
X526590Y133111D01*
Y131161D01*
X526140Y130711D01*
Y128761D01*
X526590Y128311D01*
Y126361D01*
X526140Y125911D01*
Y123961D01*
X526590Y123511D01*
Y121561D01*
X526140Y121111D01*
Y119161D01*
X526590Y118711D01*
Y116761D01*
X526140Y116311D01*
Y114361D01*
X526590Y113911D01*
Y111961D01*
X526140Y111511D01*
Y109561D01*
X526590Y109111D01*
Y107161D01*
X525929Y106500D01*
X525092D01*
X523943Y107649D01*
G01Y104249D02*
X525084Y105390D01*
X526389D01*
X527700Y106701D01*
Y138900D01*
X522698Y143902D01*
Y152202D01*
X506700Y168200D01*
Y261299D01*
X505433Y262566D01*
X492877D01*
X492256Y263187D01*
Y265583D01*
X492799Y266126D01*
X505645D01*
X506847Y267328D01*
Y270644D01*
X505645Y271846D01*
X492999D01*
X492289Y272556D01*
Y274966D01*
X492789Y275466D01*
X505645D01*
X506847Y276668D01*
Y279984D01*
X505645Y281186D01*
X492999D01*
X492289Y281896D01*
Y284306D01*
X492789Y284806D01*
X505645D01*
X506847Y286008D01*
Y289324D01*
X505645Y290526D01*
X492999D01*
X492289Y291236D01*
Y293646D01*
X492789Y294146D01*
X505645D01*
X506847Y295348D01*
Y300443D01*
X505524Y301766D01*
X492904D01*
X492200Y302470D01*
Y312650D01*
X469937Y334913D01*
X465096D01*
X463950Y336059D01*
G01X626305Y104249D02*
X627465Y105409D01*
X628862D01*
X630013Y106560D01*
Y143624D01*
X622054Y151583D01*
Y155215D01*
X606518Y170752D01*
X605566Y200138D01*
X608034Y241305D01*
X607355Y250086D01*
X585209Y272232D01*
X583492D01*
X579183Y267923D01*
X578347D01*
X576641Y269629D01*
Y270465D01*
X580950Y274774D01*
Y276490D01*
X578599Y278841D01*
X576883D01*
X572571Y274529D01*
X571753D01*
X570029Y276253D01*
Y277071D01*
X574341Y281383D01*
Y283099D01*
X571990Y285450D01*
X570274D01*
X565962Y281138D01*
X565186D01*
X563450Y282874D01*
Y283668D01*
X567662Y287880D01*
Y289508D01*
X550649Y306521D01*
X508311D01*
X475657Y339175D01*
X469096D01*
X465469Y342802D01*
X462079D01*
X460950Y343931D01*
Y343933D01*
G01X626305Y107649D02*
X627435Y106519D01*
X628402D01*
X628903Y107020D01*
Y109275D01*
X628453Y109725D01*
Y111675D01*
X628903Y112125D01*
Y114075D01*
X628453Y114525D01*
Y116475D01*
X628903Y116925D01*
Y118875D01*
X628453Y119325D01*
Y121275D01*
X628903Y121725D01*
Y123675D01*
X628453Y124125D01*
Y126075D01*
X628903Y126525D01*
Y128475D01*
X628453Y128925D01*
Y130875D01*
X628903Y131325D01*
Y133275D01*
X628453Y133725D01*
Y135675D01*
X628903Y136125D01*
Y138075D01*
X628453Y138525D01*
Y140475D01*
X628903Y140925D01*
Y143164D01*
X627525Y144542D01*
X626888D01*
X625508Y145922D01*
Y146559D01*
X620944Y151123D01*
Y154755D01*
X619566Y156133D01*
X618929D01*
X617549Y157513D01*
Y158150D01*
X605422Y170277D01*
X604454Y200153D01*
X606921Y241295D01*
X606279Y249591D01*
X584749Y271122D01*
X583952D01*
X579643Y266813D01*
X577887D01*
X575531Y269169D01*
Y270925D01*
X579840Y275234D01*
Y276030D01*
X578139Y277731D01*
X577343D01*
X573031Y273419D01*
X571293D01*
X568919Y275793D01*
Y277531D01*
X573231Y281843D01*
Y282639D01*
X571530Y284340D01*
X570734D01*
X566422Y280028D01*
X564726D01*
X562340Y282414D01*
Y284128D01*
X566552Y288340D01*
Y289048D01*
X550189Y305411D01*
X507851D01*
X475197Y338065D01*
X468636D01*
X465009Y341692D01*
X462109D01*
X460950Y340533D01*
G01X728667Y104249D02*
X729827Y105409D01*
X731096D01*
X732338Y106651D01*
Y141263D01*
X729387Y144214D01*
Y149996D01*
X715808Y163576D01*
X715807D01*
X709415Y169968D01*
X708009Y173206D01*
X707394Y191189D01*
X707363Y191217D01*
X710002Y235216D01*
X708537Y244563D01*
X645918Y307182D01*
X588229D01*
X584907Y310504D01*
X528966D01*
X520235Y319235D01*
X502523D01*
X477512Y344246D01*
X471725D01*
X468187Y347784D01*
Y349112D01*
X466653Y350646D01*
X465109D01*
X463950Y351805D01*
Y351807D01*
G01X728667Y107649D02*
X729797Y106519D01*
X730636D01*
X731228Y107111D01*
Y109061D01*
X730778Y109511D01*
Y111461D01*
X731228Y111911D01*
Y113861D01*
X730778Y114311D01*
Y116261D01*
X731228Y116711D01*
Y118661D01*
X730778Y119111D01*
Y121061D01*
X731228Y121511D01*
Y123461D01*
X730778Y123911D01*
Y125861D01*
X731228Y126311D01*
Y128261D01*
X730778Y128711D01*
Y130661D01*
X731228Y131111D01*
Y133061D01*
X730778Y133511D01*
Y135461D01*
X731228Y135911D01*
Y140803D01*
X728277Y143754D01*
Y149536D01*
X726899Y150914D01*
X726262D01*
X724882Y152294D01*
Y152931D01*
X723504Y154309D01*
X722867D01*
X721487Y155689D01*
Y156326D01*
X720109Y157704D01*
X719472D01*
X718092Y159084D01*
Y159721D01*
X716714Y161099D01*
X716077D01*
X714697Y162479D01*
Y163116D01*
X708481Y169332D01*
X706906Y172957D01*
X706281Y191231D01*
X706283Y191257D01*
X706259Y191283D01*
X706255Y191284D01*
X708886Y235163D01*
X707496Y244034D01*
X645458Y306072D01*
X587769D01*
X584447Y309394D01*
X528506D01*
X519775Y318125D01*
X502063D01*
X477052Y343136D01*
X471265D01*
X467077Y347324D01*
Y348652D01*
X466193Y349536D01*
X465079D01*
X463950Y348407D01*
G01X633402Y1260091D02*
Y1263721D01*
X626896Y1270227D01*
X615179Y1277251D01*
X581524Y1291191D01*
X573914Y1292702D01*
X556606D01*
X509167Y1312352D01*
X494564Y1320157D01*
X477400Y1331627D01*
X466027Y1343000D01*
Y1347042D01*
X464882Y1348187D01*
G01X638252Y1260091D02*
Y1265786D01*
X629881Y1274157D01*
X617346Y1281672D01*
X600049Y1288836D01*
Y1288837D01*
X582727Y1296011D01*
X574255Y1297692D01*
X557323D01*
X511592Y1316635D01*
X481042Y1337048D01*
X473257Y1344833D01*
Y1387362D01*
X467137Y1393482D01*
Y1395438D01*
X468282Y1396583D01*
G01X637142Y1260091D02*
Y1265326D01*
X629193Y1273275D01*
X616845Y1280677D01*
X582403Y1294943D01*
X578275Y1295761D01*
Y1295762D01*
X574145Y1296582D01*
X557102D01*
X511066Y1315651D01*
X480334Y1336186D01*
X472147Y1344373D01*
Y1386902D01*
X466027Y1393022D01*
Y1395438D01*
X464882Y1396583D01*
G01X634512Y1260091D02*
Y1264181D01*
X627584Y1271109D01*
X615680Y1278246D01*
X598775Y1285247D01*
X598776Y1285248D01*
X581848Y1292259D01*
X574024Y1293812D01*
X556827D01*
X509642Y1313357D01*
X495136Y1321111D01*
X478108Y1332489D01*
X467137Y1343460D01*
Y1347042D01*
X468282Y1348187D01*
G01X517242Y1408495D02*
X516097Y1409640D01*
Y1412114D01*
X515182Y1414067D01*
X470848Y1450966D01*
X469554Y1454017D01*
Y1494054D01*
X466832Y1496776D01*
X465500D01*
X465000Y1497276D01*
Y1498780D01*
G01X513842Y1408495D02*
X514987Y1409640D01*
Y1411866D01*
X514281Y1413371D01*
X503026Y1422739D01*
X502604Y1422700D01*
X501104Y1423949D01*
X501065Y1424371D01*
X469931Y1450285D01*
X468444Y1453791D01*
Y1493594D01*
X466372Y1495666D01*
X465500D01*
X465000Y1495166D01*
Y1493662D01*
G01X473662Y1494449D02*
Y1492945D01*
X474162Y1492445D01*
X475494D01*
X478216Y1489723D01*
Y1452433D01*
X479624Y1449438D01*
X519605Y1416283D01*
X522217Y1410724D01*
Y1394427D01*
X528337Y1388307D01*
Y1385442D01*
X529482Y1384297D01*
G01X526082D02*
X527227Y1385442D01*
Y1387847D01*
X521107Y1393967D01*
Y1410476D01*
X518705Y1415586D01*
X508014Y1424451D01*
X507521Y1424405D01*
X506019Y1425651D01*
X505973Y1426144D01*
X504472Y1427388D01*
X503980Y1427342D01*
X502478Y1428588D01*
X502432Y1429081D01*
X500931Y1430325D01*
X500438Y1430279D01*
X498936Y1431525D01*
X498890Y1432018D01*
X478724Y1448741D01*
X477106Y1452185D01*
Y1489263D01*
X475034Y1491335D01*
X474162D01*
X473662Y1490835D01*
Y1489331D01*
G01X640882Y1260091D02*
Y1267121D01*
X631966Y1276037D01*
X618511Y1284103D01*
X583289Y1298692D01*
X574057Y1300525D01*
X557446D01*
X514935Y1318134D01*
X496383Y1330530D01*
X484387Y1342526D01*
Y1362018D01*
X478267Y1368138D01*
Y1371240D01*
X477122Y1372385D01*
G01X644622Y1260091D02*
Y1268788D01*
X634418Y1278992D01*
X620177Y1287529D01*
X584171Y1302443D01*
X579324Y1303404D01*
Y1303405D01*
X574474Y1304368D01*
X558032D01*
X516830Y1321434D01*
X501421Y1331731D01*
X490507Y1342645D01*
Y1347042D01*
X489362Y1348187D01*
G01X641992Y1260091D02*
Y1267581D01*
X632654Y1276919D01*
X619012Y1285098D01*
X583613Y1299760D01*
X574167Y1301635D01*
X557667D01*
X515461Y1319118D01*
X497091Y1331392D01*
X485497Y1342986D01*
Y1362478D01*
X479377Y1368598D01*
Y1371240D01*
X480522Y1372385D01*
G01X648362Y1260091D02*
Y1270395D01*
X636722Y1282035D01*
X621843Y1290955D01*
X585055Y1306193D01*
X579704Y1307254D01*
Y1307255D01*
X574351Y1308318D01*
X558358D01*
X519924Y1324237D01*
X508854Y1331634D01*
X496627Y1343861D01*
Y1386522D01*
X490507Y1392642D01*
Y1395438D01*
X489362Y1396583D01*
G01X482323Y1498780D02*
Y1497276D01*
X482823Y1496776D01*
X484155D01*
X486877Y1494054D01*
Y1451933D01*
X488973Y1447633D01*
X532824Y1413297D01*
X534457Y1409944D01*
Y1369903D01*
X540577Y1363783D01*
Y1361244D01*
X541722Y1360099D01*
G01X538322D02*
X539467Y1361244D01*
Y1363323D01*
X533347Y1369443D01*
Y1409688D01*
X531937Y1412580D01*
X511488Y1428592D01*
X511067Y1428541D01*
X509530Y1429744D01*
X509479Y1430165D01*
X488087Y1446916D01*
X485767Y1451676D01*
Y1493594D01*
X483695Y1495666D01*
X482823D01*
X482323Y1495166D01*
Y1493662D01*
G01X645732Y1260091D02*
Y1269248D01*
X635106Y1279874D01*
X620678Y1288524D01*
X602598Y1296012D01*
X602599Y1296013D01*
X584495Y1303511D01*
X574584Y1305478D01*
X558253D01*
X517356Y1322418D01*
X502129Y1332593D01*
X491617Y1343105D01*
Y1347042D01*
X492762Y1348187D01*
G01X649472Y1260091D02*
Y1270855D01*
X637410Y1282917D01*
X622344Y1291950D01*
X603873Y1299600D01*
X603874Y1299601D01*
X585379Y1307261D01*
X574461Y1309428D01*
X558579D01*
X520450Y1325221D01*
X509562Y1332496D01*
X497737Y1344321D01*
Y1386982D01*
X491617Y1393102D01*
Y1395438D01*
X492762Y1396583D01*
G01X653212Y1260091D02*
Y1272536D01*
X639974Y1285774D01*
X623841Y1295446D01*
X586516Y1310906D01*
X574672Y1313257D01*
X559198D01*
X522525Y1328447D01*
X509977Y1340995D01*
Y1362613D01*
X503857Y1368733D01*
Y1371240D01*
X505002Y1372385D01*
G01X652102Y1260091D02*
Y1272076D01*
X639286Y1284892D01*
X623340Y1294451D01*
X586192Y1309838D01*
X574562Y1312147D01*
X558977D01*
X521896Y1327506D01*
X508867Y1340535D01*
Y1362153D01*
X502747Y1368273D01*
Y1371240D01*
X501602Y1372385D01*
G01X553962Y1384297D02*
X552817Y1385442D01*
Y1388004D01*
X546697Y1394124D01*
Y1412379D01*
X543617Y1418671D01*
Y1418672D01*
X543504Y1418902D01*
X506640Y1447529D01*
X504200Y1452831D01*
Y1494054D01*
X501478Y1496776D01*
X500146D01*
X499646Y1497276D01*
Y1498780D01*
G01Y1493662D02*
Y1495166D01*
X500146Y1495666D01*
X501018D01*
X503090Y1493594D01*
Y1452587D01*
X505744Y1446818D01*
X517438Y1437737D01*
X517488Y1437345D01*
X519029Y1436148D01*
X519422Y1436197D01*
X542620Y1418183D01*
X545587Y1412121D01*
Y1393664D01*
X551707Y1387544D01*
Y1385442D01*
X550562Y1384297D01*
G01X490985Y1494449D02*
Y1492945D01*
X491485Y1492445D01*
X492817D01*
X495539Y1489723D01*
Y1451816D01*
X497161Y1448474D01*
X538874Y1415611D01*
X540577Y1412102D01*
Y1409640D01*
X541722Y1408495D01*
G01X490985Y1489331D02*
Y1490835D01*
X491485Y1491335D01*
X492357D01*
X494429Y1489263D01*
Y1451560D01*
X496273Y1447759D01*
X509029Y1437710D01*
X509087Y1437218D01*
X510620Y1436010D01*
X511111Y1436069D01*
X512642Y1434863D01*
X512701Y1434371D01*
X514233Y1433163D01*
X514725Y1433222D01*
X516256Y1432016D01*
X516315Y1431524D01*
X517847Y1430316D01*
X518339Y1430375D01*
X537986Y1414896D01*
X539467Y1411846D01*
Y1409640D01*
X538322Y1408495D01*
G01X517242Y1348187D02*
X516097Y1347042D01*
Y1343513D01*
X526942Y1332668D01*
Y1332669D01*
X559511Y1319178D01*
X579305D01*
X612127Y1308239D01*
X612126D01*
X644825Y1297341D01*
X677670Y1283208D01*
X715718Y1262869D01*
X716795Y1261791D01*
Y1260112D01*
G01X720535Y1260091D02*
Y1263793D01*
X719399Y1264929D01*
X715487Y1267543D01*
X697408Y1277208D01*
X697407Y1277209D01*
X679335Y1286870D01*
X646406Y1301040D01*
X580665Y1322949D01*
X560392D01*
X532520Y1334495D01*
Y1334494D01*
X522217Y1344797D01*
Y1387229D01*
X516097Y1393349D01*
Y1395438D01*
X517242Y1396583D01*
G01X719425Y1260091D02*
Y1263333D01*
X718691Y1264067D01*
X714915Y1266589D01*
X678853Y1285869D01*
X646010Y1300001D01*
X580484Y1321839D01*
X560171D01*
X531891Y1333553D01*
X521107Y1344337D01*
Y1386769D01*
X514987Y1392889D01*
Y1395438D01*
X513842Y1396583D01*
G01Y1348187D02*
X514987Y1347042D01*
Y1343053D01*
X526313Y1331727D01*
X559290Y1318068D01*
X579124D01*
X644429Y1296302D01*
X660809Y1289254D01*
X660810D01*
X677188Y1282207D01*
X715049Y1261967D01*
X715685Y1261331D01*
Y1260112D01*
G01X516969Y1493662D02*
Y1495166D01*
X517469Y1495666D01*
X518341D01*
X520413Y1493594D01*
Y1452597D01*
X523644Y1445892D01*
X530152Y1440708D01*
X530199Y1440286D01*
X531725Y1439070D01*
X532147Y1439118D01*
X562279Y1415113D01*
X563947Y1411655D01*
Y1409640D01*
X562802Y1408495D01*
G01X508307Y1494449D02*
Y1492945D01*
X508807Y1492445D01*
X510139D01*
X512861Y1489723D01*
Y1452507D01*
X515632Y1446846D01*
X556764Y1414905D01*
X558937Y1410467D01*
Y1369997D01*
X565057Y1363877D01*
Y1361244D01*
X566202Y1360099D01*
G01X562802D02*
X563947Y1361244D01*
Y1363417D01*
X557827Y1369537D01*
Y1410209D01*
X555880Y1414186D01*
X531511Y1433109D01*
X531020Y1433047D01*
X529478Y1434244D01*
X529417Y1434736D01*
X527877Y1435931D01*
X527386Y1435869D01*
X525844Y1437066D01*
X525783Y1437558D01*
X524243Y1438753D01*
X523752Y1438692D01*
X522211Y1439889D01*
X522149Y1440380D01*
X514748Y1446127D01*
X511751Y1452249D01*
Y1489263D01*
X509679Y1491335D01*
X508807D01*
X508307Y1490835D01*
Y1489331D01*
G01X516969Y1498780D02*
Y1497276D01*
X517469Y1496776D01*
X518801D01*
X521523Y1494054D01*
Y1452851D01*
X524535Y1446603D01*
X563170Y1415824D01*
X565057Y1411909D01*
Y1409640D01*
X566202Y1408495D01*
G01X724275Y1260091D02*
Y1265396D01*
X721745Y1267926D01*
X715586Y1272041D01*
X699121Y1280843D01*
X699120Y1280844D01*
X682662Y1289642D01*
X648204Y1304470D01*
X581309Y1326764D01*
X563459D01*
X558893Y1327673D01*
X541554Y1334854D01*
X534457Y1341951D01*
Y1362514D01*
X528337Y1368634D01*
Y1371240D01*
X529482Y1372385D01*
G01X723165Y1260091D02*
Y1264936D01*
X721037Y1267064D01*
X715014Y1271087D01*
X682180Y1288641D01*
X647808Y1303431D01*
X581128Y1325654D01*
X563349D01*
X558569Y1326605D01*
X540925Y1333913D01*
X533347Y1341491D01*
Y1362054D01*
X527227Y1368174D01*
Y1371240D01*
X526082Y1372385D01*
G01X538322Y1348187D02*
X539467Y1347042D01*
Y1341912D01*
X543773Y1337606D01*
X560823Y1330543D01*
X566418Y1329431D01*
X582041D01*
X648583Y1307254D01*
X685964Y1291170D01*
X715115Y1275585D01*
X723601Y1269917D01*
X725854Y1267664D01*
X726906Y1265124D01*
Y1260091D01*
G01X730646D02*
Y1267397D01*
X730068Y1268792D01*
X725940Y1272920D01*
X715214Y1280084D01*
X689210Y1293986D01*
X649515Y1311065D01*
X581820Y1333626D01*
X567390D01*
X562622Y1334574D01*
X549552Y1339988D01*
X545587Y1343953D01*
Y1386583D01*
X539467Y1392703D01*
Y1395438D01*
X538322Y1396583D01*
G01X541722Y1348187D02*
X540577Y1347042D01*
Y1342372D01*
X544402Y1338547D01*
X561147Y1331611D01*
X566528Y1330541D01*
X582222D01*
X648979Y1308293D01*
X686446Y1292171D01*
X701062Y1284358D01*
X701063Y1284357D01*
X715687Y1276539D01*
X724309Y1270779D01*
X726795Y1268293D01*
X728016Y1265345D01*
Y1260091D01*
G01X731756D02*
Y1267618D01*
X731009Y1269421D01*
X726648Y1273782D01*
X721194Y1277425D01*
X721193Y1277426D01*
X715786Y1281038D01*
X689692Y1294987D01*
X649911Y1312104D01*
X582001Y1334736D01*
X567500D01*
X562946Y1335642D01*
X550181Y1340929D01*
X546697Y1344413D01*
Y1387043D01*
X540577Y1393163D01*
Y1395438D01*
X541722Y1396583D01*
G01X734386Y1260091D02*
Y1268220D01*
X733250Y1270964D01*
X728316Y1275900D01*
X721817Y1280239D01*
X721816D01*
X715321Y1284576D01*
X693142Y1296434D01*
X651025Y1314557D01*
X580317Y1338122D01*
X564692D01*
X563810Y1338487D01*
X563809Y1338488D01*
X562927Y1338853D01*
X557827Y1343953D01*
Y1362018D01*
X551707Y1368138D01*
Y1371240D01*
X550562Y1372385D01*
G01X735496Y1260091D02*
Y1268441D01*
X734191Y1271593D01*
X729024Y1276762D01*
X715893Y1285530D01*
X693624Y1297435D01*
X651421Y1315596D01*
X580498Y1339232D01*
X564913D01*
X563556Y1339794D01*
X558937Y1344413D01*
Y1362478D01*
X552817Y1368598D01*
Y1371240D01*
X553962Y1372385D01*
G01X562802Y1348187D02*
X563947Y1347042D01*
Y1344607D01*
X565723Y1342831D01*
X578317D01*
X651864Y1318319D01*
X697243Y1298793D01*
X715427Y1289072D01*
X730608Y1278932D01*
X736657Y1272883D01*
X738126Y1269335D01*
Y1260091D01*
G01X566202Y1348187D02*
X565057Y1347042D01*
Y1345067D01*
X566183Y1343941D01*
X578498D01*
X652260Y1319358D01*
X697725Y1299794D01*
X715999Y1290026D01*
X723634Y1284926D01*
Y1284925D01*
X731316Y1279794D01*
X737598Y1273512D01*
X739236Y1269556D01*
Y1260091D01*
G01X566202Y1396583D02*
X565057Y1395438D01*
Y1392979D01*
X575681Y1382355D01*
Y1382356D01*
X704067Y1300688D01*
X710952Y1297008D01*
X710953Y1297006D01*
X717925Y1293280D01*
X733732Y1282719D01*
X740770Y1275681D01*
X742976Y1270354D01*
Y1260091D01*
G01X562802Y1396583D02*
X563947Y1395438D01*
Y1392519D01*
X574982Y1381484D01*
X703506Y1299728D01*
X717353Y1292326D01*
X733024Y1281857D01*
X739829Y1275052D01*
X741866Y1270133D01*
Y1260091D01*
G01X981029Y104249D02*
X982174Y105394D01*
X987564D01*
X989060Y106890D01*
X993960D01*
X996060Y108990D01*
X998860D01*
X1010610Y120740D01*
Y132640D01*
X1064010Y186040D01*
Y234740D01*
X1089760Y260490D01*
X1219423D01*
X1238265Y268295D01*
X1273160Y303190D01*
X1318860D01*
X1320617Y304947D01*
Y309417D01*
X1321762Y310562D01*
G01X1318362D02*
X1319507Y309417D01*
Y305407D01*
X1318400Y304300D01*
X1272700D01*
X1237636Y269236D01*
X1219202Y261600D01*
X1089300D01*
X1062900Y235200D01*
Y186500D01*
X1026475Y150075D01*
X1025838D01*
X1024458Y148695D01*
Y148058D01*
X1023080Y146680D01*
X1022443D01*
X1021063Y145300D01*
Y144663D01*
X1019685Y143285D01*
X1019048D01*
X1017668Y141905D01*
Y141268D01*
X1016290Y139890D01*
X1015653D01*
X1014273Y138510D01*
Y137873D01*
X1012895Y136495D01*
X1012258D01*
X1010878Y135115D01*
Y134478D01*
X1009500Y133100D01*
Y121200D01*
X998400Y110100D01*
X995600D01*
X993500Y108000D01*
X988600D01*
X987104Y106504D01*
X982174D01*
X981029Y107649D01*
G01X1037290Y296293D02*
X1036145Y295148D01*
Y294228D01*
X1037763Y292610D01*
X1069210D01*
X1076000Y299400D01*
X1248430D01*
X1279227Y330197D01*
Y330961D01*
X1280346Y332079D01*
X1281109D01*
X1282226Y333196D01*
Y333960D01*
X1283345Y335078D01*
X1284108D01*
X1285225Y336195D01*
Y336959D01*
X1286344Y338077D01*
X1287107D01*
X1288224Y339194D01*
Y339958D01*
X1289342Y341076D01*
X1290106D01*
X1291682Y342652D01*
X1301751D01*
X1302896Y343797D01*
G01X1033890Y296293D02*
X1035035Y295148D01*
Y293768D01*
X1037303Y291500D01*
X1069670D01*
X1076460Y298290D01*
X1248890D01*
X1292142Y341542D01*
X1301751D01*
X1302896Y340397D01*
G01X1329636Y307562D02*
X1328491Y306417D01*
Y301921D01*
X1325260Y298690D01*
X1277990D01*
X1244393Y265093D01*
X1212518Y251890D01*
X1186490D01*
X1166310Y231710D01*
Y182540D01*
X1116300Y132530D01*
Y122200D01*
X1103090Y108990D01*
X1098960D01*
X1096560Y106590D01*
X1090860D01*
X1089664Y105394D01*
X1084536D01*
X1083391Y104249D01*
G01X1326236Y307562D02*
X1327381Y306417D01*
Y302381D01*
X1324800Y299800D01*
X1277530D01*
X1243764Y266034D01*
X1212297Y253000D01*
X1186030D01*
X1165200Y232170D01*
Y183000D01*
X1128770Y146570D01*
X1128133D01*
X1126753Y145190D01*
Y144553D01*
X1125375Y143175D01*
X1124738D01*
X1123358Y141795D01*
Y141158D01*
X1121980Y139780D01*
X1121343D01*
X1119963Y138400D01*
Y137763D01*
X1118585Y136385D01*
X1117948D01*
X1116568Y135005D01*
Y134368D01*
X1115190Y132990D01*
Y122660D01*
X1102630Y110100D01*
X1098500D01*
X1096100Y107700D01*
X1090400D01*
X1089204Y106504D01*
X1084536D01*
X1083391Y107649D01*
G01X1242566Y1372385D02*
X1243711Y1371240D01*
Y1369231D01*
X1237591Y1363111D01*
Y1345500D01*
X1231546Y1339186D01*
X1227213Y1336919D01*
X1112126Y1314496D01*
X1091400Y1293770D01*
X1086747Y1282537D01*
Y1259824D01*
G01X1254806Y1348187D02*
X1255951Y1347042D01*
Y1345347D01*
X1255950Y1345346D01*
X1255006Y1343919D01*
X1232361Y1333665D01*
X1114127Y1310697D01*
X1094624Y1291194D01*
X1090488Y1281209D01*
Y1259824D01*
G01X1245966Y1372385D02*
X1244821Y1371240D01*
Y1368771D01*
X1238701Y1362651D01*
Y1345054D01*
X1232222Y1338286D01*
X1227584Y1335860D01*
X1145035Y1319777D01*
X1144759Y1319366D01*
X1142844Y1318993D01*
X1142433Y1319269D01*
X1140519Y1318897D01*
X1140243Y1318485D01*
X1138328Y1318112D01*
X1137917Y1318389D01*
X1112671Y1313471D01*
X1092341Y1293141D01*
X1087857Y1282316D01*
Y1259824D01*
G01X1258206Y1348187D02*
X1257061Y1347042D01*
Y1345012D01*
X1255756Y1343039D01*
X1232700Y1332600D01*
X1159073Y1318297D01*
Y1318298D01*
X1158796Y1317886D01*
X1156881Y1317515D01*
X1156471Y1317791D01*
X1154557Y1317420D01*
X1154280Y1317008D01*
X1152365Y1316637D01*
X1151955Y1316913D01*
X1114672Y1309672D01*
X1095565Y1290565D01*
X1091598Y1280988D01*
Y1259824D01*
G01X1230326Y1348187D02*
X1231471Y1347042D01*
Y1345000D01*
X1229491Y1343020D01*
X1109687Y1317957D01*
X1088502Y1296772D01*
X1083007Y1283506D01*
Y1259824D01*
G01X1233726Y1348187D02*
X1232581Y1347042D01*
Y1344540D01*
X1230042Y1342001D01*
X1142599Y1323708D01*
X1142289Y1323234D01*
X1140380Y1322835D01*
X1139906Y1323144D01*
X1110238Y1316938D01*
X1089443Y1296143D01*
X1084117Y1283285D01*
Y1259824D01*
G01X1270446Y1372385D02*
X1269301Y1371240D01*
Y1369231D01*
X1275421Y1363111D01*
Y1346800D01*
X1270800Y1340300D01*
X1238094Y1325197D01*
X1135565Y1304995D01*
Y1304996D01*
X1135250Y1304525D01*
X1133336Y1304148D01*
X1132866Y1304463D01*
X1117669Y1301469D01*
X1102587Y1286387D01*
X1099078Y1277916D01*
Y1259824D01*
G01X1102818D02*
Y1276736D01*
X1105775Y1283875D01*
X1119429Y1297529D01*
X1142808Y1302148D01*
X1143278Y1301833D01*
X1145192Y1302211D01*
X1145507Y1302682D01*
X1238966Y1321148D01*
X1274300Y1336600D01*
X1281541Y1345013D01*
Y1347042D01*
X1282686Y1348187D01*
G01X1279286D02*
X1280431Y1347042D01*
Y1345425D01*
X1273623Y1337517D01*
X1238632Y1322214D01*
X1118883Y1298553D01*
X1104834Y1284504D01*
X1101708Y1276957D01*
Y1259824D01*
G01X1279286Y1396583D02*
X1280431Y1395438D01*
Y1392969D01*
X1286551Y1386849D01*
Y1347296D01*
X1285129Y1343379D01*
X1277814Y1335150D01*
X1240020Y1318188D01*
X1120671Y1294641D01*
X1108151Y1282121D01*
X1105448Y1275595D01*
Y1259824D01*
G01X1258206Y1396583D02*
X1257061Y1395438D01*
Y1393429D01*
X1263181Y1387309D01*
Y1346600D01*
X1262428Y1344952D01*
X1260300Y1340300D01*
X1236394Y1329186D01*
X1166714Y1315449D01*
X1166398Y1314978D01*
X1164484Y1314601D01*
X1164014Y1314916D01*
X1116063Y1305463D01*
X1099199Y1288599D01*
X1095338Y1279278D01*
Y1259824D01*
G01X1267046Y1372385D02*
X1268191Y1371240D01*
Y1368771D01*
X1274311Y1362651D01*
Y1347155D01*
X1270066Y1341184D01*
X1237749Y1326261D01*
X1117123Y1302493D01*
X1101646Y1287016D01*
X1097968Y1278137D01*
Y1259824D01*
G01X1282686Y1396583D02*
X1281541Y1395438D01*
Y1393429D01*
X1287661Y1387309D01*
Y1347100D01*
X1286100Y1342800D01*
X1278486Y1334234D01*
X1240359Y1317123D01*
X1121217Y1293617D01*
X1113708Y1286108D01*
Y1285472D01*
X1112328Y1284092D01*
X1111692D01*
X1109092Y1281492D01*
X1106558Y1275374D01*
Y1259824D01*
G01X1254806Y1396583D02*
X1255951Y1395438D01*
Y1392969D01*
X1262071Y1386849D01*
Y1346842D01*
X1259460Y1341135D01*
X1236047Y1330250D01*
X1115517Y1306487D01*
X1098258Y1289228D01*
X1094228Y1279499D01*
Y1259824D01*
G01X1316006Y1372385D02*
X1317151Y1371240D01*
Y1368771D01*
X1323271Y1362651D01*
Y1347031D01*
X1321050Y1343630D01*
X1305989Y1330144D01*
X1238915Y1300347D01*
X1126980Y1278350D01*
X1120937Y1272307D01*
X1120409Y1271032D01*
Y1259824D01*
G01X1303766Y1396583D02*
X1304911Y1395438D01*
Y1392969D01*
X1311031Y1386849D01*
Y1347745D01*
X1309027Y1342466D01*
X1300211Y1331809D01*
X1239060Y1304739D01*
X1125410Y1282481D01*
X1117844Y1274914D01*
X1116669Y1272077D01*
Y1259824D01*
G01X1307166Y1348187D02*
X1306021Y1347042D01*
Y1345013D01*
X1297501Y1334200D01*
X1239847Y1308102D01*
X1155371Y1291558D01*
X1155055Y1291088D01*
X1153140Y1290713D01*
X1152671Y1291029D01*
X1124392Y1285491D01*
X1115756Y1276856D01*
X1114039Y1272711D01*
Y1259824D01*
G01X1291526Y1372385D02*
X1292671Y1371240D01*
Y1368771D01*
X1298791Y1362651D01*
Y1347219D01*
X1297022Y1344391D01*
X1288253Y1335427D01*
X1239822Y1313680D01*
X1122634Y1290634D01*
X1111260Y1279260D01*
X1109188Y1274258D01*
Y1259824D01*
G01X1117779D02*
Y1271856D01*
X1118785Y1274285D01*
X1125956Y1281456D01*
X1158819Y1287892D01*
X1159289Y1287576D01*
X1161204Y1287951D01*
X1161519Y1288421D01*
X1239396Y1303673D01*
X1300900Y1330900D01*
X1309331Y1341092D01*
X1310000Y1341900D01*
X1312141Y1347541D01*
Y1387309D01*
X1306021Y1393429D01*
Y1395438D01*
X1307166Y1396583D01*
G01X1303766Y1348187D02*
X1304911Y1347042D01*
Y1345398D01*
X1296796Y1335100D01*
X1239507Y1309167D01*
X1123846Y1286516D01*
X1114815Y1277485D01*
X1112929Y1272932D01*
Y1259824D01*
G01X1294926Y1372385D02*
X1293781Y1371240D01*
Y1369231D01*
X1299901Y1363111D01*
Y1346900D01*
X1297900Y1343700D01*
X1288900Y1334500D01*
X1240161Y1312615D01*
X1150275Y1294938D01*
X1149959Y1294468D01*
X1148045Y1294092D01*
X1147575Y1294407D01*
X1123180Y1289610D01*
X1112201Y1278631D01*
X1110298Y1274037D01*
Y1259824D01*
G01X1121519D02*
Y1270811D01*
X1121878Y1271678D01*
X1127526Y1277326D01*
X1164211Y1284534D01*
X1164681Y1284219D01*
X1166595Y1284595D01*
X1166910Y1285066D01*
Y1285065D01*
X1239252Y1299281D01*
X1306600Y1329200D01*
X1321900Y1342900D01*
X1324201Y1346425D01*
Y1346424D01*
X1324381Y1346700D01*
Y1363111D01*
X1318261Y1369231D01*
Y1371240D01*
X1319406Y1372385D01*
G01X1132739Y1260024D02*
Y1263722D01*
X1134273Y1265586D01*
X1173462Y1273276D01*
X1173931Y1272961D01*
X1175846Y1273336D01*
X1176161Y1273807D01*
X1178074Y1274182D01*
X1178544Y1273867D01*
X1180458Y1274242D01*
X1180774Y1274713D01*
Y1274711D01*
X1240397Y1286413D01*
X1319500Y1322100D01*
X1335726Y1334742D01*
Y1334741D01*
X1341101Y1338929D01*
X1341102D01*
X1346200Y1342900D01*
X1348861Y1346800D01*
Y1363111D01*
X1342741Y1369231D01*
Y1371240D01*
X1343886Y1372385D01*
G01X1356126Y1348187D02*
X1354981Y1347042D01*
Y1345012D01*
X1353600Y1343000D01*
X1338584Y1331237D01*
Y1331236D01*
X1323600Y1319500D01*
X1240700Y1282104D01*
X1164186Y1267109D01*
X1163896Y1266675D01*
X1161824Y1266269D01*
X1161390Y1266562D01*
X1159477Y1266187D01*
X1159122Y1265658D01*
X1157207Y1265283D01*
X1156679Y1265638D01*
X1146855Y1263713D01*
X1138414Y1262556D01*
X1137537Y1262121D01*
X1136479Y1261063D01*
Y1259824D01*
G01X1340486Y1372385D02*
X1341631Y1371240D01*
Y1368771D01*
X1347751Y1362651D01*
Y1347143D01*
X1345380Y1343670D01*
X1318922Y1323058D01*
X1240057Y1287478D01*
X1133669Y1266599D01*
X1131629Y1264120D01*
Y1260024D01*
G01X1356126Y1396583D02*
X1354981Y1395438D01*
Y1393573D01*
X1360287Y1386945D01*
X1361503Y1384984D01*
X1362004Y1362574D01*
X1360987Y1347882D01*
X1360175Y1342876D01*
X1325776Y1315213D01*
X1241837Y1278337D01*
X1157401Y1261479D01*
X1146141Y1259802D01*
X1146129Y1259790D01*
X1142980D01*
G01X1328246Y1348187D02*
X1329391Y1347042D01*
Y1345413D01*
X1328148Y1343912D01*
X1310287Y1327942D01*
X1239919Y1296127D01*
X1128536Y1274307D01*
X1125422Y1271193D01*
X1124149Y1268105D01*
Y1259824D01*
G01X1331646Y1348187D02*
X1330501Y1347042D01*
Y1345013D01*
X1330246Y1344704D01*
Y1344705D01*
X1328950Y1343140D01*
X1310900Y1327000D01*
X1240259Y1295062D01*
X1171024Y1281499D01*
X1170708Y1281028D01*
X1168793Y1280654D01*
X1168324Y1280969D01*
X1129082Y1273282D01*
X1126364Y1270565D01*
X1125259Y1267885D01*
Y1259824D01*
G01X1352726Y1348187D02*
X1353871Y1347042D01*
Y1345357D01*
X1352781Y1343769D01*
X1352780Y1343768D01*
X1323021Y1320457D01*
X1240361Y1283169D01*
X1146673Y1264809D01*
X1138083Y1263632D01*
X1136880Y1263035D01*
X1135369Y1261523D01*
Y1259824D01*
G01X1331646Y1396583D02*
X1330501Y1395438D01*
Y1393429D01*
X1336621Y1387309D01*
Y1346999D01*
X1334141Y1342952D01*
X1315746Y1324746D01*
X1240106Y1290644D01*
X1176235Y1278111D01*
X1175919Y1277641D01*
X1174005Y1277265D01*
X1173535Y1277581D01*
X1171622Y1277206D01*
X1171307Y1276736D01*
X1169392Y1276360D01*
X1168923Y1276676D01*
X1130420Y1269121D01*
X1129616Y1268318D01*
X1128999Y1266828D01*
Y1260024D01*
G01X1352726Y1396583D02*
X1353871Y1395438D01*
Y1393183D01*
X1359379Y1386303D01*
X1360400Y1384656D01*
X1360893Y1362600D01*
X1359883Y1348010D01*
X1359147Y1343475D01*
X1325194Y1316171D01*
X1241501Y1279402D01*
X1157210Y1262573D01*
X1145978Y1260900D01*
X1142980D01*
G01X1328246Y1396583D02*
X1329391Y1395438D01*
Y1392969D01*
X1335511Y1386849D01*
Y1347313D01*
X1333264Y1343647D01*
X1315107Y1325676D01*
X1239767Y1291709D01*
X1129874Y1270146D01*
X1128675Y1268947D01*
X1127889Y1267049D01*
Y1260024D01*
G01X1334110Y310562D02*
X1335255Y309417D01*
Y267625D01*
X1320540Y252910D01*
X1279840D01*
X1266790Y239860D01*
Y202490D01*
X1257668Y188838D01*
X1217290Y148460D01*
Y140060D01*
X1216840Y139610D01*
Y137660D01*
X1217290Y137210D01*
Y135260D01*
X1216840Y134810D01*
Y132860D01*
X1217290Y132410D01*
Y130460D01*
X1216840Y130010D01*
Y128060D01*
X1217290Y127610D01*
Y125660D01*
X1216840Y125210D01*
Y123260D01*
X1217290Y122810D01*
Y120860D01*
X1208240Y111810D01*
X1201610D01*
X1197500Y107700D01*
X1194300D01*
X1193104Y106504D01*
X1186898D01*
X1185753Y107649D01*
G01X1337510Y310562D02*
X1336365Y309417D01*
Y267165D01*
X1321000Y251800D01*
X1280300D01*
X1267900Y239400D01*
Y202153D01*
X1258530Y188130D01*
X1218400Y148000D01*
Y120400D01*
X1208700Y110700D01*
X1202070D01*
X1197960Y106590D01*
X1194760D01*
X1193564Y105394D01*
X1186898D01*
X1185753Y104249D01*
G01X1305079Y1607048D02*
Y1608552D01*
X1305579Y1609052D01*
X1307273D01*
X1308402Y1607923D01*
Y1555030D01*
X1305677Y1552306D01*
X1293058Y1546950D01*
X1293057D01*
X1276167Y1533043D01*
X1245113Y1445902D01*
X1245114D01*
X1244665Y1445690D01*
X1244011Y1443852D01*
X1244223Y1443405D01*
X1243569Y1441569D01*
X1243121Y1441356D01*
X1242466Y1439519D01*
X1242678Y1439071D01*
X1242024Y1437235D01*
X1241576Y1437022D01*
X1240921Y1435185D01*
X1241133Y1434737D01*
X1240479Y1432901D01*
X1240031Y1432688D01*
X1239376Y1430851D01*
X1239589Y1430403D01*
X1232350Y1410087D01*
Y1392670D01*
X1237591Y1387429D01*
Y1369611D01*
X1231471Y1363491D01*
Y1361244D01*
X1230326Y1360099D01*
G01X1305079Y1612166D02*
Y1610662D01*
X1305579Y1610162D01*
X1307733D01*
X1309512Y1608383D01*
Y1554570D01*
X1306310Y1551368D01*
X1293640Y1545991D01*
X1293641Y1545990D01*
X1293638Y1545989D01*
X1277110Y1532381D01*
X1233460Y1409895D01*
Y1393130D01*
X1238701Y1387889D01*
Y1369151D01*
X1232581Y1363031D01*
Y1361244D01*
X1233726Y1360099D01*
G01X1313740Y1611378D02*
Y1612882D01*
X1314240Y1613382D01*
X1315934D01*
X1317063Y1612253D01*
Y1558460D01*
X1316223Y1556709D01*
X1308093Y1548968D01*
X1295570Y1543705D01*
X1279290Y1530451D01*
X1246396Y1434896D01*
X1246397D01*
X1245951Y1434679D01*
X1245316Y1432835D01*
X1245533Y1432390D01*
X1237591Y1409316D01*
Y1393349D01*
X1243711Y1387229D01*
Y1385442D01*
X1242566Y1384297D01*
G01X1254806Y1360099D02*
X1255951Y1361244D01*
Y1363031D01*
X1249831Y1369151D01*
Y1413176D01*
X1252141Y1421283D01*
X1251866Y1421778D01*
X1252400Y1423654D01*
X1252895Y1423929D01*
X1253429Y1425804D01*
X1253154Y1426298D01*
X1253688Y1428174D01*
X1254184Y1428450D01*
X1254183D01*
X1254717Y1430325D01*
X1254442Y1430819D01*
X1254976Y1432695D01*
X1255472Y1432971D01*
X1256006Y1434846D01*
X1255731Y1435340D01*
X1256265Y1437216D01*
X1256761Y1437492D01*
X1256760D01*
X1282561Y1528035D01*
X1298063Y1540593D01*
X1316339Y1547138D01*
X1324662Y1553529D01*
X1325725Y1555065D01*
Y1607923D01*
X1324596Y1609052D01*
X1322902D01*
X1322402Y1608552D01*
Y1607048D01*
G01Y1612166D02*
Y1610662D01*
X1322902Y1610162D01*
X1325056D01*
X1326835Y1608383D01*
Y1554718D01*
X1325477Y1552754D01*
X1316878Y1546151D01*
X1298615Y1539611D01*
X1283533Y1527393D01*
X1250941Y1413020D01*
Y1369611D01*
X1257061Y1363491D01*
Y1361244D01*
X1258206Y1360099D01*
G01X1313740Y1616496D02*
Y1614992D01*
X1314240Y1614492D01*
X1316394D01*
X1318173Y1612713D01*
Y1558207D01*
X1317136Y1556045D01*
X1308711Y1548023D01*
X1296147Y1542743D01*
X1280237Y1529790D01*
X1238701Y1409130D01*
Y1393809D01*
X1244821Y1387689D01*
Y1385442D01*
X1245966Y1384297D01*
G01X1339725Y1612166D02*
Y1610662D01*
X1340225Y1610162D01*
X1342379D01*
X1344158Y1608383D01*
Y1554996D01*
X1342757Y1552435D01*
X1326475Y1540314D01*
X1301043Y1531217D01*
X1290156Y1522619D01*
X1263181Y1413000D01*
Y1393809D01*
X1269301Y1387689D01*
Y1385442D01*
X1270446Y1384297D01*
G01X1267046D02*
X1268191Y1385442D01*
Y1387229D01*
X1262071Y1393349D01*
Y1413135D01*
X1289169Y1523254D01*
X1300497Y1532202D01*
X1325945Y1541304D01*
X1329333Y1543826D01*
X1329415Y1544386D01*
X1330980Y1545551D01*
X1331539Y1545469D01*
X1333103Y1546633D01*
X1333185Y1547193D01*
X1334751Y1548358D01*
X1335310Y1548276D01*
X1336874Y1549440D01*
X1336956Y1550000D01*
X1338521Y1551165D01*
X1339081Y1551083D01*
X1341899Y1553181D01*
X1343048Y1555280D01*
Y1607923D01*
X1341919Y1609052D01*
X1340225D01*
X1339725Y1608552D01*
Y1607048D01*
G01X1331063Y1616496D02*
Y1615036D01*
X1331607Y1614492D01*
X1333717D01*
X1335496Y1612713D01*
Y1557895D01*
X1334714Y1555135D01*
X1330008Y1549626D01*
X1319451Y1542394D01*
X1299580Y1535425D01*
X1286830Y1524925D01*
X1257061Y1413090D01*
Y1409640D01*
X1258206Y1408495D01*
G01X1331063Y1611378D02*
Y1612882D01*
X1331563Y1613382D01*
X1333257D01*
X1334386Y1612253D01*
Y1558050D01*
X1333712Y1555671D01*
X1329259Y1550459D01*
X1318945Y1543393D01*
X1299026Y1536408D01*
X1285848Y1525556D01*
X1255988Y1413375D01*
X1255951Y1413338D01*
Y1409640D01*
X1254806Y1408495D01*
G01X1348386Y1611378D02*
Y1612882D01*
X1348886Y1613382D01*
X1350580D01*
X1351709Y1612253D01*
Y1556982D01*
X1350540Y1555034D01*
X1328051Y1537890D01*
X1302287Y1528712D01*
X1292732Y1521048D01*
X1274311Y1413065D01*
Y1369151D01*
X1280431Y1363031D01*
Y1361244D01*
X1279286Y1360099D01*
G01X1348386Y1616496D02*
Y1615114D01*
X1349008Y1614492D01*
X1351040D01*
X1352819Y1612713D01*
Y1556674D01*
X1351383Y1554280D01*
X1328586Y1536902D01*
X1302836Y1527729D01*
X1293756Y1520445D01*
X1275421Y1412971D01*
Y1369611D01*
X1281541Y1363491D01*
Y1361244D01*
X1282686Y1360099D01*
G01X1279286Y1408495D02*
X1280431Y1409640D01*
Y1413263D01*
X1280443Y1413275D01*
X1296389Y1519050D01*
X1304382Y1525400D01*
X1330494Y1534613D01*
X1342673Y1542607D01*
X1342802Y1543230D01*
X1344433Y1544301D01*
X1345056Y1544171D01*
X1346686Y1545241D01*
X1346815Y1545864D01*
X1348446Y1546935D01*
X1349069Y1546805D01*
X1350699Y1547875D01*
X1350828Y1548498D01*
X1352459Y1549569D01*
X1353083Y1549439D01*
X1358270Y1552844D01*
X1358271Y1552846D01*
X1359591Y1554598D01*
X1360370Y1557102D01*
Y1607923D01*
X1359241Y1609052D01*
X1357547D01*
X1357047Y1608552D01*
Y1607048D01*
G01Y1612166D02*
Y1610662D01*
X1357547Y1610162D01*
X1359701D01*
X1361480Y1608383D01*
Y1556933D01*
X1360594Y1554084D01*
X1359042Y1552023D01*
X1330991Y1533610D01*
X1304927Y1524415D01*
X1297422Y1518452D01*
X1281542Y1413110D01*
X1281541Y1413109D01*
Y1409640D01*
X1282686Y1408495D01*
G01X1363535Y331277D02*
X1364680Y330132D01*
X1366060D01*
X1367510Y328682D01*
Y326340D01*
X1355910Y314740D01*
Y169440D01*
X1344110Y157640D01*
Y146057D01*
X1338980Y138380D01*
X1309390Y108790D01*
X1302560D01*
X1300360Y106590D01*
X1297090D01*
X1295894Y105394D01*
X1289260D01*
X1288115Y104249D01*
G01X1363535Y327877D02*
X1364680Y329022D01*
X1365600D01*
X1366400Y328222D01*
Y326800D01*
X1354800Y315200D01*
Y169900D01*
X1343000Y158100D01*
Y146394D01*
X1340785Y143079D01*
X1340161Y142955D01*
X1339077Y141333D01*
X1339201Y140709D01*
X1338118Y139088D01*
X1336090Y137060D01*
X1335453D01*
X1334073Y135680D01*
Y135043D01*
X1332695Y133665D01*
X1332058D01*
X1330678Y132285D01*
Y131648D01*
X1329300Y130270D01*
X1328663D01*
X1327283Y128890D01*
Y128253D01*
X1325905Y126875D01*
X1325268D01*
X1323888Y125495D01*
Y124858D01*
X1322510Y123480D01*
X1321873D01*
X1320493Y122100D01*
Y121463D01*
X1319115Y120085D01*
X1318478D01*
X1317098Y118705D01*
Y118068D01*
X1315720Y116690D01*
X1315083D01*
X1313703Y115310D01*
Y114673D01*
X1312325Y113295D01*
X1311688D01*
X1310308Y111915D01*
Y111278D01*
X1308930Y109900D01*
X1306980D01*
X1306530Y110350D01*
X1304580D01*
X1304130Y109900D01*
X1302100D01*
X1299900Y107700D01*
X1296630D01*
X1295434Y106504D01*
X1289260D01*
X1288115Y107649D01*
G01X1307166Y1360099D02*
X1306021Y1361244D01*
Y1363491D01*
X1299901Y1369611D01*
Y1413200D01*
X1309512Y1451970D01*
Y1506021D01*
X1307733Y1507800D01*
X1305579D01*
X1305079Y1508300D01*
Y1509804D01*
G01Y1504685D02*
Y1506190D01*
X1305579Y1506690D01*
X1307273D01*
X1308402Y1505561D01*
Y1452106D01*
X1306812Y1445692D01*
X1306266Y1445364D01*
X1305797Y1443470D01*
X1306126Y1442925D01*
X1305657Y1441033D01*
X1305111Y1440704D01*
X1304642Y1438811D01*
X1304971Y1438266D01*
X1304502Y1436374D01*
X1303956Y1436045D01*
X1303487Y1434152D01*
X1303816Y1433607D01*
X1298791Y1413336D01*
Y1369151D01*
X1304911Y1363031D01*
Y1361244D01*
X1303766Y1360099D01*
G01X1365709Y1611378D02*
Y1612882D01*
X1366209Y1613382D01*
X1367903D01*
X1369032Y1612253D01*
Y1558000D01*
X1368426Y1556386D01*
X1361533Y1549483D01*
X1331649Y1530708D01*
X1305733Y1521506D01*
X1299952Y1516933D01*
X1286551Y1413072D01*
Y1393349D01*
X1292671Y1387229D01*
Y1385442D01*
X1291526Y1384297D01*
G01X1365709Y1616496D02*
Y1614992D01*
X1366209Y1614492D01*
X1368363D01*
X1370142Y1612713D01*
Y1557798D01*
X1369381Y1555771D01*
X1362230Y1548610D01*
X1332136Y1529703D01*
X1306278Y1520521D01*
X1300996Y1516342D01*
X1287661Y1413000D01*
Y1393809D01*
X1293781Y1387689D01*
Y1385442D01*
X1294926Y1384297D01*
G01X1322402Y1504685D02*
Y1506190D01*
X1322902Y1506690D01*
X1324596D01*
X1325725Y1505561D01*
Y1452451D01*
X1321921Y1442290D01*
X1321341Y1442026D01*
X1320657Y1440199D01*
X1320921Y1439620D01*
X1320238Y1437794D01*
X1319658Y1437531D01*
X1318974Y1435703D01*
X1319238Y1435124D01*
X1318555Y1433298D01*
X1317975Y1433035D01*
X1317291Y1431207D01*
X1317555Y1430628D01*
X1311031Y1413201D01*
Y1393349D01*
X1317151Y1387229D01*
Y1385442D01*
X1316006Y1384297D01*
G01X1319406D02*
X1318261Y1385442D01*
Y1387689D01*
X1312141Y1393809D01*
Y1413000D01*
X1326835Y1452250D01*
Y1506021D01*
X1325056Y1507800D01*
X1322902D01*
X1322402Y1508300D01*
Y1509804D01*
G01X1307166Y1408495D02*
X1306021Y1409640D01*
Y1413110D01*
X1318173Y1452110D01*
Y1510351D01*
X1316394Y1512130D01*
X1314240D01*
X1313740Y1512630D01*
Y1514134D01*
G01X1303766Y1408495D02*
X1304911Y1409640D01*
Y1413279D01*
X1312877Y1438847D01*
X1312581Y1439410D01*
X1313161Y1441273D01*
X1313725Y1441569D01*
X1314305Y1443430D01*
X1314010Y1443993D01*
X1314590Y1445856D01*
X1315154Y1446152D01*
X1317063Y1452279D01*
Y1509891D01*
X1315934Y1511020D01*
X1314240D01*
X1313740Y1510520D01*
Y1509016D01*
G01X1334109Y373401D02*
X1335254Y374546D01*
Y375926D01*
X1336738Y377410D01*
X1385660D01*
X1431860Y331210D01*
X1433560D01*
X1442410Y322360D01*
Y318660D01*
X1448760Y312310D01*
X1667860D01*
X1718756Y261414D01*
X1724200Y248271D01*
Y170570D01*
X1748810Y145960D01*
Y106544D01*
X1747660Y105394D01*
X1746347D01*
X1745202Y104249D01*
G01X1328246Y1360099D02*
X1329391Y1361244D01*
Y1363031D01*
X1323271Y1369151D01*
Y1413084D01*
X1329557Y1435324D01*
X1329246Y1435880D01*
X1329777Y1437757D01*
X1330333Y1438068D01*
X1330863Y1439944D01*
X1330553Y1440499D01*
X1331083Y1442377D01*
X1331640Y1442688D01*
X1334386Y1452404D01*
Y1509891D01*
X1333257Y1511020D01*
X1331563D01*
X1331063Y1510520D01*
Y1509016D01*
G01X1331646Y1360099D02*
X1330501Y1361244D01*
Y1363491D01*
X1324381Y1369611D01*
Y1412930D01*
X1335496Y1452250D01*
Y1510351D01*
X1333717Y1512130D01*
X1331563D01*
X1331063Y1512630D01*
Y1514134D01*
G01X1331646Y1408495D02*
X1330501Y1409640D01*
Y1413020D01*
X1344158Y1452300D01*
Y1506021D01*
X1342379Y1507800D01*
X1340225D01*
X1339725Y1508300D01*
Y1509804D01*
G01X1328246Y1408495D02*
X1329391Y1409640D01*
Y1413208D01*
X1333133Y1423975D01*
X1332855Y1424547D01*
X1333496Y1426390D01*
X1334069Y1426668D01*
X1334709Y1428509D01*
X1334432Y1429081D01*
X1335072Y1430924D01*
X1335646Y1431202D01*
X1336286Y1433043D01*
X1336009Y1433615D01*
X1336649Y1435458D01*
X1337223Y1435736D01*
X1337863Y1437577D01*
X1337586Y1438150D01*
X1338227Y1439993D01*
X1338800Y1440270D01*
X1343048Y1452488D01*
Y1505561D01*
X1341919Y1506690D01*
X1340225D01*
X1339725Y1506190D01*
Y1504685D01*
G01X1745202Y107649D02*
X1746347Y106504D01*
X1747200D01*
X1747700Y107004D01*
Y108954D01*
X1747250Y109404D01*
Y111354D01*
X1747700Y111804D01*
Y113754D01*
X1747250Y114204D01*
Y116154D01*
X1747700Y116604D01*
Y118554D01*
X1747250Y119004D01*
Y120954D01*
X1747700Y121404D01*
Y123354D01*
X1747250Y123804D01*
Y125754D01*
X1747700Y126204D01*
Y145500D01*
X1745958Y147242D01*
X1745322D01*
X1743942Y148622D01*
Y149258D01*
X1742564Y150636D01*
X1741927D01*
X1740547Y152016D01*
Y152653D01*
X1739169Y154031D01*
X1738532D01*
X1737152Y155411D01*
Y156048D01*
X1735774Y157426D01*
X1735137D01*
X1733757Y158806D01*
Y159443D01*
X1732379Y160821D01*
X1731742D01*
X1730362Y162201D01*
Y162838D01*
X1723090Y170110D01*
Y238450D01*
X1722640Y238900D01*
Y240850D01*
X1723090Y241300D01*
Y243250D01*
X1722640Y243700D01*
Y245650D01*
X1723090Y246100D01*
Y248050D01*
X1722344Y249851D01*
X1721755Y250095D01*
X1721009Y251897D01*
X1721253Y252485D01*
X1720507Y254286D01*
X1719918Y254530D01*
X1719172Y256332D01*
X1719416Y256920D01*
X1717815Y260785D01*
X1714708Y263892D01*
X1714072D01*
X1712692Y265272D01*
Y265908D01*
X1667400Y311200D01*
X1448300D01*
X1441300Y318200D01*
Y321900D01*
X1433100Y330100D01*
X1431400D01*
X1426808Y334692D01*
X1426172D01*
X1424792Y336072D01*
Y336708D01*
X1385200Y376300D01*
X1337198D01*
X1336364Y375466D01*
Y374546D01*
X1337509Y373401D01*
G01X1357047Y1509804D02*
Y1508300D01*
X1357547Y1507800D01*
X1359701D01*
X1361480Y1506021D01*
Y1451970D01*
X1348861Y1413200D01*
Y1369611D01*
X1354981Y1363491D01*
Y1361244D01*
X1356126Y1360099D01*
G01X1357047Y1504685D02*
Y1506146D01*
X1357591Y1506690D01*
X1359241D01*
X1360370Y1505561D01*
Y1452147D01*
X1357140Y1442223D01*
X1356572Y1441935D01*
X1355969Y1440079D01*
X1356257Y1439512D01*
X1355654Y1437658D01*
X1355086Y1437370D01*
X1354482Y1435514D01*
X1354771Y1434947D01*
X1354168Y1433093D01*
X1353600Y1432805D01*
X1352996Y1430949D01*
X1353285Y1430382D01*
X1352682Y1428528D01*
X1352114Y1428240D01*
X1351510Y1426384D01*
X1351799Y1425817D01*
X1347751Y1413377D01*
Y1369151D01*
X1353871Y1363031D01*
Y1361244D01*
X1352726Y1360099D01*
G01X1348386Y1509016D02*
Y1510520D01*
X1348886Y1511020D01*
X1350580D01*
X1351709Y1509891D01*
Y1452560D01*
X1346777Y1440581D01*
X1346188Y1440336D01*
X1345446Y1438532D01*
X1345691Y1437944D01*
X1344949Y1436141D01*
X1344361Y1435897D01*
X1343618Y1434092D01*
X1343863Y1433505D01*
X1343121Y1431702D01*
X1342533Y1431458D01*
X1341790Y1429653D01*
X1342035Y1429066D01*
X1335511Y1413220D01*
Y1393349D01*
X1341631Y1387229D01*
Y1385442D01*
X1340486Y1384297D01*
G01X1343886D02*
X1342741Y1385442D01*
Y1387689D01*
X1336621Y1393809D01*
Y1413000D01*
X1352819Y1452340D01*
Y1510351D01*
X1351040Y1512130D01*
X1348886D01*
X1348386Y1512630D01*
Y1514134D01*
G01X1438116Y107649D02*
X1439261Y106504D01*
X1440133D01*
X1440890Y107261D01*
Y109211D01*
X1440440Y109661D01*
Y111611D01*
X1440890Y112061D01*
Y114011D01*
X1440440Y114461D01*
Y116411D01*
X1440890Y116861D01*
Y118811D01*
X1440440Y119261D01*
Y121211D01*
X1440890Y121661D01*
Y123611D01*
X1440440Y124061D01*
Y126011D01*
X1440890Y126461D01*
Y128411D01*
X1440440Y128861D01*
Y130811D01*
X1440890Y131261D01*
Y133211D01*
X1440440Y133661D01*
Y135611D01*
X1440890Y136061D01*
Y138011D01*
X1440440Y138461D01*
Y140411D01*
X1440890Y140861D01*
Y144110D01*
X1439512Y145488D01*
X1438875D01*
X1437495Y146868D01*
Y147505D01*
X1436117Y148883D01*
X1435480D01*
X1434100Y150263D01*
Y150900D01*
X1419900Y165100D01*
Y277700D01*
X1389400Y308200D01*
X1378500D01*
X1370200Y316500D01*
Y335296D01*
X1368600Y336896D01*
X1367680D01*
X1366535Y335751D01*
G01Y339151D02*
X1367680Y338006D01*
X1369060D01*
X1371310Y335756D01*
Y316960D01*
X1378960Y309310D01*
X1389860D01*
X1421010Y278160D01*
Y165560D01*
X1442000Y144570D01*
Y106801D01*
X1440593Y105394D01*
X1439261D01*
X1438116Y104249D01*
G01X1540478Y107649D02*
X1541623Y106504D01*
X1542543D01*
X1543100Y107061D01*
Y109011D01*
X1542650Y109461D01*
Y111411D01*
X1543100Y111861D01*
Y113811D01*
X1542650Y114261D01*
Y116211D01*
X1543100Y116661D01*
Y118611D01*
X1542650Y119061D01*
Y121011D01*
X1543100Y121461D01*
Y123411D01*
X1542650Y123861D01*
Y125811D01*
X1543100Y126261D01*
Y128211D01*
X1542650Y128661D01*
Y130611D01*
X1543100Y131061D01*
Y133011D01*
X1542650Y133461D01*
Y135411D01*
X1543100Y135861D01*
Y137811D01*
X1542650Y138261D01*
Y140211D01*
X1543100Y140661D01*
Y144330D01*
X1541722Y145708D01*
X1541085D01*
X1539705Y147088D01*
Y147725D01*
X1538327Y149103D01*
X1537690D01*
X1536310Y150483D01*
Y151120D01*
X1522834Y164596D01*
X1519490Y172670D01*
Y253910D01*
X1477100Y296300D01*
X1436900D01*
X1420900Y312300D01*
X1381000D01*
X1374900Y318400D01*
Y339600D01*
X1369730Y344770D01*
X1364680D01*
X1363535Y343625D01*
G01X1366535Y354899D02*
X1367680Y353754D01*
X1371616D01*
X1380910Y344460D01*
Y319860D01*
X1383860Y316910D01*
X1425360D01*
X1440660Y301610D01*
X1572060D01*
X1615337Y258333D01*
X1623200Y239350D01*
Y168170D01*
X1646410Y144960D01*
Y106544D01*
X1645260Y105394D01*
X1643985D01*
X1642840Y104249D01*
G01Y107649D02*
X1643985Y106504D01*
X1644800D01*
X1645300Y107004D01*
Y108954D01*
X1644850Y109404D01*
Y111354D01*
X1645300Y111804D01*
Y113754D01*
X1644850Y114204D01*
Y116154D01*
X1645300Y116604D01*
Y118554D01*
X1644850Y119004D01*
Y120954D01*
X1645300Y121404D01*
Y123354D01*
X1644850Y123804D01*
Y125754D01*
X1645300Y126204D01*
Y128154D01*
X1644850Y128604D01*
Y130554D01*
X1645300Y131004D01*
Y132954D01*
X1644850Y133404D01*
Y135354D01*
X1645300Y135804D01*
Y137754D01*
X1644850Y138204D01*
Y140154D01*
X1645300Y140604D01*
Y144500D01*
X1643922Y145878D01*
X1643285D01*
X1641905Y147258D01*
Y147895D01*
X1640527Y149273D01*
X1639890D01*
X1638510Y150653D01*
Y151290D01*
X1622090Y167710D01*
Y239129D01*
X1614396Y257704D01*
X1571600Y300500D01*
X1440200D01*
X1424900Y315800D01*
X1383400D01*
X1379800Y319400D01*
Y344000D01*
X1371156Y352644D01*
X1367680D01*
X1366535Y351499D01*
G01X1363535Y347025D02*
X1364680Y345880D01*
X1370190D01*
X1376010Y340060D01*
Y318860D01*
X1381460Y313410D01*
X1421360D01*
X1437360Y297410D01*
X1477560D01*
X1520600Y254370D01*
Y172891D01*
X1523775Y165225D01*
X1544210Y144790D01*
Y106601D01*
X1543003Y105394D01*
X1541623D01*
X1540478Y104249D01*
G01X1365709Y1509016D02*
Y1510520D01*
X1366209Y1511020D01*
X1367903D01*
X1369032Y1509891D01*
Y1452090D01*
X1364332Y1440083D01*
X1363748Y1439828D01*
X1363037Y1438012D01*
X1363292Y1437429D01*
X1362582Y1435614D01*
X1361998Y1435359D01*
X1361287Y1433542D01*
X1361542Y1432959D01*
X1360832Y1431144D01*
X1360312Y1430917D01*
X1359602Y1429100D01*
X1359828Y1428582D01*
X1353871Y1413360D01*
Y1409640D01*
X1352726Y1408495D01*
G01X1356126D02*
X1354981Y1409640D01*
Y1413150D01*
X1370142Y1451880D01*
Y1510351D01*
X1368363Y1512130D01*
X1366209D01*
X1365709Y1512630D01*
Y1514134D01*
G01X1478307Y1607048D02*
Y1608552D01*
X1478807Y1609052D01*
X1480501D01*
X1481630Y1607923D01*
Y1556605D01*
X1480608Y1553928D01*
X1477907Y1551327D01*
X1475666Y1550316D01*
X1475137Y1550516D01*
X1473359Y1549713D01*
X1473159Y1549184D01*
X1467526Y1546643D01*
X1464301Y1544193D01*
X1463741Y1544270D01*
X1462187Y1543089D01*
X1462110Y1542528D01*
X1452220Y1535014D01*
X1445622Y1519863D01*
X1443692Y1468934D01*
X1446290Y1444577D01*
X1456448Y1369097D01*
X1462515Y1363031D01*
Y1361244D01*
X1461370Y1360099D01*
G01X1478307Y1612166D02*
Y1610662D01*
X1478807Y1610162D01*
X1480961D01*
X1482740Y1608383D01*
Y1556400D01*
X1481557Y1553300D01*
X1478539Y1550394D01*
X1468098Y1545682D01*
X1453122Y1534305D01*
X1446724Y1519612D01*
X1444805Y1468972D01*
X1447393Y1444710D01*
X1457499Y1369617D01*
X1463625Y1363491D01*
Y1361244D01*
X1464770Y1360099D01*
G01X1486968Y1611378D02*
Y1612882D01*
X1487468Y1613382D01*
X1489162D01*
X1490291Y1612253D01*
Y1561160D01*
X1489251Y1557616D01*
X1484864Y1551989D01*
X1478478Y1546957D01*
X1468599Y1542521D01*
X1455218Y1532456D01*
X1449732Y1519194D01*
X1447563Y1469776D01*
X1450141Y1445333D01*
X1468780Y1393203D01*
X1474755Y1387229D01*
Y1385442D01*
X1473610Y1384297D01*
G01X1477010D02*
X1475865Y1385442D01*
Y1387689D01*
X1469742Y1393812D01*
X1451231Y1445582D01*
X1448676Y1469810D01*
X1450833Y1518950D01*
X1456128Y1531751D01*
X1469167Y1541559D01*
X1479058Y1546000D01*
X1485657Y1551200D01*
X1487490Y1553551D01*
X1487911Y1553603D01*
X1489111Y1555142D01*
X1489059Y1555563D01*
X1490257Y1557100D01*
X1491401Y1561000D01*
Y1612713D01*
X1489622Y1614492D01*
X1487468D01*
X1486968Y1614992D01*
Y1616496D01*
G01X1464770Y1348187D02*
X1463625Y1347042D01*
Y1343458D01*
X1538259Y1266729D01*
X1540637Y1263115D01*
X1541204Y1261749D01*
Y1259630D01*
G01X1461370Y1348187D02*
X1462515Y1347042D01*
Y1343007D01*
X1537389Y1266030D01*
X1539652Y1262592D01*
X1540094Y1261527D01*
Y1259630D01*
G01X1495630Y1607048D02*
Y1608552D01*
X1496130Y1609052D01*
X1497824D01*
X1498953Y1607923D01*
Y1555778D01*
X1498142Y1554256D01*
X1493733Y1551618D01*
X1493185Y1551756D01*
X1491510Y1550754D01*
X1491373Y1550205D01*
X1489700Y1549204D01*
X1489152Y1549342D01*
X1487477Y1548340D01*
X1487339Y1547791D01*
X1479152Y1542892D01*
X1470955Y1539397D01*
X1458379Y1530084D01*
X1453721Y1518667D01*
X1451708Y1469886D01*
X1454040Y1446268D01*
X1463561Y1431960D01*
X1478809Y1414814D01*
X1480875Y1409386D01*
Y1369151D01*
X1486995Y1363031D01*
Y1361244D01*
X1485850Y1360099D01*
G01X1495630Y1612166D02*
Y1610662D01*
X1496130Y1610162D01*
X1498284D01*
X1500063Y1608383D01*
Y1555500D01*
X1498977Y1553462D01*
X1479657Y1541900D01*
X1471511Y1538427D01*
X1459290Y1529376D01*
X1454823Y1518427D01*
X1452821Y1469918D01*
X1455118Y1446653D01*
X1464442Y1432640D01*
X1479775Y1415400D01*
X1481985Y1409591D01*
Y1369611D01*
X1488105Y1363491D01*
Y1361244D01*
X1489250Y1360099D01*
G01X1512953Y1612166D02*
Y1610662D01*
X1513453Y1610162D01*
X1515607D01*
X1517386Y1608383D01*
Y1556200D01*
X1515957Y1552600D01*
X1498057Y1541800D01*
X1475617Y1531669D01*
X1465797Y1524696D01*
X1462658Y1516745D01*
X1460799Y1470081D01*
X1462630Y1449265D01*
X1470461Y1437966D01*
X1491092Y1417770D01*
X1494225Y1410320D01*
Y1393809D01*
X1500345Y1387689D01*
Y1385442D01*
X1501490Y1384297D01*
G01X1489250Y1408495D02*
X1488105Y1409640D01*
Y1411120D01*
X1486519Y1415121D01*
X1467511Y1435335D01*
X1458866Y1447924D01*
X1456877Y1469386D01*
X1458851Y1517613D01*
X1462467Y1526986D01*
X1467867Y1530942D01*
Y1530941D01*
X1473264Y1534896D01*
Y1534897D01*
X1482657Y1539000D01*
X1497143Y1547327D01*
X1497553Y1547216D01*
X1499244Y1548189D01*
X1499355Y1548599D01*
X1503548Y1551009D01*
X1506357Y1554100D01*
X1508724Y1560000D01*
Y1612713D01*
X1506945Y1614492D01*
X1504791D01*
X1504291Y1614992D01*
Y1616496D01*
G01X1512953Y1607048D02*
Y1608552D01*
X1513453Y1609052D01*
X1515147D01*
X1516276Y1607923D01*
Y1556413D01*
X1515063Y1553357D01*
X1511045Y1550933D01*
X1510496Y1551069D01*
X1508826Y1550061D01*
X1508690Y1549512D01*
X1507021Y1548505D01*
X1506472Y1548641D01*
X1504801Y1547633D01*
X1504665Y1547084D01*
X1497540Y1542785D01*
X1475062Y1532637D01*
X1464885Y1525411D01*
X1461556Y1516977D01*
X1459687Y1470054D01*
X1461549Y1448874D01*
X1469608Y1437246D01*
X1490155Y1417133D01*
X1493115Y1410096D01*
Y1393349D01*
X1499235Y1387229D01*
Y1385442D01*
X1498090Y1384297D01*
G01X1485850Y1408495D02*
X1486995Y1409640D01*
Y1410908D01*
X1485565Y1414515D01*
X1466643Y1434636D01*
X1457787Y1447534D01*
X1456766Y1458552D01*
X1455764Y1469357D01*
X1457749Y1517842D01*
X1461548Y1527690D01*
X1472707Y1535865D01*
X1482157Y1539993D01*
X1502843Y1551885D01*
X1505401Y1554699D01*
X1507614Y1560215D01*
Y1612253D01*
X1506485Y1613382D01*
X1504791D01*
X1504291Y1612882D01*
Y1611378D01*
G01X1521614D02*
Y1612882D01*
X1522114Y1613382D01*
X1523808D01*
X1524937Y1612253D01*
Y1559806D01*
X1522410Y1553234D01*
X1518988Y1549997D01*
X1501159Y1539695D01*
X1477675Y1529645D01*
X1468177Y1523094D01*
X1465363Y1516078D01*
X1463579Y1469963D01*
X1465222Y1450603D01*
X1472994Y1440272D01*
X1502841Y1414493D01*
X1505355Y1409001D01*
Y1369151D01*
X1511475Y1363031D01*
Y1361244D01*
X1510330Y1360099D01*
G01X1513730D02*
X1512585Y1361244D01*
Y1363491D01*
X1506465Y1369611D01*
Y1409243D01*
X1503750Y1415175D01*
X1473810Y1441034D01*
X1466302Y1451015D01*
X1464691Y1469989D01*
X1466465Y1515843D01*
X1469083Y1522370D01*
X1478214Y1528668D01*
X1501657Y1538700D01*
X1514996Y1546407D01*
X1515406Y1546297D01*
X1517095Y1547274D01*
X1517205Y1547684D01*
X1519657Y1549100D01*
X1523357Y1552600D01*
X1526047Y1559600D01*
Y1612713D01*
X1524268Y1614492D01*
X1522114D01*
X1521614Y1614992D01*
Y1616496D01*
G01X1473610Y1372385D02*
X1474755Y1371240D01*
Y1368771D01*
X1480875Y1362651D01*
Y1346264D01*
X1481753Y1342875D01*
X1501559Y1320227D01*
X1539650Y1270264D01*
X1543834Y1263082D01*
Y1259924D01*
G01X1477010Y1372385D02*
X1475865Y1371240D01*
Y1369231D01*
X1481985Y1363111D01*
Y1346406D01*
X1482762Y1343408D01*
X1502419Y1320930D01*
X1540575Y1270883D01*
X1544944Y1263382D01*
Y1259924D01*
G01X1525970Y1384297D02*
X1524825Y1385442D01*
Y1387689D01*
X1518705Y1393809D01*
Y1409961D01*
X1515859Y1416195D01*
X1478455Y1448635D01*
X1473765Y1454505D01*
X1472428Y1468689D01*
X1474160Y1513887D01*
X1475818Y1517317D01*
X1481657Y1521500D01*
X1524157Y1540000D01*
X1533057Y1545500D01*
X1536977Y1549513D01*
X1537401Y1549518D01*
X1538765Y1550914D01*
X1538760Y1551339D01*
X1541457Y1554100D01*
X1543370Y1559200D01*
Y1612713D01*
X1541591Y1614492D01*
X1539437D01*
X1538937Y1614992D01*
Y1616496D01*
G01X1530275Y1607048D02*
Y1608552D01*
X1530775Y1609052D01*
X1532469D01*
X1533598Y1607923D01*
Y1557179D01*
X1532483Y1553794D01*
X1530284Y1551562D01*
X1529718Y1551558D01*
X1528349Y1550168D01*
X1528353Y1549602D01*
X1526061Y1547276D01*
X1524335Y1546218D01*
X1523785Y1546350D01*
X1522121Y1545330D01*
X1521989Y1544780D01*
X1520046Y1543590D01*
X1479613Y1526375D01*
X1471226Y1520444D01*
X1469255Y1514865D01*
X1467504Y1468278D01*
X1467507Y1468243D01*
X1467509Y1468212D01*
X1468843Y1452585D01*
X1475640Y1443794D01*
X1509917Y1414362D01*
X1511475Y1410973D01*
Y1409640D01*
X1510330Y1408495D01*
G01X1530275Y1612166D02*
Y1610662D01*
X1530775Y1610162D01*
X1532929D01*
X1534708Y1608383D01*
Y1557000D01*
X1533457Y1553200D01*
X1526757Y1546400D01*
X1520557Y1542600D01*
X1480157Y1525400D01*
X1472155Y1519741D01*
X1470358Y1514654D01*
X1468616Y1468307D01*
Y1468304D01*
X1469922Y1453006D01*
X1476450Y1444563D01*
X1510825Y1415047D01*
X1512585Y1411216D01*
Y1409640D01*
X1513730Y1408495D01*
G01X1538937Y1611378D02*
Y1612882D01*
X1539437Y1613382D01*
X1541131D01*
X1542260Y1612253D01*
Y1559402D01*
X1541379Y1557054D01*
X1541378D01*
X1540499Y1554709D01*
X1532358Y1546373D01*
X1523641Y1540986D01*
X1481106Y1522471D01*
X1474941Y1518055D01*
X1473059Y1514162D01*
X1471315Y1468658D01*
X1472690Y1454071D01*
X1477650Y1447862D01*
X1514949Y1415514D01*
X1517595Y1409719D01*
Y1393349D01*
X1523715Y1387229D01*
Y1385442D01*
X1522570Y1384297D01*
G01X1478307Y1494449D02*
Y1492945D01*
X1478807Y1492445D01*
X1480961D01*
X1482740Y1490666D01*
Y1456022D01*
X1485707Y1449834D01*
X1527910Y1415939D01*
X1530945Y1409610D01*
Y1369611D01*
X1537065Y1363491D01*
Y1361244D01*
X1538210Y1360099D01*
G01X1534810D02*
X1535955Y1361244D01*
Y1363031D01*
X1529835Y1369151D01*
Y1409357D01*
X1527017Y1415231D01*
X1502194Y1435167D01*
X1501702Y1435113D01*
X1500181Y1436335D01*
X1500127Y1436827D01*
X1498607Y1438048D01*
X1498115Y1437994D01*
X1496594Y1439216D01*
X1496540Y1439708D01*
X1495020Y1440929D01*
X1494528Y1440875D01*
X1493007Y1442097D01*
X1492953Y1442589D01*
X1484814Y1449126D01*
X1481630Y1455769D01*
Y1490206D01*
X1480501Y1491335D01*
X1478807D01*
X1478307Y1490835D01*
Y1489331D01*
G01X1489250Y1348187D02*
X1488105Y1347042D01*
Y1345181D01*
X1513315Y1316008D01*
X1543752Y1273222D01*
X1548073Y1265745D01*
X1548684Y1264270D01*
Y1260024D01*
G01X1485850Y1348187D02*
X1486995Y1347042D01*
Y1344767D01*
X1512440Y1315321D01*
X1542817Y1272621D01*
X1547075Y1265253D01*
X1547574Y1264049D01*
Y1260024D01*
G01X1485850Y1396583D02*
X1486995Y1395438D01*
Y1392969D01*
X1493115Y1386849D01*
Y1345413D01*
X1517416Y1316445D01*
X1545038Y1276678D01*
X1550879Y1266384D01*
X1551315Y1265335D01*
Y1260024D01*
G01X1489250Y1396583D02*
X1488105Y1395438D01*
Y1393429D01*
X1494225Y1387309D01*
Y1345817D01*
X1518299Y1317120D01*
X1545979Y1277270D01*
X1551879Y1266873D01*
X1552425Y1265557D01*
Y1260024D01*
G01X1486968Y1498780D02*
Y1497276D01*
X1487468Y1496776D01*
X1489622D01*
X1491401Y1494997D01*
Y1455565D01*
X1494062Y1449875D01*
X1534996Y1415675D01*
X1537065Y1411250D01*
Y1409640D01*
X1538210Y1408495D01*
G01X1486968Y1493662D02*
Y1495166D01*
X1487468Y1495666D01*
X1489162D01*
X1490291Y1494537D01*
Y1455318D01*
X1493161Y1449181D01*
X1500607Y1442960D01*
X1500651Y1442467D01*
X1502149Y1441216D01*
X1502642Y1441260D01*
X1534095Y1414981D01*
X1535955Y1411003D01*
Y1409640D01*
X1534810Y1408495D01*
G01X1547050Y1384297D02*
X1548195Y1385442D01*
Y1387229D01*
X1542075Y1393349D01*
Y1409467D01*
X1539270Y1415715D01*
X1515881Y1436520D01*
X1515386Y1436491D01*
X1513928Y1437788D01*
X1513899Y1438282D01*
X1512443Y1439578D01*
X1511948Y1439549D01*
X1510490Y1440846D01*
X1510461Y1441340D01*
X1509005Y1442636D01*
X1508511Y1442607D01*
X1507053Y1443904D01*
X1507024Y1444398D01*
X1501935Y1448925D01*
X1498953Y1455571D01*
Y1490206D01*
X1497824Y1491335D01*
X1496130D01*
X1495630Y1490835D01*
Y1489331D01*
G01Y1494449D02*
Y1492945D01*
X1496130Y1492445D01*
X1498284D01*
X1500063Y1490666D01*
Y1455809D01*
X1502851Y1449597D01*
X1540186Y1416387D01*
X1543185Y1409705D01*
Y1393809D01*
X1549305Y1387689D01*
Y1385442D01*
X1550450Y1384297D01*
G01X1501490Y1372385D02*
X1500345Y1371240D01*
Y1369231D01*
X1506465Y1363111D01*
Y1347069D01*
X1507396Y1343401D01*
X1522938Y1322198D01*
X1549987Y1278758D01*
X1555109Y1268949D01*
X1556165Y1266400D01*
Y1260024D01*
G01X1498090Y1372385D02*
X1499235Y1371240D01*
Y1368771D01*
X1505355Y1362651D01*
Y1346930D01*
X1506373Y1342919D01*
X1522017Y1321575D01*
X1535520Y1299890D01*
X1535521D01*
X1549022Y1278206D01*
X1554102Y1268479D01*
X1555055Y1266179D01*
Y1260024D01*
G01X1513730Y1348187D02*
X1512585Y1347042D01*
Y1344898D01*
X1512937Y1343868D01*
X1526706Y1324690D01*
X1553859Y1280335D01*
X1558643Y1271057D01*
X1559905Y1268011D01*
Y1260024D01*
G01X1510330Y1348187D02*
X1511475Y1347042D01*
Y1344713D01*
X1511939Y1343354D01*
X1525780Y1324075D01*
X1552891Y1279790D01*
X1557635Y1270589D01*
X1558795Y1267790D01*
Y1260024D01*
G01X1510330Y1396583D02*
X1511475Y1395438D01*
Y1392969D01*
X1517595Y1386849D01*
Y1347312D01*
X1518604Y1343520D01*
X1535121Y1318714D01*
X1555768Y1283045D01*
X1561202Y1272131D01*
X1562535Y1268913D01*
Y1260024D01*
G01X1513730Y1396583D02*
X1512585Y1395438D01*
Y1393429D01*
X1518705Y1387309D01*
Y1347458D01*
X1519630Y1343983D01*
X1536065Y1319301D01*
X1556747Y1283571D01*
X1562213Y1272591D01*
X1563645Y1269134D01*
Y1260024D01*
G01X1504291Y1493662D02*
Y1495166D01*
X1504791Y1495666D01*
X1506485D01*
X1507614Y1494537D01*
Y1455370D01*
X1510455Y1449336D01*
X1517401Y1443593D01*
X1517448Y1443101D01*
X1518952Y1441857D01*
X1519444Y1441904D01*
X1551761Y1415187D01*
X1554315Y1409762D01*
Y1369151D01*
X1560435Y1363031D01*
Y1361244D01*
X1559290Y1360099D01*
G01X1504291Y1498780D02*
Y1497276D01*
X1504791Y1496776D01*
X1506945D01*
X1508724Y1494997D01*
Y1455619D01*
X1511354Y1450033D01*
X1552660Y1415884D01*
X1555425Y1410011D01*
Y1369611D01*
X1561545Y1363491D01*
Y1361244D01*
X1562690Y1360099D01*
G01X1512953Y1489331D02*
Y1490835D01*
X1513453Y1491335D01*
X1515147D01*
X1516276Y1490206D01*
Y1455827D01*
X1519238Y1449317D01*
X1524155Y1445033D01*
X1524189Y1444540D01*
X1525660Y1443258D01*
X1526154Y1443292D01*
X1527624Y1442012D01*
X1527658Y1441518D01*
X1529129Y1440236D01*
X1529623Y1440270D01*
X1531093Y1438990D01*
X1531127Y1438496D01*
X1532598Y1437214D01*
X1533092Y1437248D01*
X1558609Y1415017D01*
X1560435Y1411006D01*
Y1409640D01*
X1559290Y1408495D01*
G01X1512953Y1494449D02*
Y1492945D01*
X1513453Y1492445D01*
X1515607D01*
X1517386Y1490666D01*
Y1456068D01*
X1520149Y1449996D01*
X1559520Y1415696D01*
X1561545Y1411247D01*
Y1409640D01*
X1562690Y1408495D01*
G01X1522570Y1372385D02*
X1523715Y1371240D01*
Y1368771D01*
X1529835Y1362651D01*
Y1345580D01*
X1566275Y1270313D01*
Y1260024D01*
G01X1525970Y1372385D02*
X1524825Y1371240D01*
Y1369231D01*
X1530945Y1363111D01*
Y1345835D01*
X1567385Y1270568D01*
Y1260024D01*
G01X1571530Y1384297D02*
X1572675Y1385442D01*
Y1387229D01*
X1566555Y1393349D01*
Y1409381D01*
X1563741Y1415833D01*
X1533891Y1443535D01*
X1533397Y1443516D01*
X1531966Y1444844D01*
X1531948Y1445339D01*
X1527536Y1449433D01*
X1524937Y1455390D01*
Y1494537D01*
X1523808Y1495666D01*
X1522114D01*
X1521614Y1495166D01*
Y1493662D01*
G01Y1498780D02*
Y1497276D01*
X1522114Y1496776D01*
X1524268D01*
X1526047Y1494997D01*
Y1455622D01*
X1528461Y1450089D01*
X1564666Y1416489D01*
X1567665Y1409613D01*
Y1393809D01*
X1573785Y1387689D01*
Y1385442D01*
X1574930Y1384297D01*
G01X1629858Y1260024D02*
Y1263555D01*
X1628856Y1264925D01*
X1538794Y1340862D01*
X1537904Y1342026D01*
X1535955Y1345248D01*
Y1347042D01*
X1534810Y1348187D01*
G01X1538210D02*
X1537065Y1347042D01*
Y1345558D01*
X1538823Y1342653D01*
X1539603Y1341633D01*
X1629674Y1265688D01*
X1630968Y1263918D01*
Y1260024D01*
G01X1538210Y1396583D02*
X1537065Y1395438D01*
Y1393429D01*
X1543185Y1387309D01*
Y1347069D01*
X1544027Y1345344D01*
X1544026Y1345343D01*
X1544869Y1343619D01*
X1630458Y1271062D01*
X1634708Y1265235D01*
Y1260024D01*
G01X1534810Y1396583D02*
X1535955Y1395438D01*
Y1392969D01*
X1542075Y1386849D01*
Y1346812D01*
X1543973Y1342922D01*
X1629639Y1270301D01*
X1633598Y1264873D01*
Y1260024D01*
G01X1530275Y1494449D02*
Y1492945D01*
X1530775Y1492445D01*
X1532929D01*
X1534708Y1490666D01*
Y1456085D01*
X1537756Y1449515D01*
X1576523Y1416718D01*
X1579905Y1409427D01*
Y1369611D01*
X1586025Y1363491D01*
Y1361244D01*
X1587170Y1360099D01*
G01X1583770Y1408495D02*
X1584915Y1409640D01*
Y1411024D01*
X1583128Y1415032D01*
X1552168Y1442879D01*
X1551744Y1442857D01*
X1550293Y1444162D01*
X1550271Y1444586D01*
X1545326Y1449033D01*
X1542260Y1455915D01*
Y1494537D01*
X1541131Y1495666D01*
X1539437D01*
X1538937Y1495166D01*
Y1493662D01*
G01X1583770Y1360099D02*
X1584915Y1361244D01*
Y1363031D01*
X1578795Y1369151D01*
Y1409182D01*
X1575618Y1416028D01*
X1549671Y1437979D01*
X1549178Y1437937D01*
X1547688Y1439198D01*
X1547647Y1439691D01*
X1546159Y1440950D01*
X1545666Y1440908D01*
X1544176Y1442169D01*
X1544135Y1442662D01*
X1542647Y1443921D01*
X1542154Y1443880D01*
X1540664Y1445141D01*
X1540623Y1445634D01*
X1536851Y1448825D01*
X1533598Y1455840D01*
Y1490206D01*
X1532469Y1491335D01*
X1530775D01*
X1530275Y1490835D01*
Y1489331D01*
G01X1538937Y1498780D02*
Y1497276D01*
X1539437Y1496776D01*
X1541591D01*
X1543370Y1494997D01*
Y1456152D01*
X1546245Y1449701D01*
X1584046Y1415700D01*
X1584047D01*
X1586025Y1411261D01*
Y1409640D01*
X1587170Y1408495D01*
G01X1547050Y1372385D02*
X1548195Y1371240D01*
Y1368771D01*
X1554315Y1362651D01*
Y1346656D01*
X1555859Y1342456D01*
X1630847Y1275353D01*
X1637338Y1266200D01*
Y1260024D01*
G01X1559290Y1348187D02*
X1560435Y1347042D01*
Y1344680D01*
X1561314Y1342895D01*
X1633191Y1278715D01*
X1641079Y1267603D01*
Y1260024D01*
G01X1562690Y1348187D02*
X1561545Y1347042D01*
Y1344939D01*
X1562216Y1343579D01*
X1634024Y1279460D01*
X1642189Y1267957D01*
Y1260024D01*
G01X1550450Y1372385D02*
X1549305Y1371240D01*
Y1369231D01*
X1555425Y1363111D01*
Y1346854D01*
X1556806Y1343099D01*
X1631681Y1276098D01*
X1638448Y1266554D01*
Y1260024D01*
G01X1562690Y1396583D02*
X1561545Y1395438D01*
Y1393429D01*
X1567665Y1387309D01*
Y1346777D01*
X1568394Y1344248D01*
X1636352Y1282852D01*
X1645929Y1269278D01*
Y1260024D01*
G01X1559290Y1396583D02*
X1560435Y1395438D01*
Y1392969D01*
X1566555Y1386849D01*
Y1346620D01*
X1567415Y1343636D01*
X1635516Y1282111D01*
X1644819Y1268925D01*
Y1260024D01*
G01X1571530Y1372385D02*
X1572675Y1371240D01*
Y1368771D01*
X1578795Y1362651D01*
Y1343682D01*
X1580230Y1340467D01*
X1638498Y1284903D01*
X1648559Y1270227D01*
Y1260024D01*
G01X1574930Y1372385D02*
X1573785Y1371240D01*
Y1369231D01*
X1579905Y1363111D01*
Y1343919D01*
X1580530Y1342520D01*
X1580529D01*
X1581155Y1341120D01*
X1639349Y1285627D01*
X1649669Y1270571D01*
Y1260024D01*
G01X1592187Y-79306D02*
X1593332Y-80451D01*
X1608606D01*
X1609768Y-81425D01*
X1611663Y-92170D01*
X1613168Y-93225D01*
X1617167Y-92518D01*
X1618222Y-91013D01*
X1614354Y-69074D01*
X1615936Y-66817D01*
X1620847Y-65950D01*
X1623104Y-67533D01*
X1627463Y-92258D01*
X1628968Y-93313D01*
X1632967Y-92606D01*
X1634022Y-91101D01*
X1630135Y-69054D01*
X1631717Y-66797D01*
X1636626Y-65930D01*
X1638884Y-67512D01*
X1643278Y-92433D01*
X1644783Y-93488D01*
X1648782Y-92781D01*
X1649837Y-91276D01*
X1645919Y-69051D01*
X1647501Y-66794D01*
X1652410Y-65927D01*
X1654668Y-67509D01*
X1659044Y-92331D01*
X1660549Y-93386D01*
X1664548Y-92679D01*
X1665603Y-91173D01*
X1661703Y-69048D01*
X1663285Y-66791D01*
X1668194Y-65924D01*
X1670452Y-67506D01*
X1674818Y-92270D01*
X1676322Y-93325D01*
X1680321Y-92618D01*
X1681376Y-91112D01*
X1677485Y-69039D01*
X1679067Y-66782D01*
X1683976Y-65915D01*
X1686234Y-67497D01*
X1690599Y-92253D01*
X1692103Y-93308D01*
X1696102Y-92601D01*
X1697158Y-91095D01*
X1693270Y-69056D01*
X1694852Y-66798D01*
X1699761Y-65931D01*
X1702021Y-67514D01*
X1706391Y-92313D01*
X1707900Y-93368D01*
X1711900Y-92661D01*
X1712954Y-91160D01*
X1709052Y-69041D01*
X1710634Y-66783D01*
X1715543Y-65916D01*
X1717802Y-67500D01*
X1719940Y-79620D01*
X1721085Y-80423D01*
X1735260D01*
X1736405Y-79278D01*
G01X1592187Y-82706D02*
X1593332Y-81561D01*
X1608202D01*
X1608745Y-82016D01*
X1610649Y-92816D01*
X1612908Y-94399D01*
X1617813Y-93532D01*
X1619396Y-91274D01*
X1615528Y-69335D01*
X1616582Y-67831D01*
X1620586Y-67124D01*
X1622090Y-68179D01*
X1626449Y-92904D01*
X1628708Y-94487D01*
X1633613Y-93620D01*
X1635196Y-91362D01*
X1631309Y-69315D01*
X1632363Y-67811D01*
X1636366Y-67104D01*
X1637870Y-68158D01*
X1642264Y-93079D01*
X1644523Y-94662D01*
X1649428Y-93795D01*
X1651011Y-91537D01*
X1647093Y-69312D01*
X1648147Y-67808D01*
X1652150Y-67101D01*
X1653654Y-68155D01*
X1658030Y-92977D01*
X1660289Y-94560D01*
X1665194Y-93693D01*
X1666777Y-91433D01*
X1662877Y-69309D01*
X1663931Y-67805D01*
X1667934Y-67098D01*
X1669438Y-68152D01*
X1673804Y-92915D01*
X1676062Y-94499D01*
X1680967Y-93632D01*
X1682550Y-91372D01*
X1678659Y-69300D01*
X1679713Y-67796D01*
X1683716Y-67089D01*
X1685220Y-68143D01*
X1689585Y-92898D01*
X1691843Y-94482D01*
X1696748Y-93615D01*
X1698332Y-91356D01*
X1694444Y-69316D01*
X1695498Y-67812D01*
X1699501Y-67105D01*
X1701007Y-68160D01*
X1705377Y-92959D01*
X1707640Y-94542D01*
X1712545Y-93675D01*
X1714128Y-91421D01*
X1710226Y-69301D01*
X1711280Y-67797D01*
X1715282Y-67090D01*
X1716788Y-68146D01*
X1718926Y-80266D01*
X1720734Y-81533D01*
X1735260D01*
X1736405Y-82678D01*
G01X1582187Y-43786D02*
X1583332Y-42641D01*
X1596082D01*
X1598018Y-44577D01*
X1600298Y-57499D01*
X1602556Y-59082D01*
X1607461Y-58215D01*
X1609044Y-55956D01*
X1603941Y-27011D01*
X1604995Y-25507D01*
X1608998Y-24800D01*
X1610502Y-25854D01*
X1616097Y-57581D01*
X1618354Y-59163D01*
X1623258Y-58295D01*
X1624842Y-56035D01*
X1619727Y-27025D01*
X1620781Y-25521D01*
X1624784Y-24814D01*
X1626288Y-25868D01*
X1631953Y-57989D01*
X1634211Y-59572D01*
X1639116Y-58705D01*
X1640699Y-56447D01*
X1635516Y-27050D01*
X1636570Y-25546D01*
X1640573Y-24839D01*
X1642077Y-25893D01*
X1647746Y-58049D01*
X1650007Y-59632D01*
X1654912Y-58765D01*
X1656495Y-56509D01*
X1651296Y-27024D01*
X1652350Y-25520D01*
X1656353Y-24813D01*
X1657857Y-25867D01*
X1663498Y-57862D01*
X1665757Y-59445D01*
X1670662Y-58578D01*
X1672245Y-56320D01*
X1667076Y-27005D01*
X1668130Y-25501D01*
X1672133Y-24794D01*
X1673637Y-25848D01*
X1679267Y-57779D01*
X1681526Y-59362D01*
X1686431Y-58495D01*
X1688014Y-56237D01*
X1682865Y-27036D01*
X1683919Y-25532D01*
X1687922Y-24825D01*
X1689427Y-25880D01*
X1695067Y-57867D01*
X1697326Y-59450D01*
X1702231Y-58583D01*
X1703814Y-56325D01*
X1698654Y-27062D01*
X1699708Y-25558D01*
X1703711Y-24851D01*
X1705216Y-25905D01*
X1710882Y-58042D01*
X1713141Y-59625D01*
X1718046Y-58758D01*
X1719629Y-56500D01*
X1714435Y-27041D01*
X1715489Y-25537D01*
X1719492Y-24830D01*
X1720996Y-25884D01*
X1726648Y-57940D01*
X1728907Y-59523D01*
X1733812Y-58656D01*
X1735395Y-56398D01*
X1730210Y-26987D01*
X1731264Y-25483D01*
X1735267Y-24776D01*
X1736771Y-25830D01*
X1742413Y-57830D01*
X1744672Y-59413D01*
X1749577Y-58546D01*
X1751160Y-56288D01*
X1745997Y-27006D01*
X1747051Y-25502D01*
X1751054Y-24795D01*
X1752558Y-25849D01*
X1758185Y-57765D01*
X1760444Y-59348D01*
X1765349Y-58481D01*
X1766933Y-56222D01*
X1761784Y-27033D01*
X1762838Y-25529D01*
X1766841Y-24822D01*
X1768347Y-25877D01*
X1773980Y-57825D01*
X1776239Y-59408D01*
X1781144Y-58541D01*
X1782727Y-56283D01*
X1777584Y-27115D01*
X1778638Y-25611D01*
X1782640Y-24904D01*
X1784146Y-25960D01*
X1786882Y-41476D01*
X1788690Y-42743D01*
X1800616D01*
X1801761Y-43888D01*
G01X1582187Y-40386D02*
X1583332Y-41531D01*
X1596542D01*
X1599051Y-44039D01*
X1601312Y-56853D01*
X1602816Y-57908D01*
X1606815Y-57201D01*
X1607870Y-55695D01*
X1602767Y-26750D01*
X1604349Y-24493D01*
X1609258Y-23626D01*
X1611516Y-25208D01*
X1617111Y-56934D01*
X1618614Y-57989D01*
X1622612Y-57281D01*
X1623668Y-55774D01*
X1618553Y-26764D01*
X1620135Y-24507D01*
X1625044Y-23640D01*
X1627302Y-25222D01*
X1632967Y-57343D01*
X1634471Y-58398D01*
X1638470Y-57691D01*
X1639525Y-56186D01*
X1634342Y-26789D01*
X1635924Y-24532D01*
X1640833Y-23665D01*
X1643091Y-25247D01*
X1648760Y-57403D01*
X1650267Y-58458D01*
X1654266Y-57751D01*
X1655321Y-56248D01*
X1650122Y-26763D01*
X1651704Y-24506D01*
X1656613Y-23639D01*
X1658871Y-25221D01*
X1664512Y-57216D01*
X1666017Y-58271D01*
X1670016Y-57564D01*
X1671071Y-56059D01*
X1665902Y-26744D01*
X1667484Y-24487D01*
X1672393Y-23620D01*
X1674651Y-25202D01*
X1680281Y-57133D01*
X1681786Y-58188D01*
X1685785Y-57481D01*
X1686840Y-55976D01*
X1681691Y-26775D01*
X1683273Y-24518D01*
X1688182Y-23651D01*
X1690441Y-25234D01*
X1696081Y-57221D01*
X1697586Y-58276D01*
X1701585Y-57569D01*
X1702640Y-56064D01*
X1697480Y-26801D01*
X1699062Y-24544D01*
X1703971Y-23677D01*
X1706230Y-25259D01*
X1711896Y-57396D01*
X1713401Y-58451D01*
X1717400Y-57744D01*
X1718455Y-56239D01*
X1713261Y-26780D01*
X1714843Y-24523D01*
X1719752Y-23656D01*
X1722010Y-25238D01*
X1727662Y-57294D01*
X1729167Y-58349D01*
X1733166Y-57642D01*
X1734221Y-56137D01*
X1729036Y-26726D01*
X1730618Y-24469D01*
X1735527Y-23602D01*
X1737785Y-25184D01*
X1743427Y-57184D01*
X1744932Y-58239D01*
X1748931Y-57532D01*
X1749986Y-56027D01*
X1744823Y-26745D01*
X1746405Y-24488D01*
X1751314Y-23621D01*
X1753572Y-25203D01*
X1759199Y-57119D01*
X1760704Y-58174D01*
X1764703Y-57467D01*
X1765759Y-55961D01*
X1760610Y-26773D01*
X1762192Y-24515D01*
X1767101Y-23648D01*
X1769361Y-25231D01*
X1774994Y-57179D01*
X1776499Y-58234D01*
X1780498Y-57527D01*
X1781553Y-56022D01*
X1776410Y-26854D01*
X1777992Y-24597D01*
X1782901Y-23730D01*
X1785160Y-25314D01*
X1787896Y-40830D01*
X1789041Y-41633D01*
X1800616D01*
X1801761Y-40488D01*
G01X1587170Y1348187D02*
X1586025Y1347042D01*
Y1344682D01*
X1586893Y1342228D01*
X1642574Y1288037D01*
X1653409Y1272055D01*
Y1260024D01*
G01X1583770Y1348187D02*
X1584915Y1347042D01*
Y1344491D01*
X1585933Y1341613D01*
X1641719Y1287320D01*
X1652299Y1271714D01*
Y1260024D01*
G01X1583770Y1396583D02*
X1584915Y1395438D01*
Y1392616D01*
X1588964Y1388567D01*
X1590410Y1386164D01*
X1590411Y1386163D01*
X1590892Y1385364D01*
X1599054Y1364549D01*
X1599055D01*
X1607305Y1343510D01*
X1645721Y1291378D01*
X1656039Y1273101D01*
Y1260024D01*
G01X1587170Y1396583D02*
X1586025Y1395438D01*
Y1393076D01*
X1589845Y1389256D01*
X1590880Y1387537D01*
Y1387538D01*
X1591892Y1385856D01*
X1608286Y1344052D01*
X1646655Y1291982D01*
X1657149Y1273393D01*
Y1260024D01*
G54D27*
X1795453Y812874D03*
Y834922D03*
G54D18*
X173829Y455492D03*
Y583957D03*
X202844Y455492D03*
Y583957D03*
X266841Y421555D03*
Y550020D03*
X295856Y421555D03*
Y550020D03*
X1545089Y455492D03*
X1574104D03*
X1638101Y421555D03*
X1667116D03*
G54D28*
X1803917Y823898D03*
G54D19*
X179173Y1473977D03*
Y1479095D03*
X187835Y1478308D03*
Y1483426D03*
X283110Y1504685D03*
X291771Y1509016D03*
X283110Y1509804D03*
X291771Y1514134D03*
X283110Y1607048D03*
X291771Y1611378D03*
X283110Y1612166D03*
X291771Y1616496D03*
X300433Y1504685D03*
X309094Y1509016D03*
X300433Y1509804D03*
X309094Y1514134D03*
X300433Y1607048D03*
X309094Y1611378D03*
X300433Y1612166D03*
X309094Y1616496D03*
X317756Y1504685D03*
X326417Y1509016D03*
X317756Y1509804D03*
X326417Y1514134D03*
X317756Y1607048D03*
X326417Y1611378D03*
X317756Y1612166D03*
X326417Y1616496D03*
X335078Y1504685D03*
X343740Y1509016D03*
X335078Y1509804D03*
X343740Y1514134D03*
X335078Y1607048D03*
X343740Y1611378D03*
X335078Y1612166D03*
X343740Y1616496D03*
X456339Y1489331D03*
Y1494449D03*
Y1607048D03*
Y1612166D03*
X473662Y1489331D03*
Y1494449D03*
X465000Y1493662D03*
Y1498780D03*
X473662Y1607048D03*
Y1612166D03*
X465000Y1611378D03*
Y1616496D03*
X490985Y1489331D03*
Y1494449D03*
X482323Y1493662D03*
Y1498780D03*
X490985Y1607048D03*
Y1612166D03*
X482323Y1611378D03*
Y1616496D03*
X499646Y1493662D03*
Y1498780D03*
Y1611378D03*
Y1616496D03*
X508307Y1489331D03*
X516969Y1493662D03*
X508307Y1494449D03*
X516969Y1498780D03*
X508307Y1607048D03*
X516969Y1611378D03*
X508307Y1612166D03*
X516969Y1616496D03*
X1305079Y1504685D03*
X1313740Y1509016D03*
X1305079Y1509804D03*
X1313740Y1514134D03*
X1305079Y1607048D03*
X1313740Y1611378D03*
X1305079Y1612166D03*
X1313740Y1616496D03*
X1322402Y1504685D03*
X1331063Y1509016D03*
X1322402Y1509804D03*
X1331063Y1514134D03*
X1322402Y1607048D03*
X1331063Y1611378D03*
X1322402Y1612166D03*
X1331063Y1616496D03*
X1339725Y1504685D03*
X1348386Y1509016D03*
X1339725Y1509804D03*
X1348386Y1514134D03*
X1339725Y1607048D03*
X1348386Y1611378D03*
X1339725Y1612166D03*
X1348386Y1616496D03*
X1357047Y1504685D03*
X1365709Y1509016D03*
X1357047Y1509804D03*
X1365709Y1514134D03*
X1357047Y1607048D03*
X1365709Y1611378D03*
X1357047Y1612166D03*
X1365709Y1616496D03*
X1478307Y1489331D03*
Y1494449D03*
Y1607048D03*
Y1612166D03*
X1495630Y1489331D03*
Y1494449D03*
X1486968Y1493662D03*
Y1498780D03*
X1495630Y1607048D03*
Y1612166D03*
X1486968Y1611378D03*
Y1616496D03*
X1512953Y1489331D03*
Y1494449D03*
X1504291Y1493662D03*
Y1498780D03*
X1512953Y1607048D03*
Y1612166D03*
X1504291Y1611378D03*
Y1616496D03*
X1530275Y1489331D03*
Y1494449D03*
X1521614Y1493662D03*
Y1498780D03*
X1530275Y1607048D03*
Y1612166D03*
X1521614Y1611378D03*
Y1616496D03*
X1538937Y1493662D03*
Y1498780D03*
Y1611378D03*
Y1616496D03*
G54D29*
G01X971443Y938828D02*
X973697Y941082D01*
X1024559D01*
X1027319Y938322D01*
M02*
